FILE_TYPE=CROSS_REFERENCE;
ROOT_DRAWING='SCM';
RUN_TIME='Nov 30 14:24:28 2020';
PROGRAM_VERSION='16.20-p001';
**** Part Type '10M02SCU169C8G' ('10M02SCU169C8G-10M02SCU169C8G,A') ****
**** Part Type '74HC1G126GW' ('74HC1G126GW-74HC1G126GW,SMLF,IA') ****
**** Part Type '74LVC1G07GW' ('74LVC1G07GW-74LVC1G07GW,SMLF,IA') ****
**** Part Type '74LVC1G17GW' ('74LVC1G17GW-74LVC1G17GW,SMLF,IA') ****
**** Part Type 'AP22811AW57' ('AP22811AW57-AP22811AW5-7,SMLF,A') ****
**** Part Type 'AST2600A1GP' ('AST2600A1GP-AST2600A1-GP,SMLF,A') ****
**** Part Type 'BAT54C' ('BAT54C-BAT54C,SMLF,IC,BCBAT54CA') ****
**** Part Type 'BCM54612EB1KMLG' ('BCM54612EB1KMLG-BCM54612EB1KMLA') ****
**** Part Type 'BZA462A' ('BZA462A-BZA462A,SMLF,IC,BCZA46A') ****
**** Part Type 'CONN3_210P9103GBR1' ('CONN3_210P9103GBR1-CONN3_210-PA') ****
**** Part Type 'CONN7_4400547' ('CONN7_4400547-CONN7_440054-7,TA') ****
**** Part Type 'CONN9_GSB311131HR' ('CONN9_GSB311131HR-CONN9_GSB311A') ****
**** Part Type 'DELTA_L' ('DELTA_L-DELTA-L,THLF,EMPTY,TP24') ****
**** Part Type 'DUMMY_SYMBOL' ('DUMMY_SYMBOL-BMC_FLASH,MECH,MEA') ****
**** Part Type 'DUMMY_SYMBOL' ('DUMMY_SYMBOL-PB-E1_SMALL,MECH,A') ****
**** Part Type 'DUMMY_SYMBOL' ('DUMMY_SYMBOL-PCBA_LABEL_15X5,MA') ****
**** Part Type 'DUMMY_SYMBOL' ('DUMMY_SYMBOL-QUANTA_LOGO_7X26,A') ****
**** Part Type 'DUMMY_SYMBOL' ('DUMMY_SYMBOL-WEEE,MECH,EMPTY,DA') ****
**** Part Type 'FCONN168_ME1016810106011' ('FCONN168_ME1016810106011-FCONNA') ****
**** Part Type 'FT234XDR' ('FT234XDR-FT234XD-R,SMLF,IC,AL0A') ****
**** Part Type 'HOLE' ('HOLE_TH-EMPTY,DUMMY50') ****
**** Part Type 'HOLE' ('HOLE_TH-EMPTY,HOLE620') ****
**** Part Type 'HOLE' ('HOLE_TH-EMPTY,HOLE1101') ****
**** Part Type 'HOLE' ('HOLE_TH-EMPTY,HOLE1211') ****
**** Part Type 'IDTQS3VH257PAG' ('IDTQS3VH257PAG_SMLF-IDTQS3VH25A') ****
**** Part Type 'K4A8G165WCBCTD' ('K4A8G165WCBCTD-K4A8G165WC-BCTDA') ****
**** Part Type 'M24128BWDW6TP' ('M24128BWDW6TP-M24128-BWDW6TP,SA') ****
**** Part Type 'MMBT39047F' ('MMBT39047F-MMBT3904-7-F,SMLF,IA') ****
**** Part Type 'MOSFET_DUAL_6P' ('MOSFET_DUAL_6P-2N7002KDW,SMLF,A') ****
**** Part Type 'MOSFET_DUAL_6P' ('MOSFET_DUAL_6P-DMN2400UV-7,SMLA') ****
**** Part Type 'MOSFET_NCH_DUAL' ('MOSFET_NCH_DUAL-2N7002KDW,SMLFA') ****
**** Part Type 'MOSFET_N_123' ('MOSFET_N_123-BSS123-7-F,SMLF,IA') ****
**** Part Type 'MOSFET_N_GSD' ('MOSFET_N_GSD-DMG6968U-7,SMLF,IA') ****
**** Part Type 'MOSFET_N_GSD' ('MOSFET_N_GSD-NX7002AK,SMLF,IC,A') ****
**** Part Type 'MOSFET_N' ('MOSFET_N_SMLF-BSS138K,BSS138K,A') ****
**** Part Type 'MPQ8626GDZ' ('MPQ8626GDZ-MPQ8626GD-Z,SMLF,ICA') ****
**** Part Type 'MPQ8633AGLEC807Z' ('MPQ8633AGLEC807Z-MPQ8633AGLE-CA') ****
**** Part Type 'MTFC8GAKAJCN1MWT' ('MTFC8GAKAJCN1MWT-MTFC8GAKAJCN-A') ****
**** Part Type 'MX66L1G45GMI08G' ('MX66L1G45GMI08G-MX66L1G45GMI-0A') ****
**** Part Type 'NB695GDZ' ('NB695GDZ-NB695GD-Z,SMLF,IC,AL0A') ****
**** Part Type 'OSC4_7X25000018' ('OSC4_7X25000018-25MHZ,SMLF,MISA') ****
**** Part Type 'PCA9517ADP' ('PCA9517ADP_SMLF-PCA9517ADP,IC,A') ****
**** Part Type 'PRTR5V0U2X' ('PRTR5V0U2X-PRTR5V0U2X,SMLF,IC,A') ****
**** Part Type 'Q_CAP' ('Q_CAP_0402-0.1UF,10V,10%,EMPTYA') ****
**** Part Type 'Q_CAP' ('Q_CAP_0402-0.1UF,10V,10%,X7R,TA') ****
**** Part Type 'Q_CAP' ('Q_CAP_0402-0.1UF,25V,10%,EMPTYA') ****
**** Part Type 'Q_CAP' ('Q_CAP_0402-0.1UF,25V,10%,X7R,CA') ****
**** Part Type 'Q_CAP' ('Q_CAP_0402-0.22UF,16V,10%,EMPTA') ****
**** Part Type 'Q_CAP' ('Q_CAP_0402-0.22UF,16V,10%,X7R,A') ****
**** Part Type 'Q_CAP' ('Q_CAP_0402-100PF,50V,5%,EMPTY,A') ****
**** Part Type 'Q_CAP' ('Q_CAP_0402-100PF,50V,5%,NPO,CHA') ****
**** Part Type 'Q_CAP' ('Q_CAP_0402-10PF,50V,1%,NPO,TMPA') ****
**** Part Type 'Q_CAP' ('Q_CAP_0402-10PF,50V,5%,COG,CH0A') ****
**** Part Type 'Q_CAP' ('Q_CAP_0402-1UF,16V,10%,EMPTY,TA') ****
**** Part Type 'Q_CAP' ('Q_CAP_0402-2.2UF,10V,20%,X5R,TA') ****
**** Part Type 'Q_CAP' ('Q_CAP_0402-2200PF,50V,10%,X7R,A') ****
**** Part Type 'Q_CAP' ('Q_CAP_0402-22PF,50V,5%,EMPTY,TA') ****
**** Part Type 'Q_CAP' ('Q_CAP_0402-3300PF,50V,10%,X7R,A') ****
**** Part Type 'Q_CAP' ('Q_CAP_0402-4.7UF,10V,10%,X5R,CA') ****
**** Part Type 'Q_CAP' ('Q_CAP_0402-470PF,50V,10%,X7R,TA') ****
**** Part Type 'Q_CAP' ('Q_CAP_0603-1UF,16V,10%,EMPTY,TA') ****
**** Part Type 'Q_CAP' ('Q_CAP_0805-22UF,4V,20%,X6S,TMPA') ****
**** Part Type 'Q_CAP' ('Q_CAP_1206-47UF ,10V,20%,X5R,CA') ****
**** Part Type 'Q_CAP' ('Q_CAP_C0402-0.001UF,50V,10%,X7A') ****
**** Part Type 'Q_CAP' ('Q_CAP_C0402-0.01UF,50V,10%,EMPA') ****
**** Part Type 'Q_CAP' ('Q_CAP_C0402-0.01UF,50V,10%,X7RA') ****
**** Part Type 'Q_CAP' ('Q_CAP_C0402-0.1UF,16V,10%,EMPTA') ****
**** Part Type 'Q_CAP' ('Q_CAP_C0402-0.1UF,16V,10%,X7R,A') ****
**** Part Type 'Q_CAP' ('Q_CAP_C0402-0.1UF,25V,10%,X6S,A') ****
**** Part Type 'Q_CAP' ('Q_CAP_C0402-10UF,10V,20%,X5R,CA') ****
**** Part Type 'Q_CAP' ('Q_CAP_C0402-10UF,6.3V,20%,X6S,A') ****
**** Part Type 'Q_CAP' ('Q_CAP_C0402-12PF,50V,5%,C0G,CHA') ****
**** Part Type 'Q_CAP' ('Q_CAP_C0402-1UF,25V,10%,EMPTY,A') ****
**** Part Type 'Q_CAP' ('Q_CAP_C0402-1UF,25V,10%,X6S,CHA') ****
**** Part Type 'Q_CAP' ('Q_CAP_C0402-1UF,6.3V,10%,EMPTYA') ****
**** Part Type 'Q_CAP' ('Q_CAP_C0402-22UF,6.3V,20%,X5R,A') ****
**** Part Type 'Q_CAP' ('Q_CAP_C0402-33PF,50V,1%,C0G,CHA') ****
**** Part Type 'Q_CAP' ('Q_CAP_C0402-4.7UF,10V,10%,X5R,A') ****
**** Part Type 'Q_CAP' ('Q_CAP_C0402-4700P,25V,10%,EMPTA') ****
**** Part Type 'Q_CAP' ('Q_CAP_C0402-68PF,50V,5%,COG,CHA') ****
**** Part Type 'Q_CAP' ('Q_CAP_C0603-10UF,16V,20%,X6S,CA') ****
**** Part Type 'Q_CAP' ('Q_CAP_C0603-22UF,10V,20%,EMPTYA') ****
**** Part Type 'Q_CAP' ('Q_CAP_C0603-22UF,10V,20%,X5R,CA') ****
**** Part Type 'Q_CAP' ('Q_CAP_C0603-22UF,6.3V,20%,EMPTA') ****
**** Part Type 'Q_CAP' ('Q_CAP_C0603-22UF,6.3V,20%,X6S,A') ****
**** Part Type 'Q_CAP' ('Q_CAP_C0603-4.7UF,25V,10%,X6S,A') ****
**** Part Type 'Q_CAP' ('Q_CAP_C0805-10UF,25V,10%,X6S,CA') ****
**** Part Type 'Q_CAP' ('Q_CAP_C0805-22UF,10V,20%,X6S,CA') ****
**** Part Type 'Q_CAP' ('Q_CAP_C0805-22UF,16V,20%,X6S,CA') ****
**** Part Type 'Q_CAP' ('Q_CAP_C0805-22UF,25V,20%,X5R,CA') ****
**** Part Type 'Q_DIODE' ('Q_DIODE_SMLF-SDMK0340L-7-F,IC,A') ****
**** Part Type 'Q_FUSE' ('Q_FUSE_SMLF-0.5A/6V,IC,DK050TPA') ****
**** Part Type 'Q_FUSE' ('Q_FUSE_SMLF-1.1A/8V,IC,DK110TPA') ****
**** Part Type 'Q_INDUCTOR4P_12' ('Q_INDUCTOR4P_12-67/320MA,320MAA') ****
**** Part Type 'Q_INDUCTOR4P_12' ('Q_INDUCTOR4P_12-67/320MA,320MAB') ****
**** Part Type 'Q_INDUCTOR' ('Q_INDUCTOR_SMLF-1UH,IND,CV-10BA') ****
**** Part Type 'Q_INDUCTOR' ('Q_INDUCTOR_SMLF-220/1500MA,INDA') ****
**** Part Type 'Q_INDUCTOR' ('Q_INDUCTOR_SMLF-3.3UH/6A,IND,CA') ****
**** Part Type 'Q_INDUCTOR' ('Q_INDUCTOR_SMLF-4.7UH,IND,CV-4A') ****
**** Part Type 'Q_INDUCTOR' ('Q_INDUCTOR_SMLF-47/300MA,IND,CA') ****
**** Part Type 'Q_INDUCTOR' ('Q_INDUCTOR_SMLF-BLM15PX121SN1DA') ****
**** Part Type 'Q_INDUCTOR' ('Q_INDUCTOR_SMLF-BLM18EG121SN1DA') ****
**** Part Type 'Q_INDUCTOR' ('Q_INDUCTOR_SMLF-BLM18PG121SN1DA') ****
**** Part Type 'Q_INDUCTOR' ('Q_INDUCTOR_SMLF-BLM18PG121SN1DB') ****
**** Part Type 'Q_INDUCTOR' ('Q_INDUCTOR_SMLF-BLM18SN220TN1DA') ****
**** Part Type 'Q_LED' ('Q_LED_SMLF-LED_BLUE,12-215/BHCA') ****
**** Part Type 'Q_LED' ('Q_LED_SMLF-LED_GREEN,19-213/GVA') ****
**** Part Type 'Q_LED' ('Q_LED_SMLF-LED_RED,19-217/R6C-A') ****
**** Part Type 'Q_RES' ('Q_RES_0201LF-1.5K,1%,1/20W,CHIA') ****
**** Part Type 'Q_RES' ('Q_RES_0201LF-27.4,1%,1/20W,CHIA') ****
**** Part Type 'Q_RES' ('Q_RES_0201LF-47K,1%,1/20W,CHIPA') ****
**** Part Type 'Q_RES' ('Q_RES_0402LF -49.9K,1%,1/16W ,A') ****
**** Part Type 'Q_RES' ('Q_RES_0402LF-0,5%,1/16W,CHIP,CA') ****
**** Part Type 'Q_RES' ('Q_RES_0402LF-0,5%,1/16W,EMPTY,A') ****
**** Part Type 'Q_RES' ('Q_RES_0402LF-1.24K,1%,1/16W,CHA') ****
**** Part Type 'Q_RES' ('Q_RES_0402LF-1.5K,1%,1/16W,CHIA') ****
**** Part Type 'Q_RES' ('Q_RES_0402LF-1.5K,1%,1/16W,EMPA') ****
**** Part Type 'Q_RES' ('Q_RES_0402LF-1.69K,1%,1/16W,CHA') ****
**** Part Type 'Q_RES' ('Q_RES_0402LF-10,1%,1/16W,CHIP,A') ****
**** Part Type 'Q_RES' ('Q_RES_0402LF-100,1%,1/16W,CHIPA') ****
**** Part Type 'Q_RES' ('Q_RES_0402LF-100,1%,1/16W,EMPTA') ****
**** Part Type 'Q_RES' ('Q_RES_0402LF-100K,0.1%,1/16W,CA') ****
**** Part Type 'Q_RES' ('Q_RES_0402LF-100K,1%,1/16W,CHIA') ****
**** Part Type 'Q_RES' ('Q_RES_0402LF-100K,1%,1/16W,CHIB') ****
**** Part Type 'Q_RES' ('Q_RES_0402LF-100K,1%,1/16W,EMPA') ****
**** Part Type 'Q_RES' ('Q_RES_0402LF-100K,1%,1/16W,EMPB') ****
**** Part Type 'Q_RES' ('Q_RES_0402LF-10K,0.10%,1/16W,CA') ****
**** Part Type 'Q_RES' ('Q_RES_0402LF-10K,1%,1/16W,CHIPA') ****
**** Part Type 'Q_RES' ('Q_RES_0402LF-10K,1%,1/16W,EMPTA') ****
**** Part Type 'Q_RES' ('Q_RES_0402LF-10K,1%,1/16W,EMPTB') ****
**** Part Type 'Q_RES' ('Q_RES_0402LF-12.4K,1%,1/16W,CHA') ****
**** Part Type 'Q_RES' ('Q_RES_0402LF-120,1%,1/16W,CHIPA') ****
**** Part Type 'Q_RES' ('Q_RES_0402LF-120,1%,1/16W,EMPTA') ****
**** Part Type 'Q_RES' ('Q_RES_0402LF-12K,1%,1/16W,CHIPA') ****
**** Part Type 'Q_RES' ('Q_RES_0402LF-13.3K,1%,1/16W,CHA') ****
**** Part Type 'Q_RES' ('Q_RES_0402LF-15.8K,1%,1/16W,CHA') ****
**** Part Type 'Q_RES' ('Q_RES_0402LF-150,1%,1/16W,CHIPA') ****
**** Part Type 'Q_RES' ('Q_RES_0402LF-150K,1%,1/16W,CHIA') ****
**** Part Type 'Q_RES' ('Q_RES_0402LF-15K,1%,1/16W,CHIPA') ****
**** Part Type 'Q_RES' ('Q_RES_0402LF-1K,1%,1/16W,CHIP,A') ****
**** Part Type 'Q_RES' ('Q_RES_0402LF-1K,1%,1/16W,EMPTYA') ****
**** Part Type 'Q_RES' ('Q_RES_0402LF-1M,1%,1/16W,CHIP,A') ****
**** Part Type 'Q_RES' ('Q_RES_0402LF-2.21K    ,1%  ,1/A') ****
**** Part Type 'Q_RES' ('Q_RES_0402LF-2.2K ,5%,1/16W,CHA') ****
**** Part Type 'Q_RES' ('Q_RES_0402LF-2.74K,1%,1/16W,CHA') ****
**** Part Type 'Q_RES' ('Q_RES_0402LF-2.87K,1%,1/16W,CHA') ****
**** Part Type 'Q_RES' ('Q_RES_0402LF-200K,1%,1/16W,CHIA') ****
**** Part Type 'Q_RES' ('Q_RES_0402LF-20K,1%,1/16W,CHIPA') ****
**** Part Type 'Q_RES' ('Q_RES_0402LF-22,1%,1/16W,CHIP,A') ****
**** Part Type 'Q_RES' ('Q_RES_0402LF-22,5%,1/16W,CHIP,A') ****
**** Part Type 'Q_RES' ('Q_RES_0402LF-220,5%,1/16W,CHIPA') ****
**** Part Type 'Q_RES' ('Q_RES_0402LF-240,1%,1/16W,CHIPA') ****
**** Part Type 'Q_RES' ('Q_RES_0402LF-25.5K,1%,1/16W,CHA') ****
**** Part Type 'Q_RES' ('Q_RES_0402LF-2K,1%,1/16W,CHIP,A') ****
**** Part Type 'Q_RES' ('Q_RES_0402LF-2K,1%,1/16W,EMPTYA') ****
**** Part Type 'Q_RES' ('Q_RES_0402LF-33       ,1%  ,1/A') ****
**** Part Type 'Q_RES' ('Q_RES_0402LF-33       ,1%  ,1/B') ****
**** Part Type 'Q_RES' ('Q_RES_0402LF-330,1%,1/16W,CHIPA') ****
**** Part Type 'Q_RES' ('Q_RES_0402LF-4.7K,1%,1/16W,CHIA') ****
**** Part Type 'Q_RES' ('Q_RES_0402LF-4.7K,1%,1/16W,EMPA') ****
**** Part Type 'Q_RES' ('Q_RES_0402LF-4.7K,5%,1/16W,CHIA') ****
**** Part Type 'Q_RES' ('Q_RES_0402LF-4.7K,5%,1/16W,EMPA') ****
**** Part Type 'Q_RES' ('Q_RES_0402LF-470K,1%,1/16W,CHIA') ****
**** Part Type 'Q_RES' ('Q_RES_0402LF-47K,1%,1/16W,CHIPA') ****
**** Part Type 'Q_RES' ('Q_RES_0402LF-47K,5%,1/16W,EMPTA') ****
**** Part Type 'Q_RES' ('Q_RES_0402LF-49.9     ,1%  ,1/A') ****
**** Part Type 'Q_RES' ('Q_RES_0402LF-499,1%,1/16W,CHIPA') ****
**** Part Type 'Q_RES' ('Q_RES_0402LF-5.1,5%,1/16W,CHIPA') ****
**** Part Type 'Q_RES' ('Q_RES_0402LF-5.36K,1%,1/16W,CHA') ****
**** Part Type 'Q_RES' ('Q_RES_0402LF-51.1K,1%,1/16W,CHA') ****
**** Part Type 'Q_RES' ('Q_RES_0402LF-56K,1%,1/16W,CHIPA') ****
**** Part Type 'Q_RES' ('Q_RES_0402LF-60.4,1%,1/16W,CHIA') ****
**** Part Type 'Q_RES' ('Q_RES_0402LF-60.4K,1%,1/16W,CHA') ****
**** Part Type 'Q_RES' ('Q_RES_0402LF-665,1%,1/16W,CHIPA') ****
**** Part Type 'Q_RES' ('Q_RES_0402LF-681K,1%,1/16W,CHIA') ****
**** Part Type 'Q_RES' ('Q_RES_0402LF-750,1%,1/16W,CHIPA') ****
**** Part Type 'Q_RES' ('Q_RES_0402LF-8.2K     ,5%  ,1/A') ****
**** Part Type 'Q_RES' ('Q_RES_0402LF-8.66K,1%,1/16W,CHA') ****
**** Part Type 'Q_RES' ('Q_RES_0402LF-91K,1%,1/16W,CHIPA') ****
**** Part Type 'Q_RES' ('Q_RES_0603-0,5%,1/10W,EMPTY,TMA') ****
**** Part Type 'Q_XTAL_4P_13BI_24GND' ('Q_XTAL_4P_13BI_24GND-25MHZ,SMLA') ****
**** Part Type 'RT9059GQW' ('RT9059GQW-RT9059GQW,SMLF,IC,ALA') ****
**** Part Type 'SCHOTTKY_AC' ('SCHOTTKY_AC-RB161SS-20T2R,SMLFA') ****
**** Part Type 'SCHOTTKY_AC' ('SCHOTTKY_AC-SS0530,SMLF,EMPTY,A') ****
**** Part Type 'SCHOTTKY_AC' ('SCHOTTKY_AC-SS0530,SMLF,IC,BCSA') ****
**** Part Type 'SCM' ('SCM') ****

PART CROSS REFERENCE (forward interface)

Q_CAP  I4   C1     [Q_CAP_C0603-4.7UF,25V,10%,X6S,A]
    1  P1V2_AUX           A  @SCM_LIB.SCM(SCH_1):P1V2_AUX
    2  GND                B  @SCM_LIB.SCM(SCH_1):GND

Q_CAP  I5   C2     [Q_CAP_C0402-1UF,25V,10%,X6S,CHA]
    1  P1V2_AUX           A  @SCM_LIB.SCM(SCH_1):P1V2_AUX
    2  GND                B  @SCM_LIB.SCM(SCH_1):GND

Q_CAP  I6   C3     [Q_CAP_C0402-1UF,25V,10%,X6S,CHA]
    1  P1V2_AUX           A  @SCM_LIB.SCM(SCH_1):P1V2_AUX
    2  GND                B  @SCM_LIB.SCM(SCH_1):GND

Q_CAP  I7   C4     [Q_CAP_C0402-1UF,25V,10%,X6S,CHA]
    1  P1V2_AUX           A  @SCM_LIB.SCM(SCH_1):P1V2_AUX
    2  GND                B  @SCM_LIB.SCM(SCH_1):GND

Q_CAP  I23  C5     [Q_CAP_C0402-1UF,25V,10%,X6S,CHA]
    1  P1V2_AUX           A  @SCM_LIB.SCM(SCH_1):P1V2_AUX
    2  GND                B  @SCM_LIB.SCM(SCH_1):GND

Q_CAP  I19  C6     [Q_CAP_0402-0.1UF,25V,10%,X7R,CA]
    1  P2V5_AUX           A  @SCM_LIB.SCM(SCH_1):P2V5_AUX
    2  GND                B  @SCM_LIB.SCM(SCH_1):GND

Q_CAP  I24  C7     [Q_CAP_0402-0.1UF,25V,10%,X7R,CA]
    1  P1V2_AUX           A  @SCM_LIB.SCM(SCH_1):P1V2_AUX
    2  GND                B  @SCM_LIB.SCM(SCH_1):GND

Q_CAP  I21  C8     [Q_CAP_0402-0.1UF,25V,10%,X7R,CA]
    1  P2V5_AUX           A  @SCM_LIB.SCM(SCH_1):P2V5_AUX
    2  GND                B  @SCM_LIB.SCM(SCH_1):GND

Q_CAP  I25  C9     [Q_CAP_0402-100PF,50V,5%,NPO,CHA]
    1  P1V2_AUX           A  @SCM_LIB.SCM(SCH_1):P1V2_AUX
    2  GND                B  @SCM_LIB.SCM(SCH_1):GND

Q_CAP  I85  C10    [Q_CAP_0402-0.1UF,25V,10%,X7R,CA]
    1  P0V6_DDR_VREF_AUX      A  @SCM_LIB.SCM(SCH_1):P0V6_DDR_VREF_AUX
    2  GND                B  @SCM_LIB.SCM(SCH_1):GND

Q_CAP  I26  C11    [Q_CAP_0402-0.1UF,10V,10%,EMPTYA]
    1  VDDI_U2_EMMC       A  @SCM_LIB.SCM(SCH_1):VDDI_U2_EMMC
    2  GND                B  @SCM_LIB.SCM(SCH_1):GND

Q_CAP  I106  C12    [Q_CAP_0402-0.22UF,16V,10%,X7R,A]
    1  M_BMC_DDR4_MCLK_C      A  @SCM_LIB.SCM(SCH_1):M_BMC_DDR4_MCLK_C
    2  GND                B  @SCM_LIB.SCM(SCH_1):GND

Q_CAP  I186  C13    [Q_CAP_0402-0.1UF,25V,10%,X7R,CA]
    1  P1V2_AUX           A  @SCM_LIB.SCM(SCH_1):P1V2_AUX
    2  GND                B  @SCM_LIB.SCM(SCH_1):GND

Q_CAP  I187  C14    [Q_CAP_0402-0.1UF,25V,10%,X7R,CA]
    1  P1V2_AUX           A  @SCM_LIB.SCM(SCH_1):P1V2_AUX
    2  GND                B  @SCM_LIB.SCM(SCH_1):GND

Q_CAP  I134  C15    [Q_CAP_C0402-10UF,6.3V,20%,X6S,A]
    1  P1V2_AUX           A  @SCM_LIB.SCM(SCH_1):P1V2_AUX
    2  GND                B  @SCM_LIB.SCM(SCH_1):GND

Q_CAP  I113  C16    [Q_CAP_C0402-10UF,6.3V,20%,X6S,A]
    1  P1V2_AUX           A  @SCM_LIB.SCM(SCH_1):P1V2_AUX
    2  GND                B  @SCM_LIB.SCM(SCH_1):GND

Q_CAP  I190  C17    [Q_CAP_0402-0.1UF,25V,10%,X7R,CA]
    1  P1V2_AUX           A  @SCM_LIB.SCM(SCH_1):P1V2_AUX
    2  GND                B  @SCM_LIB.SCM(SCH_1):GND

Q_CAP  I192  C18    [Q_CAP_0402-0.1UF,25V,10%,X7R,CA]
    1  P1V2_AUX           A  @SCM_LIB.SCM(SCH_1):P1V2_AUX
    2  GND                B  @SCM_LIB.SCM(SCH_1):GND

Q_CAP  I21  C19    [Q_CAP_0402-0.1UF,25V,10%,X7R,CA]
    1  P3V3_AUX           A  @SCM_LIB.SCM(SCH_1):P3V3_AUX
    2  GND                B  @SCM_LIB.SCM(SCH_1):GND

Q_CAP  I47  C20    [Q_CAP_0402-0.1UF,25V,10%,X7R,CA]
    1  P3V3_AUX           A  @SCM_LIB.SCM(SCH_1):P3V3_AUX
    2  GND                B  @SCM_LIB.SCM(SCH_1):GND

Q_CAP  I24  C21    [Q_CAP_C0402-0.01UF,50V,10%,EMPA]
    1  P0V6_DDR_VREF_AUX      A  @SCM_LIB.SCM(SCH_1):P0V6_DDR_VREF_AUX
    2  GND                B  @SCM_LIB.SCM(SCH_1):GND

Q_CAP  I27  C22    [Q_CAP_0402-0.1UF,25V,10%,EMPTYA]
    1  P0V6_DDR_VREF_AUX      A  @SCM_LIB.SCM(SCH_1):P0V6_DDR_VREF_AUX
    2  GND                B  @SCM_LIB.SCM(SCH_1):GND

Q_CAP  I28  C23    [Q_CAP_0402-0.1UF,25V,10%,X7R,CA]
    1  P0V6_DDR_VREF_AUX      A  @SCM_LIB.SCM(SCH_1):P0V6_DDR_VREF_AUX
    2  GND                B  @SCM_LIB.SCM(SCH_1):GND

Q_CAP  I152  C24    [Q_CAP_0402-0.1UF,25V,10%,X7R,CA]
    2  PCIE_BMC_RX_C_DP      B  @SCM_LIB.SCM(SCH_1):PCIE_BMC_RX_C_DP
    1  P2E_BMC_RX_DP      A  @SCM_LIB.SCM(SCH_1):P2E_BMC_RX_DP

Q_CAP  I153  C25    [Q_CAP_0402-0.1UF,25V,10%,X7R,CA]
    2  PCIE_BMC_RX_C_DN      B  @SCM_LIB.SCM(SCH_1):PCIE_BMC_RX_C_DN
    1  P2E_BMC_RX_DN      A  @SCM_LIB.SCM(SCH_1):P2E_BMC_RX_DN

Q_CAP  I161  C26    [Q_CAP_0402-0.1UF,25V,10%,X7R,CA]
    2  DP_BMC_TX0_P       B  @SCM_LIB.SCM(SCH_1):DP_BMC_TX0_P
    1  DP_BMC_C_TX0_P      A  @SCM_LIB.SCM(SCH_1):DP_BMC_C_TX0_P

Q_CAP  I160  C27    [Q_CAP_0402-0.1UF,25V,10%,X7R,CA]
    2  DP_BMC_TX0_N       B  @SCM_LIB.SCM(SCH_1):DP_BMC_TX0_N
    1  DP_BMC_C_TX0_N      A  @SCM_LIB.SCM(SCH_1):DP_BMC_C_TX0_N

Q_CAP  I164  C28    [Q_CAP_0402-0.1UF,25V,10%,X7R,CA]
    2  DP_BMC_TX1_P       B  @SCM_LIB.SCM(SCH_1):DP_BMC_TX1_P
    1  DP_BMC_C_TX1_P      A  @SCM_LIB.SCM(SCH_1):DP_BMC_C_TX1_P

Q_CAP  I163  C29    [Q_CAP_0402-0.1UF,25V,10%,X7R,CA]
    2  DP_BMC_TX1_N       B  @SCM_LIB.SCM(SCH_1):DP_BMC_TX1_N
    1  DP_BMC_C_TX1_N      A  @SCM_LIB.SCM(SCH_1):DP_BMC_C_TX1_N

Q_CAP  I29  C30    [Q_CAP_C0402-1UF,25V,10%,X6S,CHA]
    1  P3V3_P2V5_P1V8_RVDD      A  @SCM_LIB.SCM(SCH_1):P3V3_P2V5_P1V8_RVDD
    2  GND                B  @SCM_LIB.SCM(SCH_1):GND

Q_CAP  I30  C31    [Q_CAP_0402-0.1UF,25V,10%,X7R,CA]
    1  P3V3_P2V5_P1V8_RVDD      A  @SCM_LIB.SCM(SCH_1):P3V3_P2V5_P1V8_RVDD
    2  GND                B  @SCM_LIB.SCM(SCH_1):GND

Q_CAP  I31  C32    [Q_CAP_C0402-1UF,25V,10%,X6S,CHA]
    1  P3V3_P2V5_P1V8_RVDD      A  @SCM_LIB.SCM(SCH_1):P3V3_P2V5_P1V8_RVDD
    2  GND                B  @SCM_LIB.SCM(SCH_1):GND

Q_CAP  I32  C33    [Q_CAP_0402-0.1UF,25V,10%,X7R,CA]
    1  P3V3_P2V5_P1V8_RVDD      A  @SCM_LIB.SCM(SCH_1):P3V3_P2V5_P1V8_RVDD
    2  GND                B  @SCM_LIB.SCM(SCH_1):GND

Q_CAP  I42  C34    [Q_CAP_0402-0.1UF,25V,10%,X7R,CA]
    1  P3V3_AUX           A  @SCM_LIB.SCM(SCH_1):P3V3_AUX
    2  GND                B  @SCM_LIB.SCM(SCH_1):GND

Q_CAP  I14  C35    [Q_CAP_C0402-1UF,25V,10%,X6S,CHA]
    1  P3V3_P1V8_SD1VDD      A  @SCM_LIB.SCM(SCH_1):P3V3_P1V8_SD1VDD
    2  GND                B  @SCM_LIB.SCM(SCH_1):GND

Q_CAP  I16  C36    [Q_CAP_0402-0.1UF,25V,10%,X7R,CA]
    1  P3V3_P1V8_SD1VDD      A  @SCM_LIB.SCM(SCH_1):P3V3_P1V8_SD1VDD
    2  GND                B  @SCM_LIB.SCM(SCH_1):GND

Q_CAP  I24  C37    [Q_CAP_0402-0.1UF,25V,10%,X7R,CA]
    1  P3V3_RGM           A  @SCM_LIB.SCM(SCH_1):P3V3_RGM
    2  GND                B  @SCM_LIB.SCM(SCH_1):GND

Q_CAP  I36  C38    [Q_CAP_C0402-1UF,25V,10%,X6S,CHA]
    1  P3V3_P1V8_SD2VDD      A  @SCM_LIB.SCM(SCH_1):P3V3_P1V8_SD2VDD
    2  GND                B  @SCM_LIB.SCM(SCH_1):GND

Q_CAP  I37  C39    [Q_CAP_0402-0.1UF,25V,10%,X7R,CA]
    1  P3V3_P1V8_SD2VDD      A  @SCM_LIB.SCM(SCH_1):P3V3_P1V8_SD2VDD
    2  GND                B  @SCM_LIB.SCM(SCH_1):GND

Q_CAP  I67  C40    [Q_CAP_C0402-4.7UF,10V,10%,X5R,A]
    1  P1V8_BMC_USB2AV18      A  @SCM_LIB.SCM(SCH_1):P1V8_BMC_USB2AV18
    2  GND                B  @SCM_LIB.SCM(SCH_1):GND

Q_CAP  I68  C41    [Q_CAP_0402-0.1UF,25V,10%,X7R,CA]
    1  P1V8_BMC_USB2AV18      A  @SCM_LIB.SCM(SCH_1):P1V8_BMC_USB2AV18
    2  GND                B  @SCM_LIB.SCM(SCH_1):GND

Q_CAP  I117  C42    [Q_CAP_C0603-22UF,6.3V,20%,X6S,A]
    1  PVCCIO_PECI_BMC      A  @SCM_LIB.SCM(SCH_1):PVCCIO_PECI_BMC
    2  GND                B  @SCM_LIB.SCM(SCH_1):GND

Q_CAP  I119  C43    [Q_CAP_C0402-1UF,25V,10%,X6S,CHA]
    1  PVCCIO_PECI_BMC      A  @SCM_LIB.SCM(SCH_1):PVCCIO_PECI_BMC
    2  GND                B  @SCM_LIB.SCM(SCH_1):GND

Q_CAP  I88  C44    [Q_CAP_C0402-4.7UF,10V,10%,X5R,A]
    1  P3V3_BMC_USB2AV33      A  @SCM_LIB.SCM(SCH_1):P3V3_BMC_USB2AV33
    2  GND                B  @SCM_LIB.SCM(SCH_1):GND

Q_CAP  I89  C45    [Q_CAP_0402-0.1UF,25V,10%,X7R,CA]
    1  P3V3_BMC_USB2AV33      A  @SCM_LIB.SCM(SCH_1):P3V3_BMC_USB2AV33
    2  GND                B  @SCM_LIB.SCM(SCH_1):GND

Q_CAP  I122  C46    [Q_CAP_C0402-1UF,25V,10%,X6S,CHA]
    1  P1V8_STBY_AVDDPLL      A  @SCM_LIB.SCM(SCH_1):P1V8_STBY_AVDDPLL
    2  GND                B  @SCM_LIB.SCM(SCH_1):GND

Q_CAP  I128  C47    [Q_CAP_C0402-1UF,25V,10%,X6S,CHA]
    1  P1V0_STBY_RC_VCC10A      A  @SCM_LIB.SCM(SCH_1):P1V0_STBY_RC_VCC10A
    2  GND                B  @SCM_LIB.SCM(SCH_1):GND

Q_CAP  I148  C48    [Q_CAP_C0402-1UF,25V,10%,X6S,CHA]
    1  P3V3_STBY_DACAV33      A  @SCM_LIB.SCM(SCH_1):P3V3_STBY_DACAV33
    2  GND                B  @SCM_LIB.SCM(SCH_1):GND

Q_CAP  I118  C49    [Q_CAP_0402-0.1UF,25V,10%,X7R,CA]
    1  P1V8_STBY_AVDDPLL      A  @SCM_LIB.SCM(SCH_1):P1V8_STBY_AVDDPLL
    2  GND                B  @SCM_LIB.SCM(SCH_1):GND

Q_CAP  I126  C50    [Q_CAP_0402-0.1UF,25V,10%,X7R,CA]
    1  P1V0_STBY_RC_VCC10A      A  @SCM_LIB.SCM(SCH_1):P1V0_STBY_RC_VCC10A
    2  GND                B  @SCM_LIB.SCM(SCH_1):GND

Q_CAP  I145  C51    [Q_CAP_0402-0.1UF,25V,10%,X7R,CA]
    1  P3V3_STBY_DACAV33      A  @SCM_LIB.SCM(SCH_1):P3V3_STBY_DACAV33
    2  GND                B  @SCM_LIB.SCM(SCH_1):GND

Q_CAP  I31  C52    [Q_CAP_C0402-1UF,25V,10%,X6S,CHA]
    1  P1V0_STBY_PLAVDD      A  @SCM_LIB.SCM(SCH_1):P1V0_STBY_PLAVDD
    2  GND                B  @SCM_LIB.SCM(SCH_1):GND

Q_CAP  I135  C53    [Q_CAP_C0402-1UF,25V,10%,X6S,CHA]
    1  P3V3_P1V8_I2C_I3C      A  @SCM_LIB.SCM(SCH_1):P3V3_P1V8_I2C_I3C
    2  GND                B  @SCM_LIB.SCM(SCH_1):GND

Q_CAP  I32  C54    [Q_CAP_0402-0.1UF,25V,10%,X7R,CA]
    1  P1V0_STBY_PLAVDD      A  @SCM_LIB.SCM(SCH_1):P1V0_STBY_PLAVDD
    2  GND                B  @SCM_LIB.SCM(SCH_1):GND

Q_CAP  I23  C55    [Q_CAP_C0603-22UF,6.3V,20%,X6S,A]
    1  P1V2_AUX           A  @SCM_LIB.SCM(SCH_1):P1V2_AUX
    2  GND                B  @SCM_LIB.SCM(SCH_1):GND

Q_CAP  I33  C56    [Q_CAP_C0402-1UF,25V,10%,X6S,CHA]
    1  P1V0_STBY_PLAVDD      A  @SCM_LIB.SCM(SCH_1):P1V0_STBY_PLAVDD
    2  GND                B  @SCM_LIB.SCM(SCH_1):GND

Q_CAP  I133  C57    [Q_CAP_0402-0.1UF,25V,10%,X7R,CA]
    1  P3V3_P1V8_I2C_I3C      A  @SCM_LIB.SCM(SCH_1):P3V3_P1V8_I2C_I3C
    2  GND                B  @SCM_LIB.SCM(SCH_1):GND

Q_CAP  I52  C58    [Q_CAP_C0402-1UF,25V,10%,X6S,CHA]
    1  P1V2_AUX           A  @SCM_LIB.SCM(SCH_1):P1V2_AUX
    2  GND                B  @SCM_LIB.SCM(SCH_1):GND

Q_CAP  I79  C59    [Q_CAP_0402-0.1UF,25V,10%,X7R,CA]
    1  P1V0_STBY_PLAVDD      A  @SCM_LIB.SCM(SCH_1):P1V0_STBY_PLAVDD
    2  GND                B  @SCM_LIB.SCM(SCH_1):GND

Q_CAP  I141  C60    [Q_CAP_C0402-1UF,25V,10%,X6S,CHA]
    1  P3V3_STBY_PLLAHVDD      A  @SCM_LIB.SCM(SCH_1):P3V3_STBY_PLLAHVDD
    2  GND                B  @SCM_LIB.SCM(SCH_1):GND

Q_CAP  I55  C61    [Q_CAP_C0402-1UF,25V,10%,X6S,CHA]
    1  P1V8_STBY_PE_VCC18A      A  @SCM_LIB.SCM(SCH_1):P1V8_STBY_PE_VCC18A
    2  GND                B  @SCM_LIB.SCM(SCH_1):GND

Q_CAP  I53  C62    [Q_CAP_C0402-1UF,25V,10%,X6S,CHA]
    1  P1V2_AUX           A  @SCM_LIB.SCM(SCH_1):P1V2_AUX
    2  GND                B  @SCM_LIB.SCM(SCH_1):GND

Q_CAP  I46  C63    [Q_CAP_0402-2200PF,50V,10%,X7R,A]
    1  P1V2_STBY_MVDD_CK      A  @SCM_LIB.SCM(SCH_1):P1V2_STBY_MVDD_CK
    2  GND                B  @SCM_LIB.SCM(SCH_1):GND

Q_CAP  I81  C64    [Q_CAP_C0402-1UF,25V,10%,X6S,CHA]
    1  P1V0_STBY_PLAVDD      A  @SCM_LIB.SCM(SCH_1):P1V0_STBY_PLAVDD
    2  GND                B  @SCM_LIB.SCM(SCH_1):GND

Q_CAP  I139  C65    [Q_CAP_0402-0.1UF,25V,10%,X7R,CA]
    1  P3V3_STBY_PLLAHVDD      A  @SCM_LIB.SCM(SCH_1):P3V3_STBY_PLLAHVDD
    2  GND                B  @SCM_LIB.SCM(SCH_1):GND

Q_CAP  I54  C66    [Q_CAP_0402-0.1UF,25V,10%,X7R,CA]
    1  P1V2_AUX           A  @SCM_LIB.SCM(SCH_1):P1V2_AUX
    2  GND                B  @SCM_LIB.SCM(SCH_1):GND

Q_CAP  I48  C67    [Q_CAP_C0402-1UF,25V,10%,X6S,CHA]
    1  P1V2_STBY_MVDD_CK      A  @SCM_LIB.SCM(SCH_1):P1V2_STBY_MVDD_CK
    2  GND                B  @SCM_LIB.SCM(SCH_1):GND

Q_CAP  I82  C68    [Q_CAP_0402-0.1UF,25V,10%,X7R,CA]
    1  P1V0_STBY_PLAVDD      A  @SCM_LIB.SCM(SCH_1):P1V0_STBY_PLAVDD
    2  GND                B  @SCM_LIB.SCM(SCH_1):GND

Q_CAP  I59  C69    [Q_CAP_0402-0.1UF,25V,10%,X7R,CA]
    1  P1V8_STBY_PE_VCC18A      A  @SCM_LIB.SCM(SCH_1):P1V8_STBY_PE_VCC18A
    2  GND                B  @SCM_LIB.SCM(SCH_1):GND

Q_CAP  I57  C70    [Q_CAP_0402-0.1UF,25V,10%,X7R,CA]
    1  P1V2_AUX           A  @SCM_LIB.SCM(SCH_1):P1V2_AUX
    2  GND                B  @SCM_LIB.SCM(SCH_1):GND

Q_CAP  I49  C71    [Q_CAP_0402-0.1UF,25V,10%,X7R,CA]
    1  P1V2_STBY_MVDD_CK      A  @SCM_LIB.SCM(SCH_1):P1V2_STBY_MVDD_CK
    2  GND                B  @SCM_LIB.SCM(SCH_1):GND

Q_CAP  I58  C72    [Q_CAP_0402-0.1UF,25V,10%,X7R,CA]
    1  P1V2_AUX           A  @SCM_LIB.SCM(SCH_1):P1V2_AUX
    2  GND                B  @SCM_LIB.SCM(SCH_1):GND

Q_CAP  I51  C73    [Q_CAP_0402-0.1UF,25V,10%,X7R,CA]
    1  P1V2_STBY_MVDD_CK      A  @SCM_LIB.SCM(SCH_1):P1V2_STBY_MVDD_CK
    2  GND                B  @SCM_LIB.SCM(SCH_1):GND

Q_CAP  I66  C74    [Q_CAP_0402-0.1UF,25V,10%,X7R,CA]
    1  P1V2_AUX           A  @SCM_LIB.SCM(SCH_1):P1V2_AUX
    2  GND                B  @SCM_LIB.SCM(SCH_1):GND

Q_CAP  I93  C75    [Q_CAP_C0402-1UF,25V,10%,X6S,CHA]
    2  GND                B  @SCM_LIB.SCM(SCH_1):GND
    1  A_BMC_ADCAV33      A  @SCM_LIB.SCM(SCH_1):A_BMC_ADCAV33

Q_CAP  I183  C76    [Q_CAP_0402-0.1UF,25V,10%,X7R,CA]
    1  P1V2_AUX           A  @SCM_LIB.SCM(SCH_1):P1V2_AUX
    2  GND                B  @SCM_LIB.SCM(SCH_1):GND

Q_CAP  I100  C77    [Q_CAP_0402-0.1UF,25V,10%,X7R,CA]
    2  GND                B  @SCM_LIB.SCM(SCH_1):GND
    1  A_BMC_ADCAV33      A  @SCM_LIB.SCM(SCH_1):A_BMC_ADCAV33

Q_CAP  I160  C78    [Q_CAP_C0402-1UF,25V,10%,X6S,CHA]
    1  P1V0_STBY_PE_VCC10A      A  @SCM_LIB.SCM(SCH_1):P1V0_STBY_PE_VCC10A
    2  GND                B  @SCM_LIB.SCM(SCH_1):GND

Q_CAP  I157  C79    [Q_CAP_0402-0.1UF,25V,10%,X7R,CA]
    1  P1V0_STBY_PE_VCC10A      A  @SCM_LIB.SCM(SCH_1):P1V0_STBY_PE_VCC10A
    2  GND                B  @SCM_LIB.SCM(SCH_1):GND

Q_CAP  I153  C80    [Q_CAP_C0402-1UF,25V,10%,X6S,CHA]
    1  P1V8_STBY_RC_VCC18A      A  @SCM_LIB.SCM(SCH_1):P1V8_STBY_RC_VCC18A
    2  GND                B  @SCM_LIB.SCM(SCH_1):GND

Q_CAP  I151  C81    [Q_CAP_0402-0.1UF,25V,10%,X7R,CA]
    1  P1V8_STBY_RC_VCC18A      A  @SCM_LIB.SCM(SCH_1):P1V8_STBY_RC_VCC18A
    2  GND                B  @SCM_LIB.SCM(SCH_1):GND

Q_CAP  I180  C82    [Q_CAP_0402-0.1UF,25V,10%,X7R,CA]
    1  P1V2_AUX           A  @SCM_LIB.SCM(SCH_1):P1V2_AUX
    2  GND                B  @SCM_LIB.SCM(SCH_1):GND

Q_CAP  I106  C83    [Q_CAP_0402-0.1UF,25V,10%,X7R,CA]
    1  P3V3_RTC_AUX       A  @SCM_LIB.SCM(SCH_1):P3V3_RTC_AUX
    2  GND                B  @SCM_LIB.SCM(SCH_1):GND

Q_CAP  I179  C84    [Q_CAP_0402-0.1UF,25V,10%,X7R,CA]
    1  P1V2_AUX           A  @SCM_LIB.SCM(SCH_1):P1V2_AUX
    2  GND                B  @SCM_LIB.SCM(SCH_1):GND

Q_CAP  I120  C85    [Q_CAP_0402-0.1UF,25V,10%,X7R,CA]
    1  P3V3_RGM           A  @SCM_LIB.SCM(SCH_1):P3V3_RGM
    2  GND                B  @SCM_LIB.SCM(SCH_1):GND

Q_CAP  I149  C86    [Q_CAP_0402-0.1UF,25V,10%,X7R,CA]
    1  P1V0_AUX           A  @SCM_LIB.SCM(SCH_1):P1V0_AUX
    2  GND                B  @SCM_LIB.SCM(SCH_1):GND

Q_CAP  I147  C87    [Q_CAP_0402-0.1UF,25V,10%,X7R,CA]
    1  P1V8_AUX           A  @SCM_LIB.SCM(SCH_1):P1V8_AUX
    2  GND                B  @SCM_LIB.SCM(SCH_1):GND

Q_CAP  I123  C88    [Q_CAP_0402-0.1UF,25V,10%,X7R,CA]
    1  P3V3_AUX           A  @SCM_LIB.SCM(SCH_1):P3V3_AUX
    2  GND                B  @SCM_LIB.SCM(SCH_1):GND

Q_CAP  I118  C89    [Q_CAP_0402-0.1UF,25V,10%,X7R,CA]
    1  P1V8_AUX           A  @SCM_LIB.SCM(SCH_1):P1V8_AUX
    2  GND                B  @SCM_LIB.SCM(SCH_1):GND

Q_CAP  I173  C90    [Q_CAP_C0402-1UF,25V,10%,X6S,CHA]
    1  P1V0_STBY_DP_VCC10A      A  @SCM_LIB.SCM(SCH_1):P1V0_STBY_DP_VCC10A
    2  GND                B  @SCM_LIB.SCM(SCH_1):GND

Q_CAP  I151  C91    [Q_CAP_0402-0.1UF,25V,10%,X7R,CA]
    1  P1V2_AUX           A  @SCM_LIB.SCM(SCH_1):P1V2_AUX
    2  GND                B  @SCM_LIB.SCM(SCH_1):GND

Q_CAP  I150  C92    [Q_CAP_0402-0.1UF,25V,10%,X7R,CA]
    1  P1V0_AUX           A  @SCM_LIB.SCM(SCH_1):P1V0_AUX
    2  GND                B  @SCM_LIB.SCM(SCH_1):GND

Q_CAP  I148  C93    [Q_CAP_0402-0.1UF,25V,10%,X7R,CA]
    1  P1V8_AUX           A  @SCM_LIB.SCM(SCH_1):P1V8_AUX
    2  GND                B  @SCM_LIB.SCM(SCH_1):GND

Q_CAP  I124  C94    [Q_CAP_0402-0.1UF,25V,10%,X7R,CA]
    1  P3V3_AUX           A  @SCM_LIB.SCM(SCH_1):P3V3_AUX
    2  GND                B  @SCM_LIB.SCM(SCH_1):GND

Q_CAP  I119  C95    [Q_CAP_0402-0.1UF,25V,10%,X7R,CA]
    1  P1V8_AUX           A  @SCM_LIB.SCM(SCH_1):P1V8_AUX
    2  GND                B  @SCM_LIB.SCM(SCH_1):GND

Q_CAP  I178  C96    [Q_CAP_0402-0.1UF,25V,10%,X7R,CA]
    1  PGPPA_BMC_AUX      A  @SCM_LIB.SCM(SCH_1):PGPPA_BMC_AUX
    2  GND                B  @SCM_LIB.SCM(SCH_1):GND

Q_CAP  I169  C97    [Q_CAP_0402-0.1UF,25V,10%,X7R,CA]
    1  P1V0_STBY_DP_VCC10A      A  @SCM_LIB.SCM(SCH_1):P1V0_STBY_DP_VCC10A
    2  GND                B  @SCM_LIB.SCM(SCH_1):GND

Q_CAP  I163  C98    [Q_CAP_0402-0.1UF,25V,10%,X7R,CA]
    1  P1V2_AUX           A  @SCM_LIB.SCM(SCH_1):P1V2_AUX
    2  GND                B  @SCM_LIB.SCM(SCH_1):GND

Q_CAP  I154  C99    [Q_CAP_0402-0.1UF,25V,10%,X7R,CA]
    1  P1V0_AUX           A  @SCM_LIB.SCM(SCH_1):P1V0_AUX
    2  GND                B  @SCM_LIB.SCM(SCH_1):GND

Q_CAP  I152  C100   [Q_CAP_0402-0.1UF,25V,10%,X7R,CA]
    1  P1V8_AUX           A  @SCM_LIB.SCM(SCH_1):P1V8_AUX
    2  GND                B  @SCM_LIB.SCM(SCH_1):GND

Q_CAP  I132  C101   [Q_CAP_0402-0.1UF,25V,10%,X7R,CA]
    1  P3V3_AUX           A  @SCM_LIB.SCM(SCH_1):P3V3_AUX
    2  GND                B  @SCM_LIB.SCM(SCH_1):GND

Q_CAP  I126  C102   [Q_CAP_0402-0.1UF,25V,10%,X7R,CA]
    1  P1V8_AUX           A  @SCM_LIB.SCM(SCH_1):P1V8_AUX
    2  GND                B  @SCM_LIB.SCM(SCH_1):GND

Q_CAP  I164  C103   [Q_CAP_0402-0.1UF,25V,10%,X7R,CA]
    1  P1V2_AUX           A  @SCM_LIB.SCM(SCH_1):P1V2_AUX
    2  GND                B  @SCM_LIB.SCM(SCH_1):GND

Q_CAP  I155  C104   [Q_CAP_C0402-1UF,25V,10%,X6S,CHA]
    1  P1V0_AUX           A  @SCM_LIB.SCM(SCH_1):P1V0_AUX
    2  GND                B  @SCM_LIB.SCM(SCH_1):GND

Q_CAP  I153  C105   [Q_CAP_0402-0.1UF,25V,10%,X7R,CA]
    1  P1V8_AUX           A  @SCM_LIB.SCM(SCH_1):P1V8_AUX
    2  GND                B  @SCM_LIB.SCM(SCH_1):GND

Q_CAP  I127  C106   [Q_CAP_C0402-1UF,25V,10%,X6S,CHA]
    1  P1V8_AUX           A  @SCM_LIB.SCM(SCH_1):P1V8_AUX
    2  GND                B  @SCM_LIB.SCM(SCH_1):GND

Q_CAP  I165  C107   [Q_CAP_0402-0.1UF,25V,10%,X7R,CA]
    1  P1V2_AUX           A  @SCM_LIB.SCM(SCH_1):P1V2_AUX
    2  GND                B  @SCM_LIB.SCM(SCH_1):GND

Q_CAP  I157  C108   [Q_CAP_C0402-1UF,25V,10%,X6S,CHA]
    1  P1V0_AUX           A  @SCM_LIB.SCM(SCH_1):P1V0_AUX
    2  GND                B  @SCM_LIB.SCM(SCH_1):GND

Q_CAP  I156  C109   [Q_CAP_0402-0.1UF,25V,10%,X7R,CA]
    1  P1V8_AUX           A  @SCM_LIB.SCM(SCH_1):P1V8_AUX
    2  GND                B  @SCM_LIB.SCM(SCH_1):GND

Q_CAP  I133  C110   [Q_CAP_C0402-1UF,25V,10%,X6S,CHA]
    1  P3V3_AUX           A  @SCM_LIB.SCM(SCH_1):P3V3_AUX
    2  GND                B  @SCM_LIB.SCM(SCH_1):GND

Q_CAP  I128  C111   [Q_CAP_C0402-1UF,25V,10%,X6S,CHA]
    1  P1V8_AUX           A  @SCM_LIB.SCM(SCH_1):P1V8_AUX
    2  GND                B  @SCM_LIB.SCM(SCH_1):GND

Q_CAP  I166  C112   [Q_CAP_0402-0.1UF,25V,10%,X7R,CA]
    1  P1V2_AUX           A  @SCM_LIB.SCM(SCH_1):P1V2_AUX
    2  GND                B  @SCM_LIB.SCM(SCH_1):GND

Q_CAP  I160  C113   [Q_CAP_C0603-22UF,10V,20%,X5R,CA]
    1  P1V0_AUX           A  @SCM_LIB.SCM(SCH_1):P1V0_AUX
    2  GND                B  @SCM_LIB.SCM(SCH_1):GND

Q_CAP  I158  C114   [Q_CAP_C0402-1UF,25V,10%,X6S,CHA]
    1  P1V8_AUX           A  @SCM_LIB.SCM(SCH_1):P1V8_AUX
    2  GND                B  @SCM_LIB.SCM(SCH_1):GND

Q_CAP  I135  C115   [Q_CAP_C0402-1UF,25V,10%,X6S,CHA]
    1  P3V3_AUX           A  @SCM_LIB.SCM(SCH_1):P3V3_AUX
    2  GND                B  @SCM_LIB.SCM(SCH_1):GND

Q_CAP  I129  C116   [Q_CAP_C0402-1UF,25V,10%,X6S,CHA]
    1  P1V8_AUX           A  @SCM_LIB.SCM(SCH_1):P1V8_AUX
    2  GND                B  @SCM_LIB.SCM(SCH_1):GND

Q_CAP  I167  C117   [Q_CAP_C0402-1UF,25V,10%,X6S,CHA]
    1  P1V2_AUX           A  @SCM_LIB.SCM(SCH_1):P1V2_AUX
    2  GND                B  @SCM_LIB.SCM(SCH_1):GND

Q_CAP  I162  C118   [Q_CAP_C0603-22UF,6.3V,20%,X6S,A]
    1  P1V0_AUX           A  @SCM_LIB.SCM(SCH_1):P1V0_AUX
    2  GND                B  @SCM_LIB.SCM(SCH_1):GND

Q_CAP  I159  C119   [Q_CAP_C0402-1UF,25V,10%,X6S,CHA]
    1  P1V8_AUX           A  @SCM_LIB.SCM(SCH_1):P1V8_AUX
    2  GND                B  @SCM_LIB.SCM(SCH_1):GND

Q_CAP  I136  C120   [Q_CAP_C0603-22UF,10V,20%,X5R,CA]
    1  P3V3_AUX           A  @SCM_LIB.SCM(SCH_1):P3V3_AUX
    2  GND                B  @SCM_LIB.SCM(SCH_1):GND

Q_CAP  I131  C121   [Q_CAP_C0603-22UF,6.3V,20%,X6S,A]
    1  P1V8_AUX           A  @SCM_LIB.SCM(SCH_1):P1V8_AUX
    2  GND                B  @SCM_LIB.SCM(SCH_1):GND

Q_CAP  I168  C122   [Q_CAP_C0402-1UF,25V,10%,X6S,CHA]
    1  P1V2_AUX           A  @SCM_LIB.SCM(SCH_1):P1V2_AUX
    2  GND                B  @SCM_LIB.SCM(SCH_1):GND

Q_CAP  I171  C123   [Q_CAP_C0603-22UF,6.3V,20%,X6S,A]
    1  P1V0_AUX           A  @SCM_LIB.SCM(SCH_1):P1V0_AUX
    2  GND                B  @SCM_LIB.SCM(SCH_1):GND

Q_CAP  I169  C124   [Q_CAP_C0603-22UF,6.3V,20%,X6S,A]
    1  P1V8_AUX           A  @SCM_LIB.SCM(SCH_1):P1V8_AUX
    2  GND                B  @SCM_LIB.SCM(SCH_1):GND

Q_CAP  I145  C125   [Q_CAP_C0603-22UF,10V,20%,X5R,CA]
    1  P3V3_AUX           A  @SCM_LIB.SCM(SCH_1):P3V3_AUX
    2  GND                B  @SCM_LIB.SCM(SCH_1):GND

Q_CAP  I143  C126   [Q_CAP_C0603-22UF,6.3V,20%,X6S,A]
    1  P1V8_AUX           A  @SCM_LIB.SCM(SCH_1):P1V8_AUX
    2  GND                B  @SCM_LIB.SCM(SCH_1):GND

Q_CAP  I173  C127   [Q_CAP_C0402-1UF,25V,10%,X6S,CHA]
    1  P1V2_AUX           A  @SCM_LIB.SCM(SCH_1):P1V2_AUX
    2  GND                B  @SCM_LIB.SCM(SCH_1):GND

Q_CAP  I165  C128   [Q_CAP_C0402-1UF,25V,10%,X6S,CHA]
    1  P1V8_STBY_DP_VCC18A      A  @SCM_LIB.SCM(SCH_1):P1V8_STBY_DP_VCC18A
    2  GND                B  @SCM_LIB.SCM(SCH_1):GND

Q_CAP  I174  C129   [Q_CAP_C0402-1UF,25V,10%,X6S,CHA]
    1  P1V2_AUX           A  @SCM_LIB.SCM(SCH_1):P1V2_AUX
    2  GND                B  @SCM_LIB.SCM(SCH_1):GND

Q_CAP  I163  C130   [Q_CAP_0402-0.1UF,25V,10%,X7R,CA]
    1  P1V8_STBY_DP_VCC18A      A  @SCM_LIB.SCM(SCH_1):P1V8_STBY_DP_VCC18A
    2  GND                B  @SCM_LIB.SCM(SCH_1):GND

Q_CAP  I176  C131   [Q_CAP_C0603-22UF,10V,20%,X5R,CA]
    1  P1V2_AUX           A  @SCM_LIB.SCM(SCH_1):P1V2_AUX
    2  GND                B  @SCM_LIB.SCM(SCH_1):GND

Q_CAP  I177  C132   [Q_CAP_C0603-22UF,10V,20%,X5R,CA]
    1  P1V2_AUX           A  @SCM_LIB.SCM(SCH_1):P1V2_AUX
    2  GND                B  @SCM_LIB.SCM(SCH_1):GND

Q_CAP  I104  C133   [Q_CAP_C0402-0.01UF,50V,10%,X7RA]
    1  GND                A  @SCM_LIB.SCM(SCH_1):GND
    2  A_BMC_ADCVREFN1      B  @SCM_LIB.SCM(SCH_1):A_BMC_ADCVREFN1

Q_CAP  I106  C134   [Q_CAP_C0402-0.01UF,50V,10%,X7RA]
    1  GND                A  @SCM_LIB.SCM(SCH_1):GND
    2  A_BMC_ADCVREFN0      B  @SCM_LIB.SCM(SCH_1):A_BMC_ADCVREFN0

Q_CAP  I107  C135   [Q_CAP_C0402-0.01UF,50V,10%,X7RA]
    1  GND                A  @SCM_LIB.SCM(SCH_1):GND
    2  A_BMC_ADCVREFP1      B  @SCM_LIB.SCM(SCH_1):A_BMC_ADCVREFP1

Q_CAP  I110  C136   [Q_CAP_C0402-0.01UF,50V,10%,X7RA]
    1  GND                A  @SCM_LIB.SCM(SCH_1):GND
    2  A_BMC_ADCVREFP0      B  @SCM_LIB.SCM(SCH_1):A_BMC_ADCVREFP0

Q_CAP  I108  C137   [Q_CAP_C0402-0.01UF,50V,10%,X7RA]
    2  A_BMC_ADCVREFP1      B  @SCM_LIB.SCM(SCH_1):A_BMC_ADCVREFP1
    1  A_BMC_ADCVREFN1      A  @SCM_LIB.SCM(SCH_1):A_BMC_ADCVREFN1

Q_CAP  I109  C138   [Q_CAP_C0402-0.01UF,50V,10%,X7RA]
    2  A_BMC_ADCVREFP0      B  @SCM_LIB.SCM(SCH_1):A_BMC_ADCVREFP0
    1  A_BMC_ADCVREFN0      A  @SCM_LIB.SCM(SCH_1):A_BMC_ADCVREFN0

Q_CAP  I98  C139   [Q_CAP_0402-0.1UF,25V,10%,X7R,CA]
    1  P1V2_P1V0_I3C_VDDL1      A  @SCM_LIB.SCM(SCH_1):P1V2_P1V0_I3C_VDDL1
    2  GND                B  @SCM_LIB.SCM(SCH_1):GND

Q_CAP  I97  C140   [Q_CAP_0402-0.1UF,25V,10%,X7R,CA]
    1  P1V2_P1V0_I3C_VDDL2      A  @SCM_LIB.SCM(SCH_1):P1V2_P1V0_I3C_VDDL2
    2  GND                B  @SCM_LIB.SCM(SCH_1):GND

Q_CAP  I206  C141   [Q_CAP_C0402-12PF,50V,5%,C0G,CHA]
    1  XTAL_PHY_XI_R      A  @SCM_LIB.SCM(SCH_1):XTAL_PHY_XI_R
    2  GND                B  @SCM_LIB.SCM(SCH_1):GND

Q_CAP  I28  C142   [Q_CAP_C0402-0.01UF,50V,10%,EMPA]
    2  RST_RSTB_N         B  @SCM_LIB.SCM(SCH_1):RST_RSTB_N
    1  GND                A  @SCM_LIB.SCM(SCH_1):GND

Q_CAP  I108  C143   [Q_CAP_C0402-10UF,10V,20%,X5R,CA]
    1  P3V3_AUX           A  @SCM_LIB.SCM(SCH_1):P3V3_AUX
    2  GND                B  @SCM_LIB.SCM(SCH_1):GND

Q_CAP  I102  C144   [Q_CAP_0402-0.1UF,25V,10%,X7R,CA]
    1  P3V3_AUX           A  @SCM_LIB.SCM(SCH_1):P3V3_AUX
    2  GND                B  @SCM_LIB.SCM(SCH_1):GND

Q_CAP  I201  C145   [Q_CAP_C0402-12PF,50V,5%,C0G,CHA]
    1  XTAL_PHY_XO_R      A  @SCM_LIB.SCM(SCH_1):XTAL_PHY_XO_R
    2  GND                B  @SCM_LIB.SCM(SCH_1):GND

Q_CAP  I292  C146   [Q_CAP_0402-0.1UF,25V,10%,X7R,CA]
    1  P3V3_AUX           A  @SCM_LIB.SCM(SCH_1):P3V3_AUX
    2  GND                B  @SCM_LIB.SCM(SCH_1):GND

Q_CAP  I17  C147   [Q_CAP_0402-0.1UF,25V,10%,X7R,CA]
    1  P3V3_AUX           A  @SCM_LIB.SCM(SCH_1):P3V3_AUX
    2  GND                B  @SCM_LIB.SCM(SCH_1):GND

Q_CAP  I48  C148   [Q_CAP_0402-0.1UF,25V,10%,X7R,CA]
    1  P3V3_AUX           A  @SCM_LIB.SCM(SCH_1):P3V3_AUX
    2  GND                B  @SCM_LIB.SCM(SCH_1):GND

Q_CAP  I17  C149   [Q_CAP_0402-0.1UF,25V,10%,X7R,CA]
    1  P3V3_AUX           A  @SCM_LIB.SCM(SCH_1):P3V3_AUX
    2  GND                B  @SCM_LIB.SCM(SCH_1):GND

Q_CAP  I49  C150   [Q_CAP_C0402-0.001UF,50V,10%,X7A]
    1  PWRGD_P5V_AUX_R      A  @SCM_LIB.SCM(SCH_1):PWRGD_P5V_AUX_R
    2  GND                B  @SCM_LIB.SCM(SCH_1):GND

Q_CAP  I93  C151   [Q_CAP_C0402-0.001UF,50V,10%,X7A]
    1  PWRGD_P3V3_AUX_R      A  @SCM_LIB.SCM(SCH_1):PWRGD_P3V3_AUX_R
    2  GND                B  @SCM_LIB.SCM(SCH_1):GND

Q_CAP  I87  C152   [Q_CAP_0402-22PF,50V,5%,EMPTY,TA]
    1  RGMII_BMC_RX_CLK      A  @SCM_LIB.SCM(SCH_1):RGMII_BMC_RX_CLK
    2  GND                B  @SCM_LIB.SCM(SCH_1):GND

Q_CAP  I64  C153   [Q_CAP_C0402-0.001UF,50V,10%,X7A]
    1  PWRGD_P2V5_AUX_R      A  @SCM_LIB.SCM(SCH_1):PWRGD_P2V5_AUX_R
    2  GND                B  @SCM_LIB.SCM(SCH_1):GND

Q_CAP  I100  C154   [Q_CAP_C0402-0.001UF,50V,10%,X7A]
    1  PWRGD_P1V8_AUX_R      A  @SCM_LIB.SCM(SCH_1):PWRGD_P1V8_AUX_R
    2  GND                B  @SCM_LIB.SCM(SCH_1):GND

Q_CAP  I52  C155   [Q_CAP_C0402-0.001UF,50V,10%,X7A]
    1  PWRGD_P1V2_AUX_R      A  @SCM_LIB.SCM(SCH_1):PWRGD_P1V2_AUX_R
    2  GND                B  @SCM_LIB.SCM(SCH_1):GND

Q_CAP  I51  C156   [Q_CAP_C0402-0.001UF,50V,10%,X7A]
    1  PWRGD_P1V0_AUX_R      A  @SCM_LIB.SCM(SCH_1):PWRGD_P1V0_AUX_R
    2  GND                B  @SCM_LIB.SCM(SCH_1):GND

Q_CAP  I3   C157   [Q_CAP_0402-0.1UF,25V,10%,X7R,CA]
    1  P3V3_AUX           A  @SCM_LIB.SCM(SCH_1):P3V3_AUX
    2  GND                B  @SCM_LIB.SCM(SCH_1):GND

Q_CAP  I18  C158   [Q_CAP_0402-0.1UF,25V,10%,X7R,CA]
    1  P3V3_AUX           A  @SCM_LIB.SCM(SCH_1):P3V3_AUX
    2  GND                B  @SCM_LIB.SCM(SCH_1):GND

Q_CAP  I15  C159   [Q_CAP_0402-0.1UF,25V,10%,X7R,CA]
    1  P3V3_AUX           A  @SCM_LIB.SCM(SCH_1):P3V3_AUX
    2  GND                B  @SCM_LIB.SCM(SCH_1):GND

Q_CAP  I48  C160   [Q_CAP_0402-0.1UF,25V,10%,X7R,CA]
    1  P3V3_AUX_RJ45      A  @SCM_LIB.SCM(SCH_1):P3V3_AUX_RJ45
    2  GND                B  @SCM_LIB.SCM(SCH_1):GND

Q_CAP  I23  C161   [Q_CAP_C0402-1UF,25V,10%,X6S,CHA]
    2  RST_BMC_SELF_HW_D_C      B  @SCM_LIB.SCM(SCH_1):RST_BMC_SELF_HW_D_C
    1  RST_BMC_SELF_HW_D      A  @SCM_LIB.SCM(SCH_1):RST_BMC_SELF_HW_D

Q_CAP  I51  C162   [Q_CAP_C0603-10UF,16V,20%,X6S,CA]
    1  P3V3_AUX_RJ45      A  @SCM_LIB.SCM(SCH_1):P3V3_AUX_RJ45
    2  GND                B  @SCM_LIB.SCM(SCH_1):GND

Q_CAP  I125  C163   [Q_CAP_C0402-0.01UF,50V,10%,X7RA]
    1  PHY_CT             A  @SCM_LIB.SCM(SCH_1):PHY_CT
    2  GND                B  @SCM_LIB.SCM(SCH_1):GND

Q_CAP  I124  C164   [Q_CAP_C0402-0.01UF,50V,10%,X7RA]
    1  PHY_CT             A  @SCM_LIB.SCM(SCH_1):PHY_CT
    2  GND                B  @SCM_LIB.SCM(SCH_1):GND

Q_CAP  I78  C165   [Q_CAP_0402-100PF,50V,5%,NPO,CHA]
    1  PHY_LED3           A  @SCM_LIB.SCM(SCH_1):PHY_LED3
    2  GND                B  @SCM_LIB.SCM(SCH_1):GND

Q_CAP  I69  C166   [Q_CAP_0402-100PF,50V,5%,NPO,CHA]
    1  PHY_LED1           A  @SCM_LIB.SCM(SCH_1):PHY_LED1
    2  GND                B  @SCM_LIB.SCM(SCH_1):GND

Q_CAP  I66  C167   [Q_CAP_0402-100PF,50V,5%,NPO,CHA]
    1  PHY_LED2           A  @SCM_LIB.SCM(SCH_1):PHY_LED2
    2  GND                B  @SCM_LIB.SCM(SCH_1):GND

Q_CAP  I32  C168   [Q_CAP_0402-0.1UF,25V,10%,X7R,CA]
    1  P0V6_DDR_VREF_AUX      A  @SCM_LIB.SCM(SCH_1):P0V6_DDR_VREF_AUX
    2  GND                B  @SCM_LIB.SCM(SCH_1):GND

Q_CAP  I34  C169   [Q_CAP_C0402-0.01UF,50V,10%,EMPA]
    1  P1V2_AUX           A  @SCM_LIB.SCM(SCH_1):P1V2_AUX
    2  P0V6_DDR_VREF_AUX      B  @SCM_LIB.SCM(SCH_1):P0V6_DDR_VREF_AUX

Q_CAP  I33  C170   [Q_CAP_C0402-0.01UF,50V,10%,X7RA]
    1  P0V6_DDR_VREF_AUX      A  @SCM_LIB.SCM(SCH_1):P0V6_DDR_VREF_AUX
    2  GND                B  @SCM_LIB.SCM(SCH_1):GND

Q_CAP  I38  C171   [Q_CAP_C0805-22UF,16V,20%,X6S,CA]
    1  P5V_AUX            A  @SCM_LIB.SCM(SCH_1):P5V_AUX
    2  GND                B  @SCM_LIB.SCM(SCH_1):GND

Q_CAP  I35  C172   [Q_CAP_0402-470PF,50V,10%,X7R,TA]
    1  P5V_AUX            A  @SCM_LIB.SCM(SCH_1):P5V_AUX
    2  GND                B  @SCM_LIB.SCM(SCH_1):GND

Q_CAP  I24  C173   [Q_CAP_C0402-0.1UF,25V,10%,X6S,A]
    1  RST_BMC_SELF_HW_D_C      A  @SCM_LIB.SCM(SCH_1):RST_BMC_SELF_HW_D_C
    2  GND                B  @SCM_LIB.SCM(SCH_1):GND

Q_CAP  I503  C174   [Q_CAP_0402-0.1UF,25V,10%,X7R,CA]
    1  P3V_BAT_R          A  @SCM_LIB.SCM(SCH_1):P3V_BAT_R
    2  GND                B  @SCM_LIB.SCM(SCH_1):GND

Q_CAP  I114  C175   [Q_CAP_0402-0.1UF,25V,10%,X7R,CA]
    1  P3V3_AUX           A  @SCM_LIB.SCM(SCH_1):P3V3_AUX
    2  GND                B  @SCM_LIB.SCM(SCH_1):GND

Q_CAP  I34  C177   [Q_CAP_1206-47UF ,10V,20%,X5R,CA]
    1  P5V_USB_REAR       A  @SCM_LIB.SCM(SCH_1):P5V_USB_REAR
    2  GND                B  @SCM_LIB.SCM(SCH_1):GND

Q_CAP  I31  C178   [Q_CAP_0402-470PF,50V,10%,X7R,TA]
    1  P5V_USB_REAR       A  @SCM_LIB.SCM(SCH_1):P5V_USB_REAR
    2  GND                B  @SCM_LIB.SCM(SCH_1):GND

Q_CAP  I30  C179   [Q_CAP_0402-470PF,50V,10%,X7R,TA]
    1  P5V_USB_REAR       A  @SCM_LIB.SCM(SCH_1):P5V_USB_REAR
    2  GND                B  @SCM_LIB.SCM(SCH_1):GND

Q_CAP  I6   C180   [Q_CAP_C0402-0.1UF,16V,10%,X7R,A]
    1  P3V3_AUX           A  @SCM_LIB.SCM(SCH_1):P3V3_AUX
    2  GND                B  @SCM_LIB.SCM(SCH_1):GND

Q_CAP  I13  C181   [Q_CAP_0402-1UF,16V,10%,EMPTY,TA]
    1  LOADSW_CT          A  @SCM_LIB.SCM(SCH_1):LOADSW_CT
    2  GND                B  @SCM_LIB.SCM(SCH_1):GND

Q_CAP  I8   C182   [Q_CAP_C0402-0.1UF,16V,10%,X7R,A]
    1  P3V3_DP            A  @SCM_LIB.SCM(SCH_1):P3V3_DP
    2  GND                B  @SCM_LIB.SCM(SCH_1):GND

Q_CAP  I102  C183   [Q_CAP_C0603-22UF,10V,20%,X5R,CA]
    1  P3V3_DP_L          A  @SCM_LIB.SCM(SCH_1):P3V3_DP_L
    2  GND                B  @SCM_LIB.SCM(SCH_1):GND

Q_CAP  I101  C184   [Q_CAP_C0603-22UF,10V,20%,X5R,CA]
    1  P3V3_DP_L          A  @SCM_LIB.SCM(SCH_1):P3V3_DP_L
    2  GND                B  @SCM_LIB.SCM(SCH_1):GND

Q_CAP  I119  C185   [Q_CAP_0402-0.1UF,25V,10%,X7R,CA]
    2  DP_BMC_AUX_P       B  @SCM_LIB.SCM(SCH_1):DP_BMC_AUX_P
    1  DP_BMC_AUX_C_P      A  @SCM_LIB.SCM(SCH_1):DP_BMC_AUX_C_P

Q_CAP  I120  C186   [Q_CAP_0402-0.1UF,25V,10%,X7R,CA]
    2  DP_BMC_AUX_N       B  @SCM_LIB.SCM(SCH_1):DP_BMC_AUX_N
    1  DP_BMC_AUX_C_N      A  @SCM_LIB.SCM(SCH_1):DP_BMC_AUX_C_N

Q_CAP  I93  C187   [Q_CAP_0402-0.1UF,25V,10%,X7R,CA]
    1  P3V3_PL2303        A  @SCM_LIB.SCM(SCH_1):P3V3_PL2303
    2  GND                B  @SCM_LIB.SCM(SCH_1):GND

Q_CAP  I79  C188   [Q_CAP_C0603-10UF,16V,20%,X6S,CA]
    1  P5V_BUS            A  @SCM_LIB.SCM(SCH_1):P5V_BUS
    2  GND                B  @SCM_LIB.SCM(SCH_1):GND

Q_CAP  I78  C189   [Q_CAP_0402-0.1UF,25V,10%,X7R,CA]
    1  P5V_BUS            A  @SCM_LIB.SCM(SCH_1):P5V_BUS
    2  GND                B  @SCM_LIB.SCM(SCH_1):GND

Q_CAP  I76  C190   [Q_CAP_C0603-10UF,16V,20%,X6S,CA]
    1  P5V_BUS            A  @SCM_LIB.SCM(SCH_1):P5V_BUS
    2  GND                B  @SCM_LIB.SCM(SCH_1):GND

Q_CAP  I25  C191   [Q_CAP_0402-0.1UF,25V,10%,X7R,CA]
    1  P3V3_AUX           A  @SCM_LIB.SCM(SCH_1):P3V3_AUX
    2  GND                B  @SCM_LIB.SCM(SCH_1):GND

Q_CAP  I17  C192   [Q_CAP_0402-0.1UF,25V,10%,X7R,CA]
    1  P3V3_AUX           A  @SCM_LIB.SCM(SCH_1):P3V3_AUX
    2  GND                B  @SCM_LIB.SCM(SCH_1):GND

Q_CAP  I17  C193   [Q_CAP_0402-2.2UF,10V,20%,X5R,TA]
    1  PVCCA_AUX_PLD      A  @SCM_LIB.SCM(SCH_1):PVCCA_AUX_PLD
    2  GND                B  @SCM_LIB.SCM(SCH_1):GND

Q_CAP  I13  C194   [Q_CAP_0402-0.1UF,25V,10%,X7R,CA]
    1  PVCCA_AUX_PLD      A  @SCM_LIB.SCM(SCH_1):PVCCA_AUX_PLD
    2  GND                B  @SCM_LIB.SCM(SCH_1):GND

Q_CAP  I11  C195   [Q_CAP_0402-0.1UF,25V,10%,X7R,CA]
    1  PVCCA_AUX_PLD      A  @SCM_LIB.SCM(SCH_1):PVCCA_AUX_PLD
    2  GND                B  @SCM_LIB.SCM(SCH_1):GND

Q_CAP  I109  C196   [Q_CAP_0402-0.1UF,25V,10%,X7R,CA]
    1  P3V3_LED           A  @SCM_LIB.SCM(SCH_1):P3V3_LED
    2  GND                B  @SCM_LIB.SCM(SCH_1):GND

Q_CAP  I96  C197   [Q_CAP_0402-0.1UF,25V,10%,X7R,CA]
    1  ID_LED_P3V3_AUX      A  @SCM_LIB.SCM(SCH_1):ID_LED_P3V3_AUX
    2  GND                B  @SCM_LIB.SCM(SCH_1):GND

Q_CAP  I44  C198   [Q_CAP_C0402-1UF,25V,10%,X6S,CHA]
    1  REAR_PWR_BTN_N      A  @SCM_LIB.SCM(SCH_1):REAR_PWR_BTN_N
    2  GND                B  @SCM_LIB.SCM(SCH_1):GND

Q_CAP  I55  C199   [Q_CAP_C0402-1UF,25V,10%,X6S,CHA]
    1  REAR_ID_RST_BTN_N      A  @SCM_LIB.SCM(SCH_1):REAR_ID_RST_BTN_N
    2  GND                B  @SCM_LIB.SCM(SCH_1):GND

Q_CAP  I43  C200   [Q_CAP_0402-0.1UF,25V,10%,X7R,CA]
    1  P3V3_AUX           A  @SCM_LIB.SCM(SCH_1):P3V3_AUX
    2  GND                B  @SCM_LIB.SCM(SCH_1):GND

Q_CAP  I51  C201   [Q_CAP_0402-0.1UF,25V,10%,X7R,CA]
    1  P3V3_AUX           A  @SCM_LIB.SCM(SCH_1):P3V3_AUX
    2  GND                B  @SCM_LIB.SCM(SCH_1):GND

Q_CAP  I11  C202   [Q_CAP_0402-0.1UF,25V,10%,X7R,CA]
    1  P5V_AUX            A  @SCM_LIB.SCM(SCH_1):P5V_AUX
    2  GND                B  @SCM_LIB.SCM(SCH_1):GND

Q_CAP  I12  C203   [Q_CAP_0402-0.1UF,25V,10%,X7R,CA]
    1  P5V_AUX            A  @SCM_LIB.SCM(SCH_1):P5V_AUX
    2  GND                B  @SCM_LIB.SCM(SCH_1):GND

Q_CAP  I45  C204   [Q_CAP_0603-1UF,16V,10%,EMPTY,TA]
    2  GND                B  @SCM_LIB.SCM(SCH_1):GND
    1  CRT_VCC5           A  @SCM_LIB.SCM(SCH_1):CRT_VCC5

Q_CAP  I25  C205   [Q_CAP_0402-10PF,50V,1%,NPO,TMPA]
    1  V_DACR             A  @SCM_LIB.SCM(SCH_1):V_DACR
    2  GND                B  @SCM_LIB.SCM(SCH_1):GND

Q_CAP  I26  C206   [Q_CAP_0402-10PF,50V,1%,NPO,TMPA]
    1  V_DACG             A  @SCM_LIB.SCM(SCH_1):V_DACG
    2  GND                B  @SCM_LIB.SCM(SCH_1):GND

Q_CAP  I29  C207   [Q_CAP_0402-10PF,50V,1%,NPO,TMPA]
    1  V_DACB             A  @SCM_LIB.SCM(SCH_1):V_DACB
    2  GND                B  @SCM_LIB.SCM(SCH_1):GND

Q_CAP  I30  C208   [Q_CAP_C0402-33PF,50V,1%,C0G,CHA]
    1  V_DACR_IO          A  @SCM_LIB.SCM(SCH_1):V_DACR_IO
    2  GND                B  @SCM_LIB.SCM(SCH_1):GND

Q_CAP  I54  C209   [Q_CAP_C0402-33PF,50V,1%,C0G,CHA]
    1  V_DACG_IO          A  @SCM_LIB.SCM(SCH_1):V_DACG_IO
    2  GND                B  @SCM_LIB.SCM(SCH_1):GND

Q_CAP  I55  C210   [Q_CAP_C0402-33PF,50V,1%,C0G,CHA]
    1  V_DACB_IO          A  @SCM_LIB.SCM(SCH_1):V_DACB_IO
    2  GND                B  @SCM_LIB.SCM(SCH_1):GND

Q_CAP  I67  C211   [Q_CAP_0402-10PF,50V,5%,COG,CH0A]
    1  V_VGAHS_BUF        A  @SCM_LIB.SCM(SCH_1):V_VGAHS_BUF
    2  GND                B  @SCM_LIB.SCM(SCH_1):GND

Q_CAP  I77  C212   [Q_CAP_0402-10PF,50V,5%,COG,CH0A]
    1  V_VGAVS_BUF        A  @SCM_LIB.SCM(SCH_1):V_VGAVS_BUF
    2  GND                B  @SCM_LIB.SCM(SCH_1):GND

Q_CAP  I83  C213   [Q_CAP_0402-100PF,50V,5%,EMPTY,A]
    1  V_BMC_LS_DDC_SDA_R      A  @SCM_LIB.SCM(SCH_1):V_BMC_LS_DDC_SDA_R
    2  GND                B  @SCM_LIB.SCM(SCH_1):GND

Q_CAP  I84  C214   [Q_CAP_0402-100PF,50V,5%,EMPTY,A]
    1  V_BMC_LS_DDC_SCL_R      A  @SCM_LIB.SCM(SCH_1):V_BMC_LS_DDC_SCL_R
    2  GND                B  @SCM_LIB.SCM(SCH_1):GND

Q_CAP  I22  C215   [Q_CAP_C0402-10UF,10V,20%,X5R,CA]
    1  P3V3_AUX           A  @SCM_LIB.SCM(SCH_1):P3V3_AUX
    2  GND                B  @SCM_LIB.SCM(SCH_1):GND

Q_CAP  I21  C217   [Q_CAP_0402-0.1UF,25V,10%,X7R,CA]
    1  P3V3_AUX           A  @SCM_LIB.SCM(SCH_1):P3V3_AUX
    2  GND                B  @SCM_LIB.SCM(SCH_1):GND

Q_CAP  I35  C220   [Q_CAP_0402-0.1UF,25V,10%,X7R,CA]
    1  PVCCD_PLL_AUX      A  @SCM_LIB.SCM(SCH_1):PVCCD_PLL_AUX
    2  GND                B  @SCM_LIB.SCM(SCH_1):GND

Q_CAP  I199  C221   [Q_CAP_0402-0.1UF,25V,10%,X7R,CA]
    1  P1V2_AUX           A  @SCM_LIB.SCM(SCH_1):P1V2_AUX
    2  GND                B  @SCM_LIB.SCM(SCH_1):GND

Q_CAP  I198  C222   [Q_CAP_0402-0.1UF,25V,10%,X7R,CA]
    1  P1V2_AUX           A  @SCM_LIB.SCM(SCH_1):P1V2_AUX
    2  GND                B  @SCM_LIB.SCM(SCH_1):GND

Q_CAP  I46  C223   [Q_CAP_C0402-4700P,25V,10%,EMPTA]
    1  RST_BMC_SRST_BUF_R_N      A  @SCM_LIB.SCM(SCH_1):RST_BMC_SRST_BUF_R_N
    2  GND                B  @SCM_LIB.SCM(SCH_1):GND

Q_CAP  I180  C224   [Q_CAP_C0402-10UF,10V,20%,X5R,CA]
    1  PGPPA_BMC_AUX      A  @SCM_LIB.SCM(SCH_1):PGPPA_BMC_AUX
    2  GND                B  @SCM_LIB.SCM(SCH_1):GND

Q_CAP  I197  C225   [Q_CAP_0402-0.1UF,25V,10%,X7R,CA]
    1  P1V2_AUX           A  @SCM_LIB.SCM(SCH_1):P1V2_AUX
    2  GND                B  @SCM_LIB.SCM(SCH_1):GND

Q_CAP  I71  C226   [Q_CAP_0402-0.1UF,10V,10%,EMPTYA]
    1  P1V8_AUX           A  @SCM_LIB.SCM(SCH_1):P1V8_AUX
    2  GND                B  @SCM_LIB.SCM(SCH_1):GND

Q_CAP  I72  C227   [Q_CAP_0402-0.1UF,10V,10%,EMPTYA]
    1  P1V8_AUX           A  @SCM_LIB.SCM(SCH_1):P1V8_AUX
    2  GND                B  @SCM_LIB.SCM(SCH_1):GND

Q_CAP  I73  C228   [Q_CAP_0402-0.1UF,10V,10%,EMPTYA]
    1  P3V3_AUX           A  @SCM_LIB.SCM(SCH_1):P3V3_AUX
    2  GND                B  @SCM_LIB.SCM(SCH_1):GND

Q_CAP  I107  C229   [Q_CAP_0402-0.22UF,16V,10%,EMPTA]
    2  P1V2_AUX           B  @SCM_LIB.SCM(SCH_1):P1V2_AUX
    1  M_BMC_DDR4_MCLK_C      A  @SCM_LIB.SCM(SCH_1):M_BMC_DDR4_MCLK_C

Q_CAP  I16  C230   [Q_CAP_C0402-1UF,25V,10%,EMPTY,A]
    2  GND                B  @SCM_LIB.SCM(SCH_1):GND
    1  BMC_EMMC_RST_N      A  @SCM_LIB.SCM(SCH_1):BMC_EMMC_RST_N

Q_CAP  I2   C231   [Q_CAP_C0402-1UF,6.3V,10%,EMPTYA]
    1  VDDI_U2_EMMC       A  @SCM_LIB.SCM(SCH_1):VDDI_U2_EMMC
    2  GND                B  @SCM_LIB.SCM(SCH_1):GND

Q_CAP  I20  C232   [Q_CAP_C0603-22UF,6.3V,20%,EMPTA]
    1  P1V8_AUX           A  @SCM_LIB.SCM(SCH_1):P1V8_AUX
    2  GND                B  @SCM_LIB.SCM(SCH_1):GND

Q_CAP  I21  C233   [Q_CAP_0402-0.1UF,10V,10%,EMPTYA]
    1  P1V8_AUX           A  @SCM_LIB.SCM(SCH_1):P1V8_AUX
    2  GND                B  @SCM_LIB.SCM(SCH_1):GND

Q_CAP  I23  C234   [Q_CAP_C0603-22UF,10V,20%,EMPTYA]
    1  P3V3_AUX           A  @SCM_LIB.SCM(SCH_1):P3V3_AUX
    2  GND                B  @SCM_LIB.SCM(SCH_1):GND

Q_CAP  I24  C235   [Q_CAP_0402-0.1UF,10V,10%,EMPTYA]
    1  P3V3_AUX           A  @SCM_LIB.SCM(SCH_1):P3V3_AUX
    2  GND                B  @SCM_LIB.SCM(SCH_1):GND

Q_CAP  I63  C240   [Q_CAP_C0402-0.1UF,16V,10%,X7R,A]
    1  P3V3_AUX           A  @SCM_LIB.SCM(SCH_1):P3V3_AUX
    2  GND                B  @SCM_LIB.SCM(SCH_1):GND

Q_CAP  I113  C241   [Q_CAP_0402-0.1UF,10V,10%,X7R,TA]
    1  P3V3_AUX           A  @SCM_LIB.SCM(SCH_1):P3V3_AUX
    2  GND                B  @SCM_LIB.SCM(SCH_1):GND

Q_CAP  I42  C244   [Q_CAP_C0402-1UF,25V,10%,X6S,CHA]
    1  P3V3_AUX           A  @SCM_LIB.SCM(SCH_1):P3V3_AUX
    2  GND                B  @SCM_LIB.SCM(SCH_1):GND

Q_CAP  I45  C246   [Q_CAP_C0402-0.01UF,50V,10%,X7RA]
    1  P3V3_AUX           A  @SCM_LIB.SCM(SCH_1):P3V3_AUX
    2  GND                B  @SCM_LIB.SCM(SCH_1):GND

Q_CAP  I69  C248   [Q_CAP_C0402-10UF,10V,20%,X5R,CA]
    1  P3V3_AUX           A  @SCM_LIB.SCM(SCH_1):P3V3_AUX
    2  GND                B  @SCM_LIB.SCM(SCH_1):GND

Q_CAP  I67  C249   [Q_CAP_0402-0.1UF,25V,10%,X7R,CA]
    1  P3V3_AUX           A  @SCM_LIB.SCM(SCH_1):P3V3_AUX
    2  GND                B  @SCM_LIB.SCM(SCH_1):GND

Q_CAP  I66  C251   [Q_CAP_C0402-0.1UF,16V,10%,X7R,A]
    1  P3V3_RGM           A  @SCM_LIB.SCM(SCH_1):P3V3_RGM
    2  GND                B  @SCM_LIB.SCM(SCH_1):GND

Q_CAP  I73  C252   [Q_CAP_C0402-0.1UF,16V,10%,EMPTA]
    1  PWRGD_P3V3_RGM_R      A  @SCM_LIB.SCM(SCH_1):PWRGD_P3V3_RGM_R
    2  GND                B  @SCM_LIB.SCM(SCH_1):GND

Q_CAP  I57  C253   [Q_CAP_0402-0.1UF,25V,10%,X7R,CA]
    1  P3V3_AUX           A  @SCM_LIB.SCM(SCH_1):P3V3_AUX
    2  GND                B  @SCM_LIB.SCM(SCH_1):GND

Q_CAP  I278  C255   [Q_CAP_0402-0.1UF,25V,10%,X7R,CA]
    1  P3V3_AUX           A  @SCM_LIB.SCM(SCH_1):P3V3_AUX
    2  GND                B  @SCM_LIB.SCM(SCH_1):GND

Q_CAP  I29  C256   [Q_CAP_C0402-1UF,25V,10%,X6S,CHA]
    1  P3V3_AUX           A  @SCM_LIB.SCM(SCH_1):P3V3_AUX
    2  GND                B  @SCM_LIB.SCM(SCH_1):GND

Q_CAP  I21  C257   [Q_CAP_C0402-1UF,25V,10%,X6S,CHA]
    1  P3V3_AUX           A  @SCM_LIB.SCM(SCH_1):P3V3_AUX
    2  GND                B  @SCM_LIB.SCM(SCH_1):GND

Q_CAP  I40  C258   [Q_CAP_C0402-0.01UF,50V,10%,X7RA]
    1  P3V3_AUX           A  @SCM_LIB.SCM(SCH_1):P3V3_AUX
    2  GND                B  @SCM_LIB.SCM(SCH_1):GND

Q_CAP  I35  C259   [Q_CAP_C0402-0.01UF,50V,10%,X7RA]
    1  P3V3_AUX           A  @SCM_LIB.SCM(SCH_1):P3V3_AUX
    2  GND                B  @SCM_LIB.SCM(SCH_1):GND

Q_CAP  I116  C262   [Q_CAP_C0402-10UF,6.3V,20%,X6S,A]
    1  P3V3_AUX           A  @SCM_LIB.SCM(SCH_1):P3V3_AUX
    2  GND                B  @SCM_LIB.SCM(SCH_1):GND

Q_CAP  I54  C263   [Q_CAP_0402-0.1UF,25V,10%,X7R,CA]
    1  P3V3_AUX           A  @SCM_LIB.SCM(SCH_1):P3V3_AUX
    2  GND                B  @SCM_LIB.SCM(SCH_1):GND

Q_CAP  I59  C264   [Q_CAP_0402-0.1UF,25V,10%,X7R,CA]
    1  U43_CT             A  @SCM_LIB.SCM(SCH_1):U43_CT
    2  GND                B  @SCM_LIB.SCM(SCH_1):GND

Q_CAP  I157  C265   [Q_CAP_0402-0.1UF,10V,10%,X7R,TA]
    1  P1V2_PHY0_PLLVDD      A  @SCM_LIB.SCM(SCH_1):P1V2_PHY0_PLLVDD
    2  GND                B  @SCM_LIB.SCM(SCH_1):GND

Q_CAP  I52  C266   [Q_CAP_0402-0.1UF,25V,10%,X7R,CA]
    1  P3V3_AUX           A  @SCM_LIB.SCM(SCH_1):P3V3_AUX
    2  GND                B  @SCM_LIB.SCM(SCH_1):GND

Q_CAP  I166  C267   [Q_CAP_0402-1UF,16V,10%,EMPTY,TA]
    1  LPC_ESPI_SEL_R1      A  @SCM_LIB.SCM(SCH_1):LPC_ESPI_SEL_R1
    2  GND                B  @SCM_LIB.SCM(SCH_1):GND

Q_CAP  I241  C268   [Q_CAP_0402-1UF,16V,10%,EMPTY,TA]
    1  LPC_ESPI_SEL_LV5      A  @SCM_LIB.SCM(SCH_1):LPC_ESPI_SEL_LV5
    2  GND                B  @SCM_LIB.SCM(SCH_1):GND

Q_CAP  I49  C269   [Q_CAP_0402-0.1UF,25V,10%,X7R,CA]
    1  P3V3_AUX           A  @SCM_LIB.SCM(SCH_1):P3V3_AUX
    2  GND                B  @SCM_LIB.SCM(SCH_1):GND

Q_CAP  I239  C270   [Q_CAP_0402-1UF,16V,10%,EMPTY,TA]
    1  LPC_ESPI_SEL_N      A  @SCM_LIB.SCM(SCH_1):LPC_ESPI_SEL_N
    2  GND                B  @SCM_LIB.SCM(SCH_1):GND

Q_CAP  I42  C272   [Q_CAP_0402-2.2UF,10V,20%,X5R,TA]
    1  PVCCD_PLL_AUX      A  @SCM_LIB.SCM(SCH_1):PVCCD_PLL_AUX
    2  GND                B  @SCM_LIB.SCM(SCH_1):GND

Q_CAP  I234  C273   [Q_CAP_0402-1UF,16V,10%,EMPTY,TA]
    1  LPC_ESPI_SEL_R      A  @SCM_LIB.SCM(SCH_1):LPC_ESPI_SEL_R
    2  GND                B  @SCM_LIB.SCM(SCH_1):GND

Q_CAP  I48  C274   [Q_CAP_0402-0.1UF,25V,10%,X7R,CA]
    1  P3V3_AUX           A  @SCM_LIB.SCM(SCH_1):P3V3_AUX
    2  GND                B  @SCM_LIB.SCM(SCH_1):GND

Q_CAP  I180  C275   [Q_CAP_0402-100PF,50V,5%,NPO,CHA]
    1  P3V_BAT_SENSOR      A  @SCM_LIB.SCM(SCH_1):P3V_BAT_SENSOR
    2  GND                B  @SCM_LIB.SCM(SCH_1):GND

Q_CAP  I253  C277   [Q_CAP_C0402-1UF,25V,10%,X6S,CHA]
    2  GND                B  @SCM_LIB.SCM(SCH_1):GND
    1  ADCVREFEXT1        A  @SCM_LIB.SCM(SCH_1):ADCVREFEXT1

Q_CAP  I47  C278   [Q_CAP_0402-0.1UF,25V,10%,X7R,CA]
    1  P3V3_AUX           A  @SCM_LIB.SCM(SCH_1):P3V3_AUX
    2  GND                B  @SCM_LIB.SCM(SCH_1):GND

Q_CAP  I255  C279   [Q_CAP_0402-0.1UF,25V,10%,X7R,CA]
    2  GND                B  @SCM_LIB.SCM(SCH_1):GND
    1  ADCVREFEXT1        A  @SCM_LIB.SCM(SCH_1):ADCVREFEXT1

Q_CAP  I38  C281   [Q_CAP_0402-0.1UF,25V,10%,X7R,CA]
    1  PVCCD_PLL_AUX      A  @SCM_LIB.SCM(SCH_1):PVCCD_PLL_AUX
    2  GND                B  @SCM_LIB.SCM(SCH_1):GND

Q_CAP  I252  C282   [Q_CAP_C0402-1UF,25V,10%,X6S,CHA]
    2  GND                B  @SCM_LIB.SCM(SCH_1):GND
    1  ADCVREFEXT0        A  @SCM_LIB.SCM(SCH_1):ADCVREFEXT0

Q_CAP  I250  C284   [Q_CAP_0402-0.1UF,25V,10%,X7R,CA]
    2  GND                B  @SCM_LIB.SCM(SCH_1):GND
    1  ADCVREFEXT0        A  @SCM_LIB.SCM(SCH_1):ADCVREFEXT0

Q_CAP  I33  C287   [Q_CAP_0402-0.1UF,25V,10%,X7R,CA]
    1  PVCCD_PLL_AUX      A  @SCM_LIB.SCM(SCH_1):PVCCD_PLL_AUX
    2  GND                B  @SCM_LIB.SCM(SCH_1):GND

Q_CAP  I150  C288   [Q_CAP_0402-0.1UF,10V,10%,X7R,TA]
    1  P3V3_XTALVDD       A  @SCM_LIB.SCM(SCH_1):P3V3_XTALVDD
    2  GND                B  @SCM_LIB.SCM(SCH_1):GND

Q_CAP  I46  C289   [Q_CAP_0402-0.1UF,25V,10%,X7R,CA]
    1  P3V3_AUX           A  @SCM_LIB.SCM(SCH_1):P3V3_AUX
    2  GND                B  @SCM_LIB.SCM(SCH_1):GND

Q_CAP  I201  C290   [Q_CAP_0402-0.1UF,25V,10%,X7R,CA]
    1  P12V_SENSOR        A  @SCM_LIB.SCM(SCH_1):P12V_SENSOR
    2  GND                B  @SCM_LIB.SCM(SCH_1):GND

Q_CAP  I156  C293   [Q_CAP_0402-0.1UF,10V,10%,X7R,TA]
    1  P3V3_AVDD          A  @SCM_LIB.SCM(SCH_1):P3V3_AVDD
    2  GND                B  @SCM_LIB.SCM(SCH_1):GND

Q_CAP  I207  C295   [Q_CAP_0402-0.1UF,25V,10%,X7R,CA]
    1  P5V_SENSOR         A  @SCM_LIB.SCM(SCH_1):P5V_SENSOR
    2  GND                B  @SCM_LIB.SCM(SCH_1):GND

Q_CAP  I165  C297   [Q_CAP_0402-0.1UF,10V,10%,X7R,TA]
    1  P1V2_PHY0_AVDDL      A  @SCM_LIB.SCM(SCH_1):P1V2_PHY0_AVDDL
    2  GND                B  @SCM_LIB.SCM(SCH_1):GND

Q_CAP  I45  C298   [Q_CAP_0402-0.1UF,25V,10%,X7R,CA]
    1  P3V3_AUX           A  @SCM_LIB.SCM(SCH_1):P3V3_AUX
    2  GND                B  @SCM_LIB.SCM(SCH_1):GND

Q_CAP  I215  C299   [Q_CAP_0402-0.1UF,25V,10%,X7R,CA]
    1  P3V3_SENSOR        A  @SCM_LIB.SCM(SCH_1):P3V3_SENSOR
    2  GND                B  @SCM_LIB.SCM(SCH_1):GND

Q_CAP  I159  C301   [Q_CAP_0402-0.1UF,10V,10%,X7R,TA]
    1  P3V3_AVDD          A  @SCM_LIB.SCM(SCH_1):P3V3_AVDD
    2  GND                B  @SCM_LIB.SCM(SCH_1):GND

Q_CAP  I44  C302   [Q_CAP_0402-0.1UF,25V,10%,X7R,CA]
    1  P3V3_AUX           A  @SCM_LIB.SCM(SCH_1):P3V3_AUX
    2  GND                B  @SCM_LIB.SCM(SCH_1):GND

Q_CAP  I235  C303   [Q_CAP_0402-0.1UF,25V,10%,X7R,CA]
    1  P2V5_SENSOR        A  @SCM_LIB.SCM(SCH_1):P2V5_SENSOR
    2  GND                B  @SCM_LIB.SCM(SCH_1):GND

Q_CAP  I170  C305   [Q_CAP_0402-0.1UF,10V,10%,X7R,TA]
    1  P1V2_PHY0          A  @SCM_LIB.SCM(SCH_1):P1V2_PHY0
    2  GND                B  @SCM_LIB.SCM(SCH_1):GND

Q_CAP  I43  C306   [Q_CAP_0402-0.1UF,25V,10%,X7R,CA]
    1  P3V3_AUX           A  @SCM_LIB.SCM(SCH_1):P3V3_AUX
    2  GND                B  @SCM_LIB.SCM(SCH_1):GND

Q_CAP  I240  C307   [Q_CAP_0402-0.1UF,25V,10%,X7R,CA]
    1  P1V8_SENSOR        A  @SCM_LIB.SCM(SCH_1):P1V8_SENSOR
    2  GND                B  @SCM_LIB.SCM(SCH_1):GND

Q_CAP  I28  C308   [Q_CAP_0402-0.1UF,25V,10%,X7R,CA]
    1  P3V3_AUX           A  @SCM_LIB.SCM(SCH_1):P3V3_AUX
    2  GND                B  @SCM_LIB.SCM(SCH_1):GND

Q_CAP  I247  C309   [Q_CAP_0402-0.1UF,25V,10%,X7R,CA]
    1  P1V2_SENSOR        A  @SCM_LIB.SCM(SCH_1):P1V2_SENSOR
    2  GND                B  @SCM_LIB.SCM(SCH_1):GND

Q_CAP  I26  C310   [Q_CAP_0402-0.1UF,25V,10%,X7R,CA]
    1  P3V3_AUX           A  @SCM_LIB.SCM(SCH_1):P3V3_AUX
    2  GND                B  @SCM_LIB.SCM(SCH_1):GND

Q_CAP  I256  C311   [Q_CAP_0402-0.1UF,25V,10%,X7R,CA]
    1  P1V0_SENSOR        A  @SCM_LIB.SCM(SCH_1):P1V0_SENSOR
    2  GND                B  @SCM_LIB.SCM(SCH_1):GND

Q_CAP  I19  C312   [Q_CAP_0402-0.1UF,25V,10%,X7R,CA]
    1  P3V3_AUX           A  @SCM_LIB.SCM(SCH_1):P3V3_AUX
    2  GND                B  @SCM_LIB.SCM(SCH_1):GND

Q_CAP  I25  C313   [Q_CAP_0402-0.1UF,25V,10%,X7R,CA]
    1  P3V3_AUX           A  @SCM_LIB.SCM(SCH_1):P3V3_AUX
    2  GND                B  @SCM_LIB.SCM(SCH_1):GND

Q_CAP  I259  C314   [Q_CAP_0402-0.1UF,25V,10%,X7R,CA]
    1  PGPPA_BMC_AUX_SENSOR      A  @SCM_LIB.SCM(SCH_1):PGPPA_BMC_AUX_SENSOR
    2  GND                B  @SCM_LIB.SCM(SCH_1):GND

Q_CAP  I15  C315   [Q_CAP_0402-0.1UF,25V,10%,X7R,CA]
    1  P3V3_AUX           A  @SCM_LIB.SCM(SCH_1):P3V3_AUX
    2  GND                B  @SCM_LIB.SCM(SCH_1):GND

Q_CAP  I23  C317   [Q_CAP_0402-0.1UF,25V,10%,X7R,CA]
    1  P3V3_AUX           A  @SCM_LIB.SCM(SCH_1):P3V3_AUX
    2  GND                B  @SCM_LIB.SCM(SCH_1):GND

Q_CAP  I433  C318   [Q_CAP_0402-0.1UF,25V,10%,X7R,CA]
    1  P3V3_AUX           A  @SCM_LIB.SCM(SCH_1):P3V3_AUX
    2  GND                B  @SCM_LIB.SCM(SCH_1):GND

Q_CAP  I14  C319   [Q_CAP_0402-0.1UF,25V,10%,X7R,CA]
    1  P3V3_AUX           A  @SCM_LIB.SCM(SCH_1):P3V3_AUX
    2  GND                B  @SCM_LIB.SCM(SCH_1):GND

Q_CAP  I22  C320   [Q_CAP_0402-0.1UF,25V,10%,X7R,CA]
    1  P3V3_AUX           A  @SCM_LIB.SCM(SCH_1):P3V3_AUX
    2  GND                B  @SCM_LIB.SCM(SCH_1):GND

Q_CAP  I95  C321   [Q_CAP_0402-0.1UF,25V,10%,X7R,CA]
    1  PWR_LED_P3V3_AUX      A  @SCM_LIB.SCM(SCH_1):PWR_LED_P3V3_AUX
    2  GND                B  @SCM_LIB.SCM(SCH_1):GND

Q_CAP  I21  C323   [Q_CAP_0402-0.1UF,25V,10%,X7R,CA]
    1  P3V3_AUX           A  @SCM_LIB.SCM(SCH_1):P3V3_AUX
    2  GND                B  @SCM_LIB.SCM(SCH_1):GND

Q_CAP  I122  C324   [Q_CAP_0402-470PF,50V,10%,X7R,TA]
    1  ID_LED_BUF_R       A  @SCM_LIB.SCM(SCH_1):ID_LED_BUF_R
    2  GND                B  @SCM_LIB.SCM(SCH_1):GND

Q_CAP  I133  C326   [Q_CAP_0402-470PF,50V,10%,X7R,TA]
    1  PWR_LED_BUF_R      A  @SCM_LIB.SCM(SCH_1):PWR_LED_BUF_R
    2  GND                B  @SCM_LIB.SCM(SCH_1):GND

Q_CAP  I32  C327   [Q_CAP_1206-47UF ,10V,20%,X5R,CA]
    1  P5V_USB_REAR       A  @SCM_LIB.SCM(SCH_1):P5V_USB_REAR
    2  GND                B  @SCM_LIB.SCM(SCH_1):GND

Q_CAP  I166  C328   [Q_CAP_0402-0.1UF,10V,10%,X7R,TA]
    1  P1V2_PHY0_AVDDL      A  @SCM_LIB.SCM(SCH_1):P1V2_PHY0_AVDDL
    2  GND                B  @SCM_LIB.SCM(SCH_1):GND

Q_CAP  I449  C329   [Q_CAP_C0805-22UF,25V,20%,X5R,CA]
    1  P12V_AUX           A  @SCM_LIB.SCM(SCH_1):P12V_AUX
    2  GND                B  @SCM_LIB.SCM(SCH_1):GND

Q_CAP  I448  C330   [Q_CAP_C0805-22UF,25V,20%,X5R,CA]
    1  P12V_AUX           A  @SCM_LIB.SCM(SCH_1):P12V_AUX
    2  GND                B  @SCM_LIB.SCM(SCH_1):GND

Q_CAP  I160  C331   [Q_CAP_0402-0.1UF,10V,10%,X7R,TA]
    1  P3V3_AVDD          A  @SCM_LIB.SCM(SCH_1):P3V3_AVDD
    2  GND                B  @SCM_LIB.SCM(SCH_1):GND

Q_CAP  I171  C332   [Q_CAP_0402-0.1UF,10V,10%,X7R,TA]
    1  P1V2_PHY0          A  @SCM_LIB.SCM(SCH_1):P1V2_PHY0
    2  GND                B  @SCM_LIB.SCM(SCH_1):GND

Q_CAP  I115  C333   [Q_CAP_0402-0.1UF,10V,10%,X7R,TA]
    1  P3V3_AUX           A  @SCM_LIB.SCM(SCH_1):P3V3_AUX
    2  GND                B  @SCM_LIB.SCM(SCH_1):GND

Q_CAP  I154  C334   [Q_CAP_0402-0.1UF,10V,10%,X7R,TA]
    1  P3V3_BIASVDD       A  @SCM_LIB.SCM(SCH_1):P3V3_BIASVDD
    2  GND                B  @SCM_LIB.SCM(SCH_1):GND

Q_CAP  I31  C339   [Q_CAP_0402-0.1UF,25V,10%,X7R,CA]
    1  PVCCA_AUX_PLD      A  @SCM_LIB.SCM(SCH_1):PVCCA_AUX_PLD
    2  GND                B  @SCM_LIB.SCM(SCH_1):GND

Q_CAP  I20  C340   [Q_CAP_0402-0.1UF,25V,10%,X7R,CA]
    1  PVCCA_AUX_PLD      A  @SCM_LIB.SCM(SCH_1):PVCCA_AUX_PLD
    2  GND                B  @SCM_LIB.SCM(SCH_1):GND

Q_CAP  I41  C341   [Q_CAP_0402-0.1UF,25V,10%,X7R,CA]
    1  PVCCA_AUX_PLD      A  @SCM_LIB.SCM(SCH_1):PVCCA_AUX_PLD
    2  GND                B  @SCM_LIB.SCM(SCH_1):GND

Q_CAP  I39  C342   [Q_CAP_0402-0.1UF,25V,10%,X7R,CA]
    1  PVCCA_AUX_PLD      A  @SCM_LIB.SCM(SCH_1):PVCCA_AUX_PLD
    2  GND                B  @SCM_LIB.SCM(SCH_1):GND

Q_CAP  I37  C343   [Q_CAP_0402-0.1UF,25V,10%,X7R,CA]
    1  PVCCA_AUX_PLD      A  @SCM_LIB.SCM(SCH_1):PVCCA_AUX_PLD
    2  GND                B  @SCM_LIB.SCM(SCH_1):GND

Q_CAP  I36  C344   [Q_CAP_0402-0.1UF,25V,10%,X7R,CA]
    1  PVCCA_AUX_PLD      A  @SCM_LIB.SCM(SCH_1):PVCCA_AUX_PLD
    2  GND                B  @SCM_LIB.SCM(SCH_1):GND

Q_CAP  I32  C345   [Q_CAP_0402-0.1UF,25V,10%,X7R,CA]
    1  PVCCA_AUX_PLD      A  @SCM_LIB.SCM(SCH_1):PVCCA_AUX_PLD
    2  GND                B  @SCM_LIB.SCM(SCH_1):GND

Q_CAP  I211  C346   [Q_CAP_C0402-22UF,6.3V,20%,X5R,A]
    1  P1V2_PHY0_PLLVDD      A  @SCM_LIB.SCM(SCH_1):P1V2_PHY0_PLLVDD
    2  GND                B  @SCM_LIB.SCM(SCH_1):GND

Q_CAP  I168  C347   [Q_CAP_0402-4.7UF,10V,10%,X5R,CA]
    1  P1V2_PHY0_AVDDL      A  @SCM_LIB.SCM(SCH_1):P1V2_PHY0_AVDDL
    2  GND                B  @SCM_LIB.SCM(SCH_1):GND

Q_CAP  I163  C348   [Q_CAP_0402-4.7UF,10V,10%,X5R,CA]
    1  P3V3_AVDD          A  @SCM_LIB.SCM(SCH_1):P3V3_AVDD
    2  GND                B  @SCM_LIB.SCM(SCH_1):GND

Q_CAP  I212  C349   [Q_CAP_C0402-22UF,6.3V,20%,X5R,A]
    1  P1V2_PHY0          A  @SCM_LIB.SCM(SCH_1):P1V2_PHY0
    2  GND                B  @SCM_LIB.SCM(SCH_1):GND

Q_CAP  I178  C350   [Q_CAP_0402-4.7UF,10V,10%,X5R,CA]
    1  P3V3_AUX           A  @SCM_LIB.SCM(SCH_1):P3V3_AUX
    2  GND                B  @SCM_LIB.SCM(SCH_1):GND

Q_LED  I7   D0     [Q_LED_SMLF-LED_GREEN,19-213/GVA]
    A  PU_LED_POSTCODE_0_N      A  @SCM_LIB.SCM(SCH_1):PU_LED_POSTCODE_0_N
    C  LED_POSTCODE_0_N      C  @SCM_LIB.SCM(SCH_1):LED_POSTCODE_0_N

Q_LED  I9   D1     [Q_LED_SMLF-LED_GREEN,19-213/GVA]
    A  PU_LED_POSTCODE_1_N      A  @SCM_LIB.SCM(SCH_1):PU_LED_POSTCODE_1_N
    C  LED_POSTCODE_1_N      C  @SCM_LIB.SCM(SCH_1):LED_POSTCODE_1_N

Q_LED  I11  D2     [Q_LED_SMLF-LED_GREEN,19-213/GVA]
    A  PU_LED_POSTCODE_2_N      A  @SCM_LIB.SCM(SCH_1):PU_LED_POSTCODE_2_N
    C  LED_POSTCODE_2_N      C  @SCM_LIB.SCM(SCH_1):LED_POSTCODE_2_N

Q_LED  I13  D3     [Q_LED_SMLF-LED_GREEN,19-213/GVA]
    A  PU_LED_POSTCODE_3_N      A  @SCM_LIB.SCM(SCH_1):PU_LED_POSTCODE_3_N
    C  LED_POSTCODE_3_N      C  @SCM_LIB.SCM(SCH_1):LED_POSTCODE_3_N

Q_LED  I10  D4     [Q_LED_SMLF-LED_RED,19-217/R6C-A]
    A  PU_LED_POSTCODE_4_N      A  @SCM_LIB.SCM(SCH_1):PU_LED_POSTCODE_4_N
    C  LED_POSTCODE_4_N      C  @SCM_LIB.SCM(SCH_1):LED_POSTCODE_4_N

Q_LED  I12  D5     [Q_LED_SMLF-LED_RED,19-217/R6C-A]
    A  PU_LED_POSTCODE_5_N      A  @SCM_LIB.SCM(SCH_1):PU_LED_POSTCODE_5_N
    C  LED_POSTCODE_5_N      C  @SCM_LIB.SCM(SCH_1):LED_POSTCODE_5_N

Q_LED  I14  D6     [Q_LED_SMLF-LED_RED,19-217/R6C-A]
    A  PU_LED_POSTCODE_6_N      A  @SCM_LIB.SCM(SCH_1):PU_LED_POSTCODE_6_N
    C  LED_POSTCODE_6_N      C  @SCM_LIB.SCM(SCH_1):LED_POSTCODE_6_N

Q_LED  I5   D7     [Q_LED_SMLF-LED_RED,19-217/R6C-A]
    A  PU_LED_POSTCODE_7_N      A  @SCM_LIB.SCM(SCH_1):PU_LED_POSTCODE_7_N
    C  LED_POSTCODE_7_N      C  @SCM_LIB.SCM(SCH_1):LED_POSTCODE_7_N

Q_LED  I46  D8     [Q_LED_SMLF-LED_GREEN,19-213/GVA]
    A  BMC_HEARTBEAT_R_N      A  @SCM_LIB.SCM(SCH_1):BMC_HEARTBEAT_R_N
    C  BMC_HEARTBEAT_N      C  @SCM_LIB.SCM(SCH_1):BMC_HEARTBEAT_N

SCHOTTKY_AC  I42  D9     [SCHOTTKY_AC-SS0530,SMLF,EMPTY,A]
    A  P5V_AUX            A  @SCM_LIB.SCM(SCH_1):P5V_AUX
    C  CRT_VCC5           C  @SCM_LIB.SCM(SCH_1):CRT_VCC5

BZA462A  I59  D10    [BZA462A-BZA462A,SMLF,IC,BCZA46A]
    6  NC                 6  NC
    5  GND                5  @SCM_LIB.SCM(SCH_1):GND
    2  GND                2  @SCM_LIB.SCM(SCH_1):GND
    3  DP_BMC_HPD_3V3      3  @SCM_LIB.SCM(SCH_1):DP_BMC_HPD_3V3
    4  DP_BMC_AUX_C_P      4  @SCM_LIB.SCM(SCH_1):DP_BMC_AUX_C_P
    1  DP_BMC_AUX_C_N      1  @SCM_LIB.SCM(SCH_1):DP_BMC_AUX_C_N

SCHOTTKY_AC  I41  D11    [SCHOTTKY_AC-SS0530,SMLF,IC,BCSA]
    A  P5V_AUX            A  @SCM_LIB.SCM(SCH_1):P5V_AUX
    C  CRT_VCC5           C  @SCM_LIB.SCM(SCH_1):CRT_VCC5

BZA462A  I74  D12    [BZA462A-BZA462A,SMLF,IC,BCZA46A]
    5  GND                5  @SCM_LIB.SCM(SCH_1):GND
    2  GND                2  @SCM_LIB.SCM(SCH_1):GND
    6  CRT_VCC5           6  @SCM_LIB.SCM(SCH_1):CRT_VCC5
    4  CRT_VCC5           4  @SCM_LIB.SCM(SCH_1):CRT_VCC5
    3  CRT_VCC5           3  @SCM_LIB.SCM(SCH_1):CRT_VCC5
    1  CRT_VCC5           1  @SCM_LIB.SCM(SCH_1):CRT_VCC5

PCA9517ADP  I1   D13    [PCA9517ADP_SMLF-PCA9517ADP,IC,A]
    6  SMB_DEBUG_AUX_LVC3_USB_R1_SDA   SDAB  @SCM_LIB.SCM(SCH_1):SMB_DEBUG_AUX_LVC3_USB_R1_SDA
    7  SMB_DEBUG_AUX_LVC3_USB_R1_SCL   SCLB  @SCM_LIB.SCM(SCH_1):SMB_DEBUG_AUX_LVC3_USB_R1_SCL
    3  SMB_BMC_MM16_R1_SDA   SDAA  @SCM_LIB.SCM(SCH_1):SMB_BMC_MM16_R1_SDA
    2  SMB_BMC_MM16_R1_SCL   SCLA  @SCM_LIB.SCM(SCH_1):SMB_BMC_MM16_R1_SCL
    8  P3V3_AUX        VCCB  @SCM_LIB.SCM(SCH_1):P3V3_AUX
    1  P3V3_AUX        VCCA  @SCM_LIB.SCM(SCH_1):P3V3_AUX
    4  GND              GND  @SCM_LIB.SCM(SCH_1):GND
    5  DEBUG_PORT_PRSNT_BUF_EN  ENABLE  @SCM_LIB.SCM(SCH_1):DEBUG_PORT_PRSNT_BUF_EN

Q_LED  I142  D14    [Q_LED_SMLF-LED_BLUE,12-215/BHCA]
    A  PWR_LED_P3V3_AUX      A  @SCM_LIB.SCM(SCH_1):PWR_LED_P3V3_AUX
    C  PWR_LED_BUF_R      C  @SCM_LIB.SCM(SCH_1):PWR_LED_BUF_R

Q_LED  I143  D15    [Q_LED_SMLF-LED_BLUE,12-215/BHCA]
    A  ID_LED_P3V3_AUX      A  @SCM_LIB.SCM(SCH_1):ID_LED_P3V3_AUX
    C  ID_LED_BUF_R       C  @SCM_LIB.SCM(SCH_1):ID_LED_BUF_R

SCHOTTKY_AC  I152  D16    [SCHOTTKY_AC-RB161SS-20T2R,SMLFA]
    C  UNNAMED_231_QFUSE_I153_1      C  @SCM_LIB.SCM(SCH_1):UNNAMED_231_QFUSE_I153_1
    A  CRT_VCC5           A  @SCM_LIB.SCM(SCH_1):CRT_VCC5

Q_DIODE  I28  D17    [Q_DIODE_SMLF-SDMK0340L-7-F,IC,A]
    1  RST_BMC_SELF_HW_R3      1  @SCM_LIB.SCM(SCH_1):RST_BMC_SELF_HW_R3
    2  RST_BMC_SELF_HW_D      2  @SCM_LIB.SCM(SCH_1):RST_BMC_SELF_HW_D

DUMMY_SYMBOL  I3   DM2    [DUMMY_SYMBOL-BMC_FLASH,MECH,MEA]
    1  NC                 1  NC

DUMMY_SYMBOL  I9   DM4    [DUMMY_SYMBOL-WEEE,MECH,EMPTY,DA]
    1  NC                 1  NC

DUMMY_SYMBOL  I5   DM5    [DUMMY_SYMBOL-BMC_FLASH,MECH,MEA]
    1  NC                 1  NC

DUMMY_SYMBOL  I10  DM7    [DUMMY_SYMBOL-PB-E1_SMALL,MECH,A]
    1  NC                 1  NC

DUMMY_SYMBOL  I15  DM10   [DUMMY_SYMBOL-PCBA_LABEL_15X5,MA]
    1  NC                 1  NC

DUMMY_SYMBOL  I26  DM19   [DUMMY_SYMBOL-QUANTA_LOGO_7X26,A]
    1  NC                 1  NC

Q_FUSE  I153  FS1    [Q_FUSE_SMLF-1.1A/8V,IC,DK110TPA]
    2  UNNAMED_231_QFUSE_I153_2      2  @SCM_LIB.SCM(SCH_1):UNNAMED_231_QFUSE_I153_2
    1  UNNAMED_231_QFUSE_I153_1      1  @SCM_LIB.SCM(SCH_1):UNNAMED_231_QFUSE_I153_1

FCONN168_ME1016810106011  I171  GF1    [FCONN168_ME1016810106011-FCONNA]
  B50  USB_HOST_BMC_B_DP    B50  @SCM_LIB.SCM(SCH_1):USB_HOST_BMC_B_DP
  B51  USB_HOST_BMC_B_DN    B51  @SCM_LIB.SCM(SCH_1):USB_HOST_BMC_B_DN
  B53  USB_HOST_BMC_A_DP    B53  @SCM_LIB.SCM(SCH_1):USB_HOST_BMC_A_DP
  B54  USB_HOST_BMC_A_DN    B54  @SCM_LIB.SCM(SCH_1):USB_HOST_BMC_A_DN
  B56  USB_FPNL_DP      B56  @SCM_LIB.SCM(SCH_1):USB_FPNL_DP
  B57  USB_FPNL_DN      B57  @SCM_LIB.SCM(SCH_1):USB_FPNL_DN
  OB5  UART_2_BMC_TXD    OB5  @SCM_LIB.SCM(SCH_1):UART_2_BMC_TXD
  OB6  UART_2_BMC_RXD    OB6  @SCM_LIB.SCM(SCH_1):UART_2_BMC_RXD
  OB13  NC              OB13  NC
  OB14  NC              OB14  NC
  OB11  NC              OB11  NC
  A52  NC               A52  NC
  B68  NC               B68  NC
  B65  NC               B65  NC
  B62  NC               B62  NC
  B59  NC               B59  NC
  B69  NC               B69  NC
  B66  NC               B66  NC
  B63  NC               B63  NC
  B60  NC               B60  NC
  A68  NC               A68  NC
  A65  NC               A65  NC
  A62  NC               A62  NC
  A59  NC               A59  NC
  A69  NC               A69  NC
  A66  NC               A66  NC
  A63  NC               A63  NC
  A60  NC               A60  NC
  OB8  NC               OB8  NC
  OB9  NC               OB9  NC
  A47  SYS_PWRBTN_N     A47  @SCM_LIB.SCM(SCH_1):SYS_PWRBTN_N
  OB12  SPI_TPM_CS_N    OB12  @SCM_LIB.SCM(SCH_1):SPI_TPM_CS_N
  B15  SPI_SYS_WP_R_IO2    B15  @SCM_LIB.SCM(SCH_1):SPI_SYS_WP_R_IO2
  B13  SPI_SYS_R_MOSI    B13  @SCM_LIB.SCM(SCH_1):SPI_SYS_R_MOSI
  B14  SPI_SYS_R_MISO    B14  @SCM_LIB.SCM(SCH_1):SPI_SYS_R_MISO
  B11  SPI_SYS_R_CLK    B11  @SCM_LIB.SCM(SCH_1):SPI_SYS_R_CLK
  B16  SPI_SYS_HOLD_R_IO3    B16  @SCM_LIB.SCM(SCH_1):SPI_SYS_HOLD_R_IO3
  B12  SPI_SYS_CS0_N    B12  @SCM_LIB.SCM(SCH_1):SPI_SYS_CS0_N
  A30  SMB_BMC_MM9_SDA    A30  @SCM_LIB.SCM(SCH_1):SMB_BMC_MM9_SDA
  A29  SMB_BMC_MM9_SCL    A29  @SCM_LIB.SCM(SCH_1):SMB_BMC_MM9_SCL
  A28  SMB_BMC_MM8_SDA    A28  @SCM_LIB.SCM(SCH_1):SMB_BMC_MM8_SDA
  A27  SMB_BMC_MM8_SCL    A27  @SCM_LIB.SCM(SCH_1):SMB_BMC_MM8_SCL
  A26  SMB_BMC_MM7_SDA    A26  @SCM_LIB.SCM(SCH_1):SMB_BMC_MM7_SDA
  A25  SMB_BMC_MM7_SCL    A25  @SCM_LIB.SCM(SCH_1):SMB_BMC_MM7_SCL
  A24  SMB_BMC_MM6_SDA    A24  @SCM_LIB.SCM(SCH_1):SMB_BMC_MM6_SDA
  A23  SMB_BMC_MM6_SCL    A23  @SCM_LIB.SCM(SCH_1):SMB_BMC_MM6_SCL
  A22  SMB_BMC_MM5_SDA    A22  @SCM_LIB.SCM(SCH_1):SMB_BMC_MM5_SDA
  A21  SMB_BMC_MM5_SCL    A21  @SCM_LIB.SCM(SCH_1):SMB_BMC_MM5_SCL
  A10  SMB_BMC_MM4_SDA    A10  @SCM_LIB.SCM(SCH_1):SMB_BMC_MM4_SDA
   A9  SMB_BMC_MM4_SCL     A9  @SCM_LIB.SCM(SCH_1):SMB_BMC_MM4_SCL
   A8  SMB_BMC_MM3_SDA     A8  @SCM_LIB.SCM(SCH_1):SMB_BMC_MM3_SDA
   A7  SMB_BMC_MM3_SCL     A7  @SCM_LIB.SCM(SCH_1):SMB_BMC_MM3_SCL
   A6  SMB_BMC_MM2_SDA     A6  @SCM_LIB.SCM(SCH_1):SMB_BMC_MM2_SDA
   A5  SMB_BMC_MM2_SCL     A5  @SCM_LIB.SCM(SCH_1):SMB_BMC_MM2_SCL
   A4  SMB_BMC_MM1_SDA     A4  @SCM_LIB.SCM(SCH_1):SMB_BMC_MM1_SDA
   A3  SMB_BMC_MM1_SCL     A3  @SCM_LIB.SCM(SCH_1):SMB_BMC_MM1_SCL
   A2  SMB_BMC_MM14_R1_SDA     A2  @SCM_LIB.SCM(SCH_1):SMB_BMC_MM14_R1_SDA
   A1  SMB_BMC_MM14_R1_SCL     A1  @SCM_LIB.SCM(SCH_1):SMB_BMC_MM14_R1_SCL
  A41  SMB_BMC_MM13_SDA    A41  @SCM_LIB.SCM(SCH_1):SMB_BMC_MM13_SDA
  A40  SMB_BMC_MM13_SCL    A40  @SCM_LIB.SCM(SCH_1):SMB_BMC_MM13_SCL
  A39  SMB_BMC_MM12_SDA    A39  @SCM_LIB.SCM(SCH_1):SMB_BMC_MM12_SDA
  A38  SMB_BMC_MM12_SCL    A38  @SCM_LIB.SCM(SCH_1):SMB_BMC_MM12_SCL
  A32  SMB_BMC_MM10_SDA    A32  @SCM_LIB.SCM(SCH_1):SMB_BMC_MM10_SDA
  A31  SMB_BMC_MM10_SCL    A31  @SCM_LIB.SCM(SCH_1):SMB_BMC_MM10_SCL
  B37  SGPIO_LD_1       B37  @SCM_LIB.SCM(SCH_1):SGPIO_LD_1
  B32  SGPIO_LD_0       B32  @SCM_LIB.SCM(SCH_1):SGPIO_LD_0
  B34  SGPIO_DO_1       B34  @SCM_LIB.SCM(SCH_1):SGPIO_DO_1
  B29  SGPIO_DO_0       B29  @SCM_LIB.SCM(SCH_1):SGPIO_DO_0
  B36  SGPIO_DI_1       B36  @SCM_LIB.SCM(SCH_1):SGPIO_DI_1
  B31  SGPIO_DI_0       B31  @SCM_LIB.SCM(SCH_1):SGPIO_DI_0
  B35  SGPIO_CLK_1      B35  @SCM_LIB.SCM(SCH_1):SGPIO_CLK_1
  B30  SGPIO_CLK_0      B30  @SCM_LIB.SCM(SCH_1):SGPIO_CLK_0
  B39  RST_SGPIO_RESET_N    B39  @SCM_LIB.SCM(SCH_1):RST_SGPIO_RESET_N
  A53  RST_ROT_CPU_N    A53  @SCM_LIB.SCM(SCH_1):RST_ROT_CPU_N
  A51  RST_PLTRST_N     A51  @SCM_LIB.SCM(SCH_1):RST_PLTRST_N
  A46  RST_MB_STBY_N    A46  @SCM_LIB.SCM(SCH_1):RST_MB_STBY_N
   B4  RST_BMC_LPC_ESPI_N     B4  @SCM_LIB.SCM(SCH_1):RST_BMC_LPC_ESPI_N
  B20  RMII_TXEN        B20  @SCM_LIB.SCM(SCH_1):RMII_TXEN
  B22  RMII_TXD1        B22  @SCM_LIB.SCM(SCH_1):RMII_TXD1
  B21  RMII_TXD0        B21  @SCM_LIB.SCM(SCH_1):RMII_TXD0
  B23  RMII_RXER        B23  @SCM_LIB.SCM(SCH_1):RMII_RXER
  B25  RMII_RXD1        B25  @SCM_LIB.SCM(SCH_1):RMII_RXD1
  B24  RMII_RXD0        B24  @SCM_LIB.SCM(SCH_1):RMII_RXD0
  B18  RMII_OCP_RCLKI    B18  @SCM_LIB.SCM(SCH_1):RMII_OCP_RCLKI
  B19  RMII_CSRDV       B19  @SCM_LIB.SCM(SCH_1):RMII_CSRDV
  B49  QSPI_2_PLD_IO3    B49  @SCM_LIB.SCM(SCH_1):QSPI_2_PLD_IO3
  B48  QSPI_2_PLD_IO2    B48  @SCM_LIB.SCM(SCH_1):QSPI_2_PLD_IO2
  B47  QSPI_2_PLD_IO1    B47  @SCM_LIB.SCM(SCH_1):QSPI_2_PLD_IO1
  B46  QSPI_2_PLD_IO0    B46  @SCM_LIB.SCM(SCH_1):QSPI_2_PLD_IO0
  B42  QSPI_2_PLD_CS1_N    B42  @SCM_LIB.SCM(SCH_1):QSPI_2_PLD_CS1_N
  B45  QSPI_2_PLD_CS0_N    B45  @SCM_LIB.SCM(SCH_1):QSPI_2_PLD_CS0_N
  B44  QSPI_2_PLD_CLK    B44  @SCM_LIB.SCM(SCH_1):QSPI_2_PLD_CLK
  A48  PWRGD_SYS_PWROK    A48  @SCM_LIB.SCM(SCH_1):PWRGD_SYS_PWROK
  A44  PWRGD_PSU_AC_PWROK_R    A44  @SCM_LIB.SCM(SCH_1):PWRGD_PSU_AC_PWROK_R
  B28  PVCCIO_PECI_BMC    B28  @SCM_LIB.SCM(SCH_1):PVCCIO_PECI_BMC
  B27  PECI_BMC         B27  @SCM_LIB.SCM(SCH_1):PECI_BMC
  A15  PCIE_BMC_TX_DP    A15  @SCM_LIB.SCM(SCH_1):PCIE_BMC_TX_DP
  A16  PCIE_BMC_TX_DN    A16  @SCM_LIB.SCM(SCH_1):PCIE_BMC_TX_DN
  A18  PCIE_BMC_RX_C_DP    A18  @SCM_LIB.SCM(SCH_1):PCIE_BMC_RX_C_DP
  A19  PCIE_BMC_RX_C_DN    A19  @SCM_LIB.SCM(SCH_1):PCIE_BMC_RX_C_DN
  B41  P3V_BAT_R        B41  @SCM_LIB.SCM(SCH_1):P3V_BAT_R
  OB2  P12V_AUX         OB2  @SCM_LIB.SCM(SCH_1):P12V_AUX
  OB1  P12V_AUX         OB1  @SCM_LIB.SCM(SCH_1):P12V_AUX
  OA2  P12V_AUX         OA2  @SCM_LIB.SCM(SCH_1):P12V_AUX
  OA1  P12V_AUX         OA1  @SCM_LIB.SCM(SCH_1):P12V_AUX
   B9  LPC_ESPI_SEL      B9  @SCM_LIB.SCM(SCH_1):LPC_ESPI_SEL
  A35  JTAG_MB_TMS      A35  @SCM_LIB.SCM(SCH_1):JTAG_MB_TMS
  A37  JTAG_MB_TDO      A37  @SCM_LIB.SCM(SCH_1):JTAG_MB_TDO
  A36  JTAG_MB_TDI      A36  @SCM_LIB.SCM(SCH_1):JTAG_MB_TDI
  A34  JTAG_MB_TCK      A34  @SCM_LIB.SCM(SCH_1):JTAG_MB_TCK
  A56  IRQ_SMI_ACTIVE_GF_N    A56  @SCM_LIB.SCM(SCH_1):IRQ_SMI_ACTIVE_GF_N
  B40  IRQ_SGPIO_N      B40  @SCM_LIB.SCM(SCH_1):IRQ_SGPIO_N
   B3  IRQ_BMC_LPC_SERIRQ_ESPI_GF     B3  @SCM_LIB.SCM(SCH_1):IRQ_BMC_LPC_SERIRQ_ESPI_GF
  OA12  I3C4_SPD_SDA    OA12  @SCM_LIB.SCM(SCH_1):I3C4_SPD_SDA
  OA11  I3C4_SPD_SCL    OA11  @SCM_LIB.SCM(SCH_1):I3C4_SPD_SCL
  OA10  I3C3_SPD_SDA    OA10  @SCM_LIB.SCM(SCH_1):I3C3_SPD_SDA
  OA9  I3C3_SPD_SCL     OA9  @SCM_LIB.SCM(SCH_1):I3C3_SPD_SCL
  OA8  I3C2_SPD_SDA     OA8  @SCM_LIB.SCM(SCH_1):I3C2_SPD_SDA
  OA7  I3C2_SPD_SCL     OA7  @SCM_LIB.SCM(SCH_1):I3C2_SPD_SCL
  OA6  I3C1_SPD_SDA     OA6  @SCM_LIB.SCM(SCH_1):I3C1_SPD_SDA
  OA5  I3C1_SPD_SCL     OA5  @SCM_LIB.SCM(SCH_1):I3C1_SPD_SCL
  OB10  GND             OB10  @SCM_LIB.SCM(SCH_1):GND
  OB7  GND              OB7  @SCM_LIB.SCM(SCH_1):GND
  OB4  GND              OB4  @SCM_LIB.SCM(SCH_1):GND
  OA13  GND             OA13  @SCM_LIB.SCM(SCH_1):GND
  OA4  GND              OA4  @SCM_LIB.SCM(SCH_1):GND
  OA3  GND              OA3  @SCM_LIB.SCM(SCH_1):GND
  B70  GND              B70  @SCM_LIB.SCM(SCH_1):GND
  B67  GND              B67  @SCM_LIB.SCM(SCH_1):GND
  B64  GND              B64  @SCM_LIB.SCM(SCH_1):GND
  B61  GND              B61  @SCM_LIB.SCM(SCH_1):GND
  B58  GND              B58  @SCM_LIB.SCM(SCH_1):GND
  B55  GND              B55  @SCM_LIB.SCM(SCH_1):GND
  B52  GND              B52  @SCM_LIB.SCM(SCH_1):GND
  B43  GND              B43  @SCM_LIB.SCM(SCH_1):GND
  B38  GND              B38  @SCM_LIB.SCM(SCH_1):GND
  B33  GND              B33  @SCM_LIB.SCM(SCH_1):GND
  B26  GND              B26  @SCM_LIB.SCM(SCH_1):GND
  B17  GND              B17  @SCM_LIB.SCM(SCH_1):GND
  B10  GND              B10  @SCM_LIB.SCM(SCH_1):GND
  A70  GND              A70  @SCM_LIB.SCM(SCH_1):GND
  A67  GND              A67  @SCM_LIB.SCM(SCH_1):GND
  A64  GND              A64  @SCM_LIB.SCM(SCH_1):GND
  A61  GND              A61  @SCM_LIB.SCM(SCH_1):GND
  A58  GND              A58  @SCM_LIB.SCM(SCH_1):GND
  A43  GND              A43  @SCM_LIB.SCM(SCH_1):GND
  A42  GND              A42  @SCM_LIB.SCM(SCH_1):GND
  A33  GND              A33  @SCM_LIB.SCM(SCH_1):GND
  A20  GND              A20  @SCM_LIB.SCM(SCH_1):GND
  A17  GND              A17  @SCM_LIB.SCM(SCH_1):GND
  A14  GND              A14  @SCM_LIB.SCM(SCH_1):GND
  A11  GND              A11  @SCM_LIB.SCM(SCH_1):GND
  OA14  FM_VIRTUAL_RESEAT   OA14  @SCM_LIB.SCM(SCH_1):FM_VIRTUAL_RESEAT
  A57  FM_PRSNT_1_N     A57  @SCM_LIB.SCM(SCH_1):FM_PRSNT_1_N
  OB3  FM_PRSNT_0_R_N    OB3  @SCM_LIB.SCM(SCH_1):FM_PRSNT_0_R_N
  A45  FM_MB_STBY_EN    A45  @SCM_LIB.SCM(SCH_1):FM_MB_STBY_EN
  A54  FM_INTRUDER_HDR_PCH_N    A54  @SCM_LIB.SCM(SCH_1):FM_INTRUDER_HDR_PCH_N
  A49  FM_DBP_CPU_PREQ_GF_R_N    A49  @SCM_LIB.SCM(SCH_1):FM_DBP_CPU_PREQ_GF_R_N
  A50  FM_DBP_BMC_PRDY_N    A50  @SCM_LIB.SCM(SCH_1):FM_DBP_BMC_PRDY_N
  A55  FM_BMC_CPU_FBRK_OUT_R_N    A55  @SCM_LIB.SCM(SCH_1):FM_BMC_CPU_FBRK_OUT_R_N
   B8  ESPI_LPC_LAD3_IO3     B8  @SCM_LIB.SCM(SCH_1):ESPI_LPC_LAD3_IO3
   B7  ESPI_LPC_LAD2_IO2     B7  @SCM_LIB.SCM(SCH_1):ESPI_LPC_LAD2_IO2
   B6  ESPI_LPC_LAD1_IO1     B6  @SCM_LIB.SCM(SCH_1):ESPI_LPC_LAD1_IO1
   B5  ESPI_LPC_LAD0_IO0     B5  @SCM_LIB.SCM(SCH_1):ESPI_LPC_LAD0_IO0
   B2  ESPI_HOST_LPC_BMC_LFRAME_N     B2  @SCM_LIB.SCM(SCH_1):ESPI_HOST_LPC_BMC_LFRAME_N
   B1  ESPI_HOST_LPC_BMC_CLK     B1  @SCM_LIB.SCM(SCH_1):ESPI_HOST_LPC_BMC_CLK
  A12  CLK_BMC_GF_DP    A12  @SCM_LIB.SCM(SCH_1):CLK_BMC_GF_DP
  A13  CLK_BMC_GF_DN    A13  @SCM_LIB.SCM(SCH_1):CLK_BMC_GF_DN

HOLE  I79  H1     [HOLE_TH-EMPTY,HOLE620]
    1  GND                1  @SCM_LIB.SCM(SCH_1):GND

HOLE  I110  H2     [HOLE_TH-EMPTY,HOLE620]
    1  GND                1  @SCM_LIB.SCM(SCH_1):GND

HOLE  I14  H2B1   [HOLE_TH-EMPTY,DUMMY50]
    1  NC                 1  NC

HOLE  I34  H2B2   [HOLE_TH-EMPTY,DUMMY50]
    1  NC                 1  NC

HOLE  I35  H5     [HOLE_TH-EMPTY,HOLE1211]
    1  GND                1  @SCM_LIB.SCM(SCH_1):GND

HOLE  I32  H6     [HOLE_TH-EMPTY,HOLE1101]
    1  GND                1  @SCM_LIB.SCM(SCH_1):GND

HOLE  I30  H7     [HOLE_TH-EMPTY,HOLE1101]
    1  GND                1  @SCM_LIB.SCM(SCH_1):GND

HOLE  I36  H9     [HOLE_TH-EMPTY,HOLE1211]
    1  GND                1  @SCM_LIB.SCM(SCH_1):GND

SCONN14_RS6QU0001  I95  J1     [SCONN14_RS6QU0001-SCONN14_RS6-A]
   L4  PU_LED_ACT        L4  @SCM_LIB.SCM(SCH_1):PU_LED_ACT
   R9  PHY_TRD_3_P     TD4+  @SCM_LIB.SCM(SCH_1):PHY_TRD_3_P
  R10  PHY_TRD_3_N     TD4-  @SCM_LIB.SCM(SCH_1):PHY_TRD_3_N
   R7  PHY_TRD_2_P     TD3+  @SCM_LIB.SCM(SCH_1):PHY_TRD_2_P
   R8  PHY_TRD_2_N     TD3-  @SCM_LIB.SCM(SCH_1):PHY_TRD_2_N
   R3  PHY_TRD_1_P     TD2+  @SCM_LIB.SCM(SCH_1):PHY_TRD_1_P
   R4  PHY_TRD_1_N     TD2-  @SCM_LIB.SCM(SCH_1):PHY_TRD_1_N
   R1  PHY_TRD_0_P     TD1+  @SCM_LIB.SCM(SCH_1):PHY_TRD_0_P
   R2  PHY_TRD_0_N     TD1-  @SCM_LIB.SCM(SCH_1):PHY_TRD_0_N
   R6  PHY_CT           CT2  @SCM_LIB.SCM(SCH_1):PHY_CT
   R5  PHY_CT           CT1  @SCM_LIB.SCM(SCH_1):PHY_CT
   L3  LED3_AD0_ACT      L3  @SCM_LIB.SCM(SCH_1):LED3_AD0_ACT
   L1  LED2_RXDELAY_1G     L1  @SCM_LIB.SCM(SCH_1):LED2_RXDELAY_1G
   L2  LED1_AD1_100M     L2  @SCM_LIB.SCM(SCH_1):LED1_AD1_100M
   G2  GND               G2  @SCM_LIB.SCM(SCH_1):GND
   G1  GND               G1  @SCM_LIB.SCM(SCH_1):GND

CONN9_GSB311131HR  I22  J2     [CONN9_GSB311131HR-CONN9_GSB311A]
    3  USB2_01_F_DP      D+  @SCM_LIB.SCM(SCH_1):USB2_01_F_DP
    2  USB2_01_F_DN      D-  @SCM_LIB.SCM(SCH_1):USB2_01_F_DN
    6  SMB_DEBUG_AUX_LVC3_USB_SDA  SSRX+  @SCM_LIB.SCM(SCH_1):SMB_DEBUG_AUX_LVC3_USB_SDA
    5  SMB_DEBUG_AUX_LVC3_USB_SCL  SSRX-  @SCM_LIB.SCM(SCH_1):SMB_DEBUG_AUX_LVC3_USB_SCL
    1  P5V_USB_REAR    VBUS  @SCM_LIB.SCM(SCH_1):P5V_USB_REAR
    4  GND              GND  @SCM_LIB.SCM(SCH_1):GND
   G2  GND               G2  @SCM_LIB.SCM(SCH_1):GND
   G1  GND               G1  @SCM_LIB.SCM(SCH_1):GND
    8  DEBUG_PORT_UART_TX  SSTX-  @SCM_LIB.SCM(SCH_1):DEBUG_PORT_UART_TX
    9  DEBUG_PORT_UART_RX  SSTX+  @SCM_LIB.SCM(SCH_1):DEBUG_PORT_UART_RX
    7  DEBUG_PORT_PRSNT  GND_D  @SCM_LIB.SCM(SCH_1):DEBUG_PORT_PRSNT

SCONN20_3VM11207D7307H  I127  J3     [SCONN20_3VM11207D7307H-SCONN20A]
   10  NC             ML_LANE_3_P  NC
   12  NC             ML_LANE_3_N  NC
   15  NC             ML_LANE_2_P  NC
   17  NC             ML_LANE_2_N  NC
   20  P3V3_DP_L      DP_PWR  @SCM_LIB.SCM(SCH_1):P3V3_DP_L
   19  GND            GND_19  @SCM_LIB.SCM(SCH_1):GND
   14  GND            GND_14  @SCM_LIB.SCM(SCH_1):GND
   13  GND            GND_13  @SCM_LIB.SCM(SCH_1):GND
    8  GND            GND_8  @SCM_LIB.SCM(SCH_1):GND
    7  GND            GND_7  @SCM_LIB.SCM(SCH_1):GND
    1  GND            GND_1  @SCM_LIB.SCM(SCH_1):GND
   G4  GND               G4  @SCM_LIB.SCM(SCH_1):GND
   G3  GND               G3  @SCM_LIB.SCM(SCH_1):GND
   G2  GND               G2  @SCM_LIB.SCM(SCH_1):GND
   G1  GND               G1  @SCM_LIB.SCM(SCH_1):GND
    6  DP_CONFIG2     CONFIG2  @SCM_LIB.SCM(SCH_1):DP_CONFIG2
    4  DP_CONFIG1     CONFIG1  @SCM_LIB.SCM(SCH_1):DP_CONFIG1
    9  DP_BMC_TX1_P   ML_LANE_1_P  @SCM_LIB.SCM(SCH_1):DP_BMC_TX1_P
   11  DP_BMC_TX1_N   ML_LANE_1_N  @SCM_LIB.SCM(SCH_1):DP_BMC_TX1_N
    3  DP_BMC_TX0_P   ML_LANE_0_P  @SCM_LIB.SCM(SCH_1):DP_BMC_TX0_P
    5  DP_BMC_TX0_N   ML_LANE_0_N  @SCM_LIB.SCM(SCH_1):DP_BMC_TX0_N
    2  DP_BMC_HPD_3V3  HOTPLUG_DETECT  @SCM_LIB.SCM(SCH_1):DP_BMC_HPD_3V3
   16  DP_BMC_AUX_C_P  AUX_CH_P  @SCM_LIB.SCM(SCH_1):DP_BMC_AUX_C_P
   18  DP_BMC_AUX_C_N  AUX_CH_N  @SCM_LIB.SCM(SCH_1):DP_BMC_AUX_C_N

SCONN5_2UB2141000111F  I83  J4     [SCONN5_2UB2141000111F-SCONN5_2A]
    3  USB2_EXT_R_DP     D+  @SCM_LIB.SCM(SCH_1):USB2_EXT_R_DP
    2  USB2_EXT_R_DN     D-  @SCM_LIB.SCM(SCH_1):USB2_EXT_R_DN
    1  P5V_AUX_VBUS    VBUS  @SCM_LIB.SCM(SCH_1):P5V_AUX_VBUS
    4  GND               ID  @SCM_LIB.SCM(SCH_1):GND
    5  GND              GND  @SCM_LIB.SCM(SCH_1):GND
   G4  GND               G4  @SCM_LIB.SCM(SCH_1):GND
   G3  GND               G3  @SCM_LIB.SCM(SCH_1):GND
   G2  GND               G2  @SCM_LIB.SCM(SCH_1):GND
   G1  GND               G1  @SCM_LIB.SCM(SCH_1):GND

SCONN11_9192031111LF  I56  J5     [SCONN11_9192031111LF-SCONN11_9A]
    5  SPI_TPM_CS_N_R      5  @SCM_LIB.SCM(SCH_1):SPI_TPM_CS_N_R
    3  SPI_SYS_R1_MOSI      3  @SCM_LIB.SCM(SCH_1):SPI_SYS_R1_MOSI
    4  SPI_SYS_R1_MISO      4  @SCM_LIB.SCM(SCH_1):SPI_SYS_R1_MISO
    1  SPI_SYS_R1_CLK      1  @SCM_LIB.SCM(SCH_1):SPI_SYS_R1_CLK
    6  SMB_TPM_MM15_SDA      6  @SCM_LIB.SCM(SCH_1):SMB_TPM_MM15_SDA
   10  SMB_TPM_MM15_SCL     10  @SCM_LIB.SCM(SCH_1):SMB_TPM_MM15_SCL
    2  RST_PLTRST_TPM_N      2  @SCM_LIB.SCM(SCH_1):RST_PLTRST_TPM_N
    7  P3V3_AUX           7  @SCM_LIB.SCM(SCH_1):P3V3_AUX
    9  IRQ_TPM_SPI_R_N      9  @SCM_LIB.SCM(SCH_1):IRQ_TPM_SPI_R_N
   G2  GND               G2  @SCM_LIB.SCM(SCH_1):GND
   G1  GND               G1  @SCM_LIB.SCM(SCH_1):GND
   11  GND               11  @SCM_LIB.SCM(SCH_1):GND
    8  FM_TPM_PRSNT_0_N      8  @SCM_LIB.SCM(SCH_1):FM_TPM_PRSNT_0_N

CONN3_210P9103GBR1  I109  J6     [CONN3_210P9103GBR1-CONN3_210-PA]
    1  UART_BMC_5_TXD_BUF_R      1  @SCM_LIB.SCM(SCH_1):UART_BMC_5_TXD_BUF_R
    3  UART_BMC_5_RXD_BUF      3  @SCM_LIB.SCM(SCH_1):UART_BMC_5_RXD_BUF
    2  GND                2  @SCM_LIB.SCM(SCH_1):GND

CONN7_4400547  I53  J7     [CONN7_4400547-CONN7_440054-7,TA]
    1  P3V3_AUX           1  @SCM_LIB.SCM(SCH_1):P3V3_AUX
    6  JTAG_SCM_PLD_R1_JTAGEN      6  @SCM_LIB.SCM(SCH_1):JTAG_SCM_PLD_R1_JTAGEN
    4  JTAG_SCM_CONN_TMS      4  @SCM_LIB.SCM(SCH_1):JTAG_SCM_CONN_TMS
    3  JTAG_SCM_CONN_TDO      3  @SCM_LIB.SCM(SCH_1):JTAG_SCM_CONN_TDO
    5  JTAG_SCM_CONN_TDI      5  @SCM_LIB.SCM(SCH_1):JTAG_SCM_CONN_TDI
    2  JTAG_SCM_CONN_TCK      2  @SCM_LIB.SCM(SCH_1):JTAG_SCM_CONN_TCK
    7  GND                7  @SCM_LIB.SCM(SCH_1):GND

SCONN13_502240130C001  I151  J8     [SCONN13_502240130C001-SCONN13_A]
    7  V_VGAVS_BUF        7  @SCM_LIB.SCM(SCH_1):V_VGAVS_BUF
    9  V_VGAHS_BUF        9  @SCM_LIB.SCM(SCH_1):V_VGAHS_BUF
    1  V_DACR_IO          1  @SCM_LIB.SCM(SCH_1):V_DACR_IO
    3  V_DACG_IO          3  @SCM_LIB.SCM(SCH_1):V_DACG_IO
    5  V_DACB_IO          5  @SCM_LIB.SCM(SCH_1):V_DACB_IO
   11  V_BMC_LS_DDC_SDA_R     11  @SCM_LIB.SCM(SCH_1):V_BMC_LS_DDC_SDA_R
   12  V_BMC_LS_DDC_SCL_R     12  @SCM_LIB.SCM(SCH_1):V_BMC_LS_DDC_SCL_R
   13  UNNAMED_231_QFUSE_I153_2     13  @SCM_LIB.SCM(SCH_1):UNNAMED_231_QFUSE_I153_2
   G2  GND               G2  @SCM_LIB.SCM(SCH_1):GND
   G1  GND               G1  @SCM_LIB.SCM(SCH_1):GND
   10  GND               10  @SCM_LIB.SCM(SCH_1):GND
    8  GND                8  @SCM_LIB.SCM(SCH_1):GND
    6  GND                6  @SCM_LIB.SCM(SCH_1):GND
    4  GND                4  @SCM_LIB.SCM(SCH_1):GND
    2  GND                2  @SCM_LIB.SCM(SCH_1):GND

DELTA_L  I1   J9     [DELTA_L-DELTA-L,THLF,EMPTY,TP24]
    3  GND_P1             3  @SCM_LIB.SCM(SCH_1):GND_P1
    2  85_5INCH_TOP_DP      2  @SCM_LIB.SCM(SCH_1):85_5INCH_TOP_DP
    1  85_5INCH_TOP_DN      1  @SCM_LIB.SCM(SCH_1):85_5INCH_TOP_DN

SCONN11_9192031111LF  I113  J10    [SCONN11_9192031111LF-SCONN11_9A]
    3  SPI_BMC_TPM_MOSI_R      3  @SCM_LIB.SCM(SCH_1):SPI_BMC_TPM_MOSI_R
    4  SPI_BMC_TPM_MISO_R      4  @SCM_LIB.SCM(SCH_1):SPI_BMC_TPM_MISO_R
    5  SPI_BMC_TPM_CS2_N_R      5  @SCM_LIB.SCM(SCH_1):SPI_BMC_TPM_CS2_N_R
    1  SPI_BMC_TPM_CLK_R      1  @SCM_LIB.SCM(SCH_1):SPI_BMC_TPM_CLK_R
    6  SMB_BMC_TPM_MM15_SDA      6  @SCM_LIB.SCM(SCH_1):SMB_BMC_TPM_MM15_SDA
   10  SMB_BMC_TPM_MM15_SCL     10  @SCM_LIB.SCM(SCH_1):SMB_BMC_TPM_MM15_SCL
    2  RST_BMC_EXTRST_R3_N      2  @SCM_LIB.SCM(SCH_1):RST_BMC_EXTRST_R3_N
    7  P3V3_AUX           7  @SCM_LIB.SCM(SCH_1):P3V3_AUX
    9  IRQ_BMC_TPM_SPI_R_N      9  @SCM_LIB.SCM(SCH_1):IRQ_BMC_TPM_SPI_R_N
   G2  GND               G2  @SCM_LIB.SCM(SCH_1):GND
   G1  GND               G1  @SCM_LIB.SCM(SCH_1):GND
   11  GND               11  @SCM_LIB.SCM(SCH_1):GND
    8  FM_TPM_PRSNT_1_N      8  @SCM_LIB.SCM(SCH_1):FM_TPM_PRSNT_1_N

DELTA_L  I11  J11    [DELTA_L-DELTA-L,THLF,EMPTY,TP24]
    3  GND_P2             3  @SCM_LIB.SCM(SCH_1):GND_P2
    2  85_5INCH_IN1_DP      2  @SCM_LIB.SCM(SCH_1):85_5INCH_IN1_DP
    1  85_5INCH_IN1_DN      1  @SCM_LIB.SCM(SCH_1):85_5INCH_IN1_DN

DELTA_L  I31  J12    [DELTA_L-DELTA-L,THLF,EMPTY,TP24]
    3  GND_P1             3  @SCM_LIB.SCM(SCH_1):GND_P1
    1  85_5INCH_TOP_DP      1  @SCM_LIB.SCM(SCH_1):85_5INCH_TOP_DP
    2  85_5INCH_TOP_DN      2  @SCM_LIB.SCM(SCH_1):85_5INCH_TOP_DN

DELTA_L  I21  J16    [DELTA_L-DELTA-L,THLF,EMPTY,TP24]
    3  GND_P2             3  @SCM_LIB.SCM(SCH_1):GND_P2
    2  85_5INCH_IN4_DP      2  @SCM_LIB.SCM(SCH_1):85_5INCH_IN4_DP
    1  85_5INCH_IN4_DN      1  @SCM_LIB.SCM(SCH_1):85_5INCH_IN4_DN

DELTA_L  I23  J17    [DELTA_L-DELTA-L,THLF,EMPTY,TP24]
    3  GND_P1             3  @SCM_LIB.SCM(SCH_1):GND_P1
    2  85_5INCH_BOT_DP      2  @SCM_LIB.SCM(SCH_1):85_5INCH_BOT_DP
    1  85_5INCH_BOT_DN      1  @SCM_LIB.SCM(SCH_1):85_5INCH_BOT_DN

DELTA_L  I27  J19    [DELTA_L-DELTA-L,THLF,EMPTY,TP24]
    3  GND_P2             3  @SCM_LIB.SCM(SCH_1):GND_P2
    1  85_5INCH_IN4_DP      1  @SCM_LIB.SCM(SCH_1):85_5INCH_IN4_DP
    2  85_5INCH_IN4_DN      2  @SCM_LIB.SCM(SCH_1):85_5INCH_IN4_DN

DELTA_L  I28  J20    [DELTA_L-DELTA-L,THLF,EMPTY,TP24]
    3  GND_P1             3  @SCM_LIB.SCM(SCH_1):GND_P1
    1  85_5INCH_BOT_DP      1  @SCM_LIB.SCM(SCH_1):85_5INCH_BOT_DP
    2  85_5INCH_BOT_DN      2  @SCM_LIB.SCM(SCH_1):85_5INCH_BOT_DN

DELTA_L  I42  J22    [DELTA_L-DELTA-L,THLF,EMPTY,TP24]
    3  GND_P1             3  @SCM_LIB.SCM(SCH_1):GND_P1
    1  85_10INCH_TOP_DP      1  @SCM_LIB.SCM(SCH_1):85_10INCH_TOP_DP
    2  85_10INCH_TOP_DN      2  @SCM_LIB.SCM(SCH_1):85_10INCH_TOP_DN

DELTA_L  I32  J23    [DELTA_L-DELTA-L,THLF,EMPTY,TP24]
    3  GND_P2             3  @SCM_LIB.SCM(SCH_1):GND_P2
    1  85_10INCH_IN4_DP      1  @SCM_LIB.SCM(SCH_1):85_10INCH_IN4_DP
    2  85_10INCH_IN4_DN      2  @SCM_LIB.SCM(SCH_1):85_10INCH_IN4_DN

DELTA_L  I33  J24    [DELTA_L-DELTA-L,THLF,EMPTY,TP24]
    3  GND_P1             3  @SCM_LIB.SCM(SCH_1):GND_P1
    1  85_10INCH_BOT_DP      1  @SCM_LIB.SCM(SCH_1):85_10INCH_BOT_DP
    2  85_10INCH_BOT_DN      2  @SCM_LIB.SCM(SCH_1):85_10INCH_BOT_DN

DELTA_L  I44  J25    [DELTA_L-DELTA-L,THLF,EMPTY,TP24]
    3  GND_P1             3  @SCM_LIB.SCM(SCH_1):GND_P1
    2  85_10INCH_TOP_DP      2  @SCM_LIB.SCM(SCH_1):85_10INCH_TOP_DP
    1  85_10INCH_TOP_DN      1  @SCM_LIB.SCM(SCH_1):85_10INCH_TOP_DN

DELTA_L  I36  J26    [DELTA_L-DELTA-L,THLF,EMPTY,TP24]
    3  GND_P2             3  @SCM_LIB.SCM(SCH_1):GND_P2
    2  85_10INCH_IN4_DP      2  @SCM_LIB.SCM(SCH_1):85_10INCH_IN4_DP
    1  85_10INCH_IN4_DN      1  @SCM_LIB.SCM(SCH_1):85_10INCH_IN4_DN

DELTA_L  I37  J27    [DELTA_L-DELTA-L,THLF,EMPTY,TP24]
    3  GND_P1             3  @SCM_LIB.SCM(SCH_1):GND_P1
    2  85_10INCH_BOT_DP      2  @SCM_LIB.SCM(SCH_1):85_10INCH_BOT_DP
    1  85_10INCH_BOT_DN      1  @SCM_LIB.SCM(SCH_1):85_10INCH_BOT_DN

DELTA_L  I45  J28    [DELTA_L-DELTA-L,THLF,EMPTY,TP24]
    3  GND_P1             3  @SCM_LIB.SCM(SCH_1):GND_P1
    2  85_10INCH_IN1_DP      2  @SCM_LIB.SCM(SCH_1):85_10INCH_IN1_DP
    1  85_10INCH_IN1_DN      1  @SCM_LIB.SCM(SCH_1):85_10INCH_IN1_DN

DELTA_L  I29  J29    [DELTA_L-DELTA-L,THLF,EMPTY,TP24]
    3  GND_P2             3  @SCM_LIB.SCM(SCH_1):GND_P2
    1  85_5INCH_IN1_DP      1  @SCM_LIB.SCM(SCH_1):85_5INCH_IN1_DP
    2  85_5INCH_IN1_DN      2  @SCM_LIB.SCM(SCH_1):85_5INCH_IN1_DN

DELTA_L  I43  J30    [DELTA_L-DELTA-L,THLF,EMPTY,TP24]
    3  GND_P1             3  @SCM_LIB.SCM(SCH_1):GND_P1
    1  85_10INCH_IN1_DP      1  @SCM_LIB.SCM(SCH_1):85_10INCH_IN1_DP
    2  85_10INCH_IN1_DN      2  @SCM_LIB.SCM(SCH_1):85_10INCH_IN1_DN

SCONN16_ACASPI006P06  I53  J40    [SCONN16_ACASPI006P06-SCONN16_AA]
    6  NC               NC3  NC
    5  NC               NC2  NC
    4  NC               NC1  NC
   14  NC               NC8  NC
   13  NC               NC7  NC
   12  NC               NC6  NC
   11  NC               NC4  NC
    1  SPI_PCH_IO3_FLASH_R1  HOLD_N  @SCM_LIB.SCM(SCH_1):SPI_PCH_IO3_FLASH_R1
    9  SPI_PCH_IO2_FLASH_R1   WP_N  @SCM_LIB.SCM(SCH_1):SPI_PCH_IO2_FLASH_R1
    8  SPI_PCH_IO1_FLASH_R1     DO  @SCM_LIB.SCM(SCH_1):SPI_PCH_IO1_FLASH_R1
   15  SPI_PCH_IO0_FLASH_R1     DI  @SCM_LIB.SCM(SCH_1):SPI_PCH_IO0_FLASH_R1
    7  SPI_PCH_CS0_FLASH_R1_N   CS_N  @SCM_LIB.SCM(SCH_1):SPI_PCH_CS0_FLASH_R1_N
   16  SPI_PCH_CLK_FLASH_R1    CLK  @SCM_LIB.SCM(SCH_1):SPI_PCH_CLK_FLASH_R1
    3  RST_SPI_PCH_FLASH_R1_N    NC0  @SCM_LIB.SCM(SCH_1):RST_SPI_PCH_FLASH_R1_N
    2  P3V3_AUX         VCC  @SCM_LIB.SCM(SCH_1):P3V3_AUX
   10  GND              GND  @SCM_LIB.SCM(SCH_1):GND

SCONN16_ACASPI006P06  I97  J121   [SCONN16_ACASPI006P06-SCONN16_AA]
    6  NC               NC3  NC
    5  NC               NC2  NC
    4  NC               NC1  NC
   14  NC               NC8  NC
   13  NC               NC7  NC
   12  NC               NC6  NC
   11  NC               NC4  NC
    1  SPI_BMC_IO3_FLASH_R1  HOLD_N  @SCM_LIB.SCM(SCH_1):SPI_BMC_IO3_FLASH_R1
    9  SPI_BMC_IO2_FLASH_R1   WP_N  @SCM_LIB.SCM(SCH_1):SPI_BMC_IO2_FLASH_R1
    8  SPI_BMC_IO1_FLASH_R1     DO  @SCM_LIB.SCM(SCH_1):SPI_BMC_IO1_FLASH_R1
   15  SPI_BMC_IO0_FLASH_R1     DI  @SCM_LIB.SCM(SCH_1):SPI_BMC_IO0_FLASH_R1
    7  SPI_BMC_CS0_FLASH_R1_N   CS_N  @SCM_LIB.SCM(SCH_1):SPI_BMC_CS0_FLASH_R1_N
   16  SPI_BMC_CLK_FLASH_R1    CLK  @SCM_LIB.SCM(SCH_1):SPI_BMC_CLK_FLASH_R1
    3  RST_SPI_BMC_FLASH_R1_N    NC0  @SCM_LIB.SCM(SCH_1):RST_SPI_BMC_FLASH_R1_N
    2  P3V3_AUX         VCC  @SCM_LIB.SCM(SCH_1):P3V3_AUX
   10  GND              GND  @SCM_LIB.SCM(SCH_1):GND

Q_FUSE  I108  L1     [Q_FUSE_SMLF-0.5A/6V,IC,DK050TPA]
    2  P3V3_DP_L          2  @SCM_LIB.SCM(SCH_1):P3V3_DP_L
    1  P3V3_DP            1  @SCM_LIB.SCM(SCH_1):P3V3_DP

Q_INDUCTOR  I272  L2     [Q_INDUCTOR_SMLF-BLM18PG121SN1DB]
    2  P3V3_STBY_PLLAHVDD      2  @SCM_LIB.SCM(SCH_1):P3V3_STBY_PLLAHVDD
    1  P1V2_AUX           1  @SCM_LIB.SCM(SCH_1):P1V2_AUX

Q_INDUCTOR  I65  L3     [Q_INDUCTOR_SMLF-BLM18PG121SN1DA]
    2  P1V8_BMC_USB2AV18      2  @SCM_LIB.SCM(SCH_1):P1V8_BMC_USB2AV18
    1  P1V8_AUX           1  @SCM_LIB.SCM(SCH_1):P1V8_AUX

Q_INDUCTOR  I82  L4     [Q_INDUCTOR_SMLF-BLM18PG121SN1DA]
    2  P3V3_BMC_USB2AV33      2  @SCM_LIB.SCM(SCH_1):P3V3_BMC_USB2AV33
    1  P3V3_AUX           1  @SCM_LIB.SCM(SCH_1):P3V3_AUX

Q_INDUCTOR  I120  L5     [Q_INDUCTOR_SMLF-BLM18PG121SN1DA]
    2  P1V8_STBY_AVDDPLL      2  @SCM_LIB.SCM(SCH_1):P1V8_STBY_AVDDPLL
    1  P1V8_AUX           1  @SCM_LIB.SCM(SCH_1):P1V8_AUX

Q_INDUCTOR  I124  L6     [Q_INDUCTOR_SMLF-BLM18PG121SN1DA]
    2  P1V0_STBY_RC_VCC10A      2  @SCM_LIB.SCM(SCH_1):P1V0_STBY_RC_VCC10A
    1  P1V0_AUX           1  @SCM_LIB.SCM(SCH_1):P1V0_AUX

Q_INDUCTOR  I146  L7     [Q_INDUCTOR_SMLF-BLM18PG121SN1DA]
    2  P3V3_STBY_DACAV33      2  @SCM_LIB.SCM(SCH_1):P3V3_STBY_DACAV33
    1  P3V3_AUX           1  @SCM_LIB.SCM(SCH_1):P3V3_AUX

Q_INDUCTOR  I29  L8     [Q_INDUCTOR_SMLF-BLM18PG121SN1DA]
    2  P1V0_STBY_PLAVDD      2  @SCM_LIB.SCM(SCH_1):P1V0_STBY_PLAVDD
    1  P1V0_AUX           1  @SCM_LIB.SCM(SCH_1):P1V0_AUX

Q_INDUCTOR  I142  L9     [Q_INDUCTOR_SMLF-BLM18PG121SN1DA]
    2  P3V3_STBY_PLLAHVDD      2  @SCM_LIB.SCM(SCH_1):P3V3_STBY_PLLAHVDD
    1  P3V3_AUX           1  @SCM_LIB.SCM(SCH_1):P3V3_AUX

Q_INDUCTOR  I24  L10    [Q_INDUCTOR_SMLF-BLM18PG121SN1DA]
    2  P1V8_STBY_PE_VCC18A      2  @SCM_LIB.SCM(SCH_1):P1V8_STBY_PE_VCC18A
    1  P1V8_AUX           1  @SCM_LIB.SCM(SCH_1):P1V8_AUX

Q_INDUCTOR  I47  L11    [Q_INDUCTOR_SMLF-BLM18PG121SN1DA]
    2  P1V2_STBY_MVDD_CK      2  @SCM_LIB.SCM(SCH_1):P1V2_STBY_MVDD_CK
    1  P1V2_AUX           1  @SCM_LIB.SCM(SCH_1):P1V2_AUX

Q_INDUCTOR  I99  L12    [Q_INDUCTOR_SMLF-BLM18PG121SN1DA]
    1  P3V3_AUX           1  @SCM_LIB.SCM(SCH_1):P3V3_AUX
    2  A_BMC_ADCAV33      2  @SCM_LIB.SCM(SCH_1):A_BMC_ADCAV33

Q_INDUCTOR  I158  L13    [Q_INDUCTOR_SMLF-BLM18PG121SN1DA]
    2  P1V0_STBY_PE_VCC10A      2  @SCM_LIB.SCM(SCH_1):P1V0_STBY_PE_VCC10A
    1  P1V0_AUX           1  @SCM_LIB.SCM(SCH_1):P1V0_AUX

Q_INDUCTOR  I154  L14    [Q_INDUCTOR_SMLF-BLM18PG121SN1DA]
    2  P1V8_STBY_RC_VCC18A      2  @SCM_LIB.SCM(SCH_1):P1V8_STBY_RC_VCC18A
    1  P1V8_AUX           1  @SCM_LIB.SCM(SCH_1):P1V8_AUX

Q_INDUCTOR  I170  L15    [Q_INDUCTOR_SMLF-BLM18PG121SN1DA]
    2  P1V0_STBY_DP_VCC10A      2  @SCM_LIB.SCM(SCH_1):P1V0_STBY_DP_VCC10A
    1  P1V0_AUX           1  @SCM_LIB.SCM(SCH_1):P1V0_AUX

Q_INDUCTOR  I166  L16    [Q_INDUCTOR_SMLF-BLM18PG121SN1DA]
    2  P1V8_STBY_DP_VCC18A      2  @SCM_LIB.SCM(SCH_1):P1V8_STBY_DP_VCC18A
    1  P1V8_AUX           1  @SCM_LIB.SCM(SCH_1):P1V8_AUX

Q_INDUCTOR  I176  L17    [Q_INDUCTOR_SMLF-BLM18EG121SN1DA]
    1  PGPPA_BMC_AUX_L      1  @SCM_LIB.SCM(SCH_1):PGPPA_BMC_AUX_L
    2  PGPPA_BMC_AUX      2  @SCM_LIB.SCM(SCH_1):PGPPA_BMC_AUX

Q_INDUCTOR  I152  L18    [Q_INDUCTOR_SMLF-BLM15PX121SN1DA]
    1  P3V3_XTALVDD       1  @SCM_LIB.SCM(SCH_1):P3V3_XTALVDD
    2  P3V3_AUX           2  @SCM_LIB.SCM(SCH_1):P3V3_AUX

Q_INDUCTOR  I49  L20    [Q_INDUCTOR_SMLF-220/1500MA,INDA]
    1  P3V3_AUX_RJ45      1  @SCM_LIB.SCM(SCH_1):P3V3_AUX_RJ45
    2  P3V3_AUX           2  @SCM_LIB.SCM(SCH_1):P3V3_AUX

Q_INDUCTOR4P_12  I9   L23    [Q_INDUCTOR4P_12-67/320MA,320MAB]
    1  USB_FPNL_DP        1  @SCM_LIB.SCM(SCH_1):USB_FPNL_DP
    4  USB_FPNL_DN        4  @SCM_LIB.SCM(SCH_1):USB_FPNL_DN
    2  USB2_01_F_DP       2  @SCM_LIB.SCM(SCH_1):USB2_01_F_DP
    3  USB2_01_F_DN       3  @SCM_LIB.SCM(SCH_1):USB2_01_F_DN

Q_INDUCTOR4P_12  I86  L24    [Q_INDUCTOR4P_12-67/320MA,320MAA]
    2  USB2_EXT_R_DP      2  @SCM_LIB.SCM(SCH_1):USB2_EXT_R_DP
    3  USB2_EXT_R_DN      3  @SCM_LIB.SCM(SCH_1):USB2_EXT_R_DN
    1  USB2_EXT_DP        1  @SCM_LIB.SCM(SCH_1):USB2_EXT_DP
    4  USB2_EXT_DN        4  @SCM_LIB.SCM(SCH_1):USB2_EXT_DN

Q_INDUCTOR  I50  L26    [Q_INDUCTOR_SMLF-BLM18EG121SN1DA]
    2  PVCCD_PLL_AUX      2  @SCM_LIB.SCM(SCH_1):PVCCD_PLL_AUX
    1  P3V3_AUX           1  @SCM_LIB.SCM(SCH_1):P3V3_AUX

Q_INDUCTOR  I16  L27    [Q_INDUCTOR_SMLF-BLM18EG121SN1DA]
    2  PVCCA_AUX_PLD      2  @SCM_LIB.SCM(SCH_1):PVCCA_AUX_PLD
    1  P3V3_AUX           1  @SCM_LIB.SCM(SCH_1):P3V3_AUX

Q_INDUCTOR  I38  L28    [Q_INDUCTOR_SMLF-47/300MA,IND,CA]
    2  V_DACB_IO          2  @SCM_LIB.SCM(SCH_1):V_DACB_IO
    1  V_DACB             1  @SCM_LIB.SCM(SCH_1):V_DACB

Q_INDUCTOR  I37  L29    [Q_INDUCTOR_SMLF-47/300MA,IND,CA]
    2  V_DACG_IO          2  @SCM_LIB.SCM(SCH_1):V_DACG_IO
    1  V_DACG             1  @SCM_LIB.SCM(SCH_1):V_DACG

Q_INDUCTOR  I36  L30    [Q_INDUCTOR_SMLF-47/300MA,IND,CA]
    2  V_DACR_IO          2  @SCM_LIB.SCM(SCH_1):V_DACR_IO
    1  V_DACR             1  @SCM_LIB.SCM(SCH_1):V_DACR

Q_INDUCTOR  I161  L31    [Q_INDUCTOR_SMLF-BLM15PX121SN1DA]
    1  P3V3_BIASVDD       1  @SCM_LIB.SCM(SCH_1):P3V3_BIASVDD
    2  P3V3_AUX           2  @SCM_LIB.SCM(SCH_1):P3V3_AUX

Q_INDUCTOR  I173  L32    [Q_INDUCTOR_SMLF-BLM15PX121SN1DA]
    1  P1V2_PHY0_AVDDL      1  @SCM_LIB.SCM(SCH_1):P1V2_PHY0_AVDDL
    2  P1V2_PHY0          2  @SCM_LIB.SCM(SCH_1):P1V2_PHY0

Q_INDUCTOR  I172  L33    [Q_INDUCTOR_SMLF-BLM15PX121SN1DA]
    1  P1V2_PHY0_PLLVDD      1  @SCM_LIB.SCM(SCH_1):P1V2_PHY0_PLLVDD
    2  P1V2_PHY0          2  @SCM_LIB.SCM(SCH_1):P1V2_PHY0

Q_INDUCTOR  I164  L34    [Q_INDUCTOR_SMLF-BLM15PX121SN1DA]
    1  P3V3_AVDD          1  @SCM_LIB.SCM(SCH_1):P3V3_AVDD
    2  P3V3_AUX           2  @SCM_LIB.SCM(SCH_1):P3V3_AUX

OSC4_7X25000018  I39  OSC1   [OSC4_7X25000018-25MHZ,SMLF,MISA]
    1  PU_25M_BMC_CLK_EN     OE  @SCM_LIB.SCM(SCH_1):PU_25M_BMC_CLK_EN
    4  P3V3_RGM         VDD  @SCM_LIB.SCM(SCH_1):P3V3_RGM
    2  GND              GND  @SCM_LIB.SCM(SCH_1):GND
    3  BMC_CLK_25M_R    OUT  @SCM_LIB.SCM(SCH_1):BMC_CLK_25M_R

OSC4_7X25000018  I431  OSC2   [OSC4_7X25000018-25MHZ,SMLF,MISA]
    1  PU_25M_FPGA_CLK_EN     OE  @SCM_LIB.SCM(SCH_1):PU_25M_FPGA_CLK_EN
    4  P3V3_AUX         VDD  @SCM_LIB.SCM(SCH_1):P3V3_AUX
    2  GND              GND  @SCM_LIB.SCM(SCH_1):GND
    3  CLK_25M_OSC_FPGA_R    OUT  @SCM_LIB.SCM(SCH_1):CLK_25M_OSC_FPGA_R

Q_CAP  I1   PC205  [Q_CAP_0402-0.1UF,25V,10%,X7R,CA]
    2  GND                B  @SCM_LIB.SCM(SCH_1):GND
    1  EN_P5V_AUX         A  @SCM_LIB.SCM(SCH_1):EN_P5V_AUX

Q_CAP  I47  PC206  [Q_CAP_C0805-10UF,25V,10%,X6S,CA]
    1  SW_P5V_AUX_FLT      A  @SCM_LIB.SCM(SCH_1):SW_P5V_AUX_FLT
    2  GND                B  @SCM_LIB.SCM(SCH_1):GND

Q_CAP  I48  PC207  [Q_CAP_C0805-10UF,25V,10%,X6S,CA]
    1  SW_P5V_AUX_FLT      A  @SCM_LIB.SCM(SCH_1):SW_P5V_AUX_FLT
    2  GND                B  @SCM_LIB.SCM(SCH_1):GND

Q_CAP  I13  PC208  [Q_CAP_C0402-1UF,25V,10%,X6S,CHA]
    1  P5V_AUX_VCC        A  @SCM_LIB.SCM(SCH_1):P5V_AUX_VCC
    2  GND                B  @SCM_LIB.SCM(SCH_1):GND

Q_CAP  I45  PC210  [Q_CAP_0402-0.1UF,25V,10%,X7R,CA]
    1  SW_P5V_AUX_FLT      A  @SCM_LIB.SCM(SCH_1):SW_P5V_AUX_FLT
    2  GND                B  @SCM_LIB.SCM(SCH_1):GND

Q_CAP  I31  PC212  [Q_CAP_0402-0.1UF,25V,10%,X7R,CA]
    1  P5V_AUX            A  @SCM_LIB.SCM(SCH_1):P5V_AUX
    2  GND                B  @SCM_LIB.SCM(SCH_1):GND

Q_CAP  I32  PC213  [Q_CAP_C0805-22UF,16V,20%,X6S,CA]
    1  P5V_AUX            A  @SCM_LIB.SCM(SCH_1):P5V_AUX
    2  GND                B  @SCM_LIB.SCM(SCH_1):GND

Q_CAP  I33  PC214  [Q_CAP_C0805-22UF,16V,20%,X6S,CA]
    1  P5V_AUX            A  @SCM_LIB.SCM(SCH_1):P5V_AUX
    2  GND                B  @SCM_LIB.SCM(SCH_1):GND

Q_CAP  I36  PC215  [Q_CAP_C0805-22UF,16V,20%,X6S,CA]
    1  P5V_AUX            A  @SCM_LIB.SCM(SCH_1):P5V_AUX
    2  GND                B  @SCM_LIB.SCM(SCH_1):GND

Q_CAP  I23  PC216  [Q_CAP_0402-0.22UF,16V,10%,X7R,A]
    2  SW_P5V_AUX_SW      B  @SCM_LIB.SCM(SCH_1):SW_P5V_AUX_SW
    1  SW_P5V_AUX_BST      A  @SCM_LIB.SCM(SCH_1):SW_P5V_AUX_BST

Q_CAP  I37  PC217  [Q_CAP_C0805-22UF,16V,20%,X6S,CA]
    1  P5V_AUX            A  @SCM_LIB.SCM(SCH_1):P5V_AUX
    2  GND                B  @SCM_LIB.SCM(SCH_1):GND

Q_CAP  I81  PC218  [Q_CAP_C0805-10UF,25V,10%,X6S,CA]
    1  SW_P3V3_AUX_FLT      A  @SCM_LIB.SCM(SCH_1):SW_P3V3_AUX_FLT
    2  GND                B  @SCM_LIB.SCM(SCH_1):GND

Q_CAP  I80  PC219  [Q_CAP_C0805-10UF,25V,10%,X6S,CA]
    1  SW_P3V3_AUX_FLT      A  @SCM_LIB.SCM(SCH_1):SW_P3V3_AUX_FLT
    2  GND                B  @SCM_LIB.SCM(SCH_1):GND

Q_CAP  I9   PC221  [Q_CAP_C0402-1UF,25V,10%,X6S,CHA]
    1  P3V3_AUX_VCC       A  @SCM_LIB.SCM(SCH_1):P3V3_AUX_VCC
    2  GND                B  @SCM_LIB.SCM(SCH_1):GND

Q_CAP  I11  PC223  [Q_CAP_0402-0.1UF,25V,10%,X7R,CA]
    1  SW_P3V3_AUX_FLT      A  @SCM_LIB.SCM(SCH_1):SW_P3V3_AUX_FLT
    2  GND                B  @SCM_LIB.SCM(SCH_1):GND

Q_CAP  I15  PC224  [Q_CAP_0402-0.22UF,16V,10%,X7R,A]
    2  SW_P3V3_AUX_SW      B  @SCM_LIB.SCM(SCH_1):SW_P3V3_AUX_SW
    1  SW_P3V3_AUX_BST      A  @SCM_LIB.SCM(SCH_1):SW_P3V3_AUX_BST

Q_CAP  I23  PC225  [Q_CAP_0402-0.1UF,25V,10%,X7R,CA]
    1  P3V3_AUX           A  @SCM_LIB.SCM(SCH_1):P3V3_AUX
    2  GND                B  @SCM_LIB.SCM(SCH_1):GND

Q_CAP  I35  PC226  [Q_CAP_C0805-22UF,10V,20%,X6S,CA]
    1  P3V3_AUX           A  @SCM_LIB.SCM(SCH_1):P3V3_AUX
    2  GND                B  @SCM_LIB.SCM(SCH_1):GND

Q_CAP  I36  PC227  [Q_CAP_C0805-22UF,10V,20%,X6S,CA]
    1  P3V3_AUX           A  @SCM_LIB.SCM(SCH_1):P3V3_AUX
    2  GND                B  @SCM_LIB.SCM(SCH_1):GND

Q_CAP  I37  PC228  [Q_CAP_C0805-22UF,10V,20%,X6S,CA]
    1  P3V3_AUX           A  @SCM_LIB.SCM(SCH_1):P3V3_AUX
    2  GND                B  @SCM_LIB.SCM(SCH_1):GND

Q_CAP  I38  PC229  [Q_CAP_C0805-22UF,10V,20%,X6S,CA]
    1  P3V3_AUX           A  @SCM_LIB.SCM(SCH_1):P3V3_AUX
    2  GND                B  @SCM_LIB.SCM(SCH_1):GND

Q_CAP  I15  PC233  [Q_CAP_C0402-1UF,25V,10%,X6S,CHA]
    1  P5V_AUX            A  @SCM_LIB.SCM(SCH_1):P5V_AUX
    2  GND                B  @SCM_LIB.SCM(SCH_1):GND

Q_CAP  I53  PC235  [Q_CAP_0402-0.1UF,25V,10%,X7R,CA]
    1  P2V5_AUX           A  @SCM_LIB.SCM(SCH_1):P2V5_AUX
    2  GND                B  @SCM_LIB.SCM(SCH_1):GND

Q_CAP  I52  PC237  [Q_CAP_C0805-10UF,25V,10%,X6S,CA]
    1  P2V5_AUX           A  @SCM_LIB.SCM(SCH_1):P2V5_AUX
    2  GND                B  @SCM_LIB.SCM(SCH_1):GND

Q_CAP  I91  PC239  [Q_CAP_0402-100PF,50V,5%,NPO,CHA]
    1  P3V3_AUX_FB_RC      A  @SCM_LIB.SCM(SCH_1):P3V3_AUX_FB_RC
    2  P3V3_AUX           B  @SCM_LIB.SCM(SCH_1):P3V3_AUX

Q_CAP  I63  PC242  [Q_CAP_C0805-10UF,25V,10%,X6S,CA]
    1  P3V3_AUX           A  @SCM_LIB.SCM(SCH_1):P3V3_AUX
    2  GND                B  @SCM_LIB.SCM(SCH_1):GND

Q_CAP  I57  PC243  [Q_CAP_C0402-1UF,25V,10%,X6S,CHA]
    1  P5V_AUX            A  @SCM_LIB.SCM(SCH_1):P5V_AUX
    2  GND                B  @SCM_LIB.SCM(SCH_1):GND

Q_CAP  I65  PC248  [Q_CAP_C0805-10UF,25V,10%,X6S,CA]
    1  P1V8_AUX           A  @SCM_LIB.SCM(SCH_1):P1V8_AUX
    2  GND                B  @SCM_LIB.SCM(SCH_1):GND

Q_CAP  I66  PC249  [Q_CAP_0402-0.1UF,25V,10%,X7R,CA]
    1  P1V8_AUX           A  @SCM_LIB.SCM(SCH_1):P1V8_AUX
    2  GND                B  @SCM_LIB.SCM(SCH_1):GND

Q_CAP  I7   PC250  [Q_CAP_C0402-1UF,25V,10%,X6S,CHA]
    1  P1V2_AUX_VCC       A  @SCM_LIB.SCM(SCH_1):P1V2_AUX_VCC
    2  GND                B  @SCM_LIB.SCM(SCH_1):GND

Q_CAP  I43  PC251  [Q_CAP_C0805-10UF,25V,10%,X6S,CA]
    1  SW_P1V2_AUX_FLT      A  @SCM_LIB.SCM(SCH_1):SW_P1V2_AUX_FLT
    2  GND                B  @SCM_LIB.SCM(SCH_1):GND

Q_CAP  I42  PC252  [Q_CAP_C0805-10UF,25V,10%,X6S,CA]
    1  SW_P1V2_AUX_FLT      A  @SCM_LIB.SCM(SCH_1):SW_P1V2_AUX_FLT
    2  GND                B  @SCM_LIB.SCM(SCH_1):GND

Q_CAP  I16  PC253  [Q_CAP_0402-0.1UF,25V,10%,X7R,CA]
    1  SW_P1V2_AUX_FLT      A  @SCM_LIB.SCM(SCH_1):SW_P1V2_AUX_FLT
    2  GND                B  @SCM_LIB.SCM(SCH_1):GND

Q_CAP  I19  PC254  [Q_CAP_0402-0.22UF,16V,10%,X7R,A]
    2  SW_P1V2_AUX_SW      B  @SCM_LIB.SCM(SCH_1):SW_P1V2_AUX_SW
    1  SW_P1V2_AUX_BST      A  @SCM_LIB.SCM(SCH_1):SW_P1V2_AUX_BST

Q_CAP  I23  PC255  [Q_CAP_0402-0.1UF,25V,10%,X7R,CA]
    1  P1V2_AUX           A  @SCM_LIB.SCM(SCH_1):P1V2_AUX
    2  GND                B  @SCM_LIB.SCM(SCH_1):GND

Q_CAP  I24  PC256  [Q_CAP_0805-22UF,4V,20%,X6S,TMPA]
    1  P1V2_AUX           A  @SCM_LIB.SCM(SCH_1):P1V2_AUX
    2  GND                B  @SCM_LIB.SCM(SCH_1):GND

Q_CAP  I25  PC257  [Q_CAP_0805-22UF,4V,20%,X6S,TMPA]
    1  P1V2_AUX           A  @SCM_LIB.SCM(SCH_1):P1V2_AUX
    2  GND                B  @SCM_LIB.SCM(SCH_1):GND

Q_CAP  I28  PC258  [Q_CAP_0805-22UF,4V,20%,X6S,TMPA]
    1  P1V2_AUX           A  @SCM_LIB.SCM(SCH_1):P1V2_AUX
    2  GND                B  @SCM_LIB.SCM(SCH_1):GND

Q_CAP  I29  PC259  [Q_CAP_0805-22UF,4V,20%,X6S,TMPA]
    1  P1V2_AUX           A  @SCM_LIB.SCM(SCH_1):P1V2_AUX
    2  GND                B  @SCM_LIB.SCM(SCH_1):GND

Q_CAP  I7   PC260  [Q_CAP_C0402-1UF,25V,10%,X6S,CHA]
    1  P1V0_AUX_VCC       A  @SCM_LIB.SCM(SCH_1):P1V0_AUX_VCC
    2  GND                B  @SCM_LIB.SCM(SCH_1):GND

Q_CAP  I44  PC261  [Q_CAP_C0805-10UF,25V,10%,X6S,CA]
    1  SW_P1V0_AUX_FLT      A  @SCM_LIB.SCM(SCH_1):SW_P1V0_AUX_FLT
    2  GND                B  @SCM_LIB.SCM(SCH_1):GND

Q_CAP  I43  PC262  [Q_CAP_C0805-10UF,25V,10%,X6S,CA]
    1  SW_P1V0_AUX_FLT      A  @SCM_LIB.SCM(SCH_1):SW_P1V0_AUX_FLT
    2  GND                B  @SCM_LIB.SCM(SCH_1):GND

Q_CAP  I16  PC263  [Q_CAP_0402-0.1UF,25V,10%,X7R,CA]
    1  SW_P1V0_AUX_FLT      A  @SCM_LIB.SCM(SCH_1):SW_P1V0_AUX_FLT
    2  GND                B  @SCM_LIB.SCM(SCH_1):GND

Q_CAP  I19  PC264  [Q_CAP_0402-0.22UF,16V,10%,X7R,A]
    2  SW_P1V0_AUX_SW      B  @SCM_LIB.SCM(SCH_1):SW_P1V0_AUX_SW
    1  SW_P1V0_AUX_BST      A  @SCM_LIB.SCM(SCH_1):SW_P1V0_AUX_BST

Q_CAP  I23  PC266  [Q_CAP_0402-0.1UF,25V,10%,X7R,CA]
    1  P1V0_AUX           A  @SCM_LIB.SCM(SCH_1):P1V0_AUX
    2  GND                B  @SCM_LIB.SCM(SCH_1):GND

Q_CAP  I24  PC267  [Q_CAP_0805-22UF,4V,20%,X6S,TMPA]
    1  P1V0_AUX           A  @SCM_LIB.SCM(SCH_1):P1V0_AUX
    2  GND                B  @SCM_LIB.SCM(SCH_1):GND

Q_CAP  I25  PC268  [Q_CAP_0805-22UF,4V,20%,X6S,TMPA]
    1  P1V0_AUX           A  @SCM_LIB.SCM(SCH_1):P1V0_AUX
    2  GND                B  @SCM_LIB.SCM(SCH_1):GND

Q_CAP  I28  PC269  [Q_CAP_0805-22UF,4V,20%,X6S,TMPA]
    1  P1V0_AUX           A  @SCM_LIB.SCM(SCH_1):P1V0_AUX
    2  GND                B  @SCM_LIB.SCM(SCH_1):GND

Q_CAP  I29  PC270  [Q_CAP_0805-22UF,4V,20%,X6S,TMPA]
    1  P1V0_AUX           A  @SCM_LIB.SCM(SCH_1):P1V0_AUX
    2  GND                B  @SCM_LIB.SCM(SCH_1):GND

Q_CAP  I22  PC271  [Q_CAP_0402-0.1UF,25V,10%,X7R,CA]
    1  P5V_AUX_REF        A  @SCM_LIB.SCM(SCH_1):P5V_AUX_REF
    2  GND                B  @SCM_LIB.SCM(SCH_1):GND

Q_CAP  I27  PC272  [Q_CAP_C0402-68PF,50V,5%,COG,CHA]
    1  P5V_AUX_FB         A  @SCM_LIB.SCM(SCH_1):P5V_AUX_FB
    2  P5V_AUX            B  @SCM_LIB.SCM(SCH_1):P5V_AUX

Q_CAP  I86  PC273  [Q_CAP_0402-3300PF,50V,10%,X7R,A]
    1  P3V3_AUX_REF       A  @SCM_LIB.SCM(SCH_1):P3V3_AUX_REF
    2  GND                B  @SCM_LIB.SCM(SCH_1):GND

Q_CAP  I51  PC307  [Q_CAP_C0805-10UF,25V,10%,X6S,CA]
    1  P3V3_AUX           A  @SCM_LIB.SCM(SCH_1):P3V3_AUX
    2  GND                B  @SCM_LIB.SCM(SCH_1):GND

Q_INDUCTOR  I39  PL4    [Q_INDUCTOR_SMLF-BLM18SN220TN1DA]
    2  SW_P5V_AUX_FLT      2  @SCM_LIB.SCM(SCH_1):SW_P5V_AUX_FLT
    1  P12V_AUX           1  @SCM_LIB.SCM(SCH_1):P12V_AUX

Q_INDUCTOR  I32  PL19   [Q_INDUCTOR_SMLF-BLM18SN220TN1DA]
    2  SW_P3V3_AUX_FLT      2  @SCM_LIB.SCM(SCH_1):SW_P3V3_AUX_FLT
    1  P12V_AUX           1  @SCM_LIB.SCM(SCH_1):P12V_AUX

Q_INDUCTOR  I31  PL29   [Q_INDUCTOR_SMLF-BLM18SN220TN1DA]
    2  SW_P1V2_AUX_FLT      2  @SCM_LIB.SCM(SCH_1):SW_P1V2_AUX_FLT
    1  P12V_AUX           1  @SCM_LIB.SCM(SCH_1):P12V_AUX

Q_INDUCTOR  I21  PL31   [Q_INDUCTOR_SMLF-1UH,IND,CV-10BA]
    1  SW_P1V2_AUX_SW      1  @SCM_LIB.SCM(SCH_1):SW_P1V2_AUX_SW
    2  P1V2_AUX           2  @SCM_LIB.SCM(SCH_1):P1V2_AUX

Q_INDUCTOR  I34  PL32   [Q_INDUCTOR_SMLF-BLM18SN220TN1DA]
    2  SW_P1V0_AUX_FLT      2  @SCM_LIB.SCM(SCH_1):SW_P1V0_AUX_FLT
    1  P12V_AUX           1  @SCM_LIB.SCM(SCH_1):P12V_AUX

Q_INDUCTOR  I37  PL33   [Q_INDUCTOR_SMLF-1UH,IND,CV-10BA]
    1  SW_P1V0_AUX_SW      1  @SCM_LIB.SCM(SCH_1):SW_P1V0_AUX_SW
    2  P1V0_AUX           2  @SCM_LIB.SCM(SCH_1):P1V0_AUX

Q_INDUCTOR  I28  PL34   [Q_INDUCTOR_SMLF-4.7UH,IND,CV-4A]
    1  SW_P5V_AUX_SW      1  @SCM_LIB.SCM(SCH_1):SW_P5V_AUX_SW
    2  P5V_AUX            2  @SCM_LIB.SCM(SCH_1):P5V_AUX

Q_INDUCTOR  I92  PL35   [Q_INDUCTOR_SMLF-3.3UH/6A,IND,CA]
    1  SW_P3V3_AUX_SW      1  @SCM_LIB.SCM(SCH_1):SW_P3V3_AUX_SW
    2  P3V3_AUX           2  @SCM_LIB.SCM(SCH_1):P3V3_AUX

Q_RES  I47  PR193  [Q_RES_0402LF-0,5%,1/16W,CHIP,CA]
    2  PVCC2_AUX          B  @SCM_LIB.SCM(SCH_1):PVCC2_AUX
    1  P3V3_AUX           A  @SCM_LIB.SCM(SCH_1):P3V3_AUX

Q_RES  I48  PR205  [Q_RES_0402LF-0,5%,1/16W,EMPTY,A]
    2  PVCC2_AUX          B  @SCM_LIB.SCM(SCH_1):PVCC2_AUX
    1  P5V_AUX            A  @SCM_LIB.SCM(SCH_1):P5V_AUX

Q_RES  I21  PR241  [Q_RES_0402LF-51.1K,1%,1/16W,CHA]
    2  PWRGD_P5V_AUX_R      B  @SCM_LIB.SCM(SCH_1):PWRGD_P5V_AUX_R
    1  P5V_AUX_VCC        A  @SCM_LIB.SCM(SCH_1):P5V_AUX_VCC

Q_RES  I13  PR242  [Q_RES_0402LF-10K,1%,1/16W,CHIPA]
    2  PWRGD_P3V3_AUX_R      B  @SCM_LIB.SCM(SCH_1):PWRGD_P3V3_AUX_R
    1  P3V3_AUX           A  @SCM_LIB.SCM(SCH_1):P3V3_AUX

Q_RES  I46  PR244  [Q_RES_0402LF-10K,1%,1/16W,CHIPA]
    2  PWRGD_P2V5_AUX_R      B  @SCM_LIB.SCM(SCH_1):PWRGD_P2V5_AUX_R
    1  P3V3_AUX           A  @SCM_LIB.SCM(SCH_1):P3V3_AUX

Q_RES  I43  PR245  [Q_RES_0402LF-100K,1%,1/16W,CHIA]
    1  PWRGD_P5V_AUX_R      A  @SCM_LIB.SCM(SCH_1):PWRGD_P5V_AUX_R
    2  GND                B  @SCM_LIB.SCM(SCH_1):GND

Q_RES  I55  PR255  [Q_RES_0402LF-10K,1%,1/16W,CHIPA]
    2  PWRGD_P1V8_AUX_R      B  @SCM_LIB.SCM(SCH_1):PWRGD_P1V8_AUX_R
    1  P3V3_AUX           A  @SCM_LIB.SCM(SCH_1):P3V3_AUX

Q_RES  I45  PR274  [Q_RES_0402LF-0,5%,1/16W,CHIP,CA]
    2  PVCC1_AUX          B  @SCM_LIB.SCM(SCH_1):PVCC1_AUX
    1  P3V3_AUX           A  @SCM_LIB.SCM(SCH_1):P3V3_AUX

Q_RES  I48  PR275  [Q_RES_0402LF-0,5%,1/16W,EMPTY,A]
    2  PVCC1_AUX          B  @SCM_LIB.SCM(SCH_1):PVCC1_AUX
    1  P5V_AUX            A  @SCM_LIB.SCM(SCH_1):P5V_AUX

Q_RES  I87  PR276  [Q_RES_0402LF-8.66K,1%,1/16W,CHA]
    2  P3V3_AUX_CS        B  @SCM_LIB.SCM(SCH_1):P3V3_AUX_CS
    1  GND                A  @SCM_LIB.SCM(SCH_1):GND

Q_RES  I6   PR496  [Q_RES_0402LF-150K,1%,1/16W,CHIA]
    1  P1V2_AUX_MODE      A  @SCM_LIB.SCM(SCH_1):P1V2_AUX_MODE
    2  GND                B  @SCM_LIB.SCM(SCH_1):GND

Q_RES  I18  PR498  [Q_RES_0402LF-10K,1%,1/16W,CHIPA]
    2  PWRGD_P1V2_AUX_R      B  @SCM_LIB.SCM(SCH_1):PWRGD_P1V2_AUX_R
    1  P3V3_AUX           A  @SCM_LIB.SCM(SCH_1):P3V3_AUX

Q_RES  I18  PR500  [Q_RES_0402LF-10K,1%,1/16W,CHIPA]
    2  PWRGD_P1V0_AUX_R      B  @SCM_LIB.SCM(SCH_1):PWRGD_P1V0_AUX_R
    1  P3V3_AUX           A  @SCM_LIB.SCM(SCH_1):P3V3_AUX

Q_RES  I4   PR521  [Q_RES_0402LF-681K,1%,1/16W,CHIA]
    1  P12V_AUX           A  @SCM_LIB.SCM(SCH_1):P12V_AUX
    2  EN_P5V_AUX         B  @SCM_LIB.SCM(SCH_1):EN_P5V_AUX

Q_RES  I3   PR522  [Q_RES_0402LF-100K,1%,1/16W,CHIA]
    2  GND                B  @SCM_LIB.SCM(SCH_1):GND
    1  EN_P5V_AUX         A  @SCM_LIB.SCM(SCH_1):EN_P5V_AUX

Q_RES  I9   PR525  [Q_RES_0402LF-13.3K,1%,1/16W,CHA]
    1  P5V_AUX_CS         A  @SCM_LIB.SCM(SCH_1):P5V_AUX_CS
    2  GND                B  @SCM_LIB.SCM(SCH_1):GND

Q_RES  I26  PR526  [Q_RES_0402LF-12.4K,1%,1/16W,CHA]
    1  P5V_AUX_FB         A  @SCM_LIB.SCM(SCH_1):P5V_AUX_FB
    2  GND                B  @SCM_LIB.SCM(SCH_1):GND

Q_RES  I30  PR527  [Q_RES_0402LF-91K,1%,1/16W,CHIPA]
    1  P5V_AUX_FB         A  @SCM_LIB.SCM(SCH_1):P5V_AUX_FB
    2  P5V_AUX            B  @SCM_LIB.SCM(SCH_1):P5V_AUX

Q_RES  I17  PR530  [Q_RES_0402LF-12.4K,1%,1/16W,CHA]
    2  P3V3_AUX_FB_RC      B  @SCM_LIB.SCM(SCH_1):P3V3_AUX_FB_RC
    1  GND                A  @SCM_LIB.SCM(SCH_1):GND

Q_RES  I88  PR532  [Q_RES_0402LF-60.4K,1%,1/16W,CHA]
    2  P3V3_AUX_MODE      B  @SCM_LIB.SCM(SCH_1):P3V3_AUX_MODE
    1  GND                A  @SCM_LIB.SCM(SCH_1):GND

Q_RES  I25  PR534  [Q_RES_0402LF-56K,1%,1/16W,CHIPA]
    1  P3V3_AUX_FB_RC      A  @SCM_LIB.SCM(SCH_1):P3V3_AUX_FB_RC
    2  P3V3_AUX           B  @SCM_LIB.SCM(SCH_1):P3V3_AUX

Q_RES  I8   PR539  [Q_RES_0402LF-5.1,5%,1/16W,CHIPA]
    1  PVCC1_AUX          A  @SCM_LIB.SCM(SCH_1):PVCC1_AUX
    2  P1V2_AUX_VCC       B  @SCM_LIB.SCM(SCH_1):P1V2_AUX_VCC

Q_RES  I8   PR541  [Q_RES_0402LF-5.1,5%,1/16W,CHIPA]
    1  PVCC2_AUX          A  @SCM_LIB.SCM(SCH_1):PVCC2_AUX
    2  P1V0_AUX_VCC       B  @SCM_LIB.SCM(SCH_1):P1V0_AUX_VCC

Q_RES  I6   PR543  [Q_RES_0402LF-100K,0.1%,1/16W,CA]
    1  P1V0_AUX_MODE      A  @SCM_LIB.SCM(SCH_1):P1V0_AUX_MODE
    2  GND                B  @SCM_LIB.SCM(SCH_1):GND

MPQ8626GDZ  I82  PU1    [MPQ8626GDZ-MPQ8626GD-Z,SMLF,ICA]
   11  SW_P3V3_AUX_SW    SW2  @SCM_LIB.SCM(SCH_1):SW_P3V3_AUX_SW
    2  SW_P3V3_AUX_SW    SW1  @SCM_LIB.SCM(SCH_1):SW_P3V3_AUX_SW
    3  SW_P3V3_AUX_FLT    VIN  @SCM_LIB.SCM(SCH_1):SW_P3V3_AUX_FLT
   10  SW_P3V3_AUX_BST    BST  @SCM_LIB.SCM(SCH_1):SW_P3V3_AUX_BST
    5  PWRGD_P5V_AUX_R2     EN  @SCM_LIB.SCM(SCH_1):PWRGD_P5V_AUX_R2
    9  PWRGD_P3V3_AUX_R  PGOOD  @SCM_LIB.SCM(SCH_1):PWRGD_P3V3_AUX_R
   13  P3V3_AUX_VCC     VCC  @SCM_LIB.SCM(SCH_1):P3V3_AUX_VCC
    8  P3V3_AUX_REF   TRK_REF  @SCM_LIB.SCM(SCH_1):P3V3_AUX_REF
   12  P3V3_AUX_MODE   MODE  @SCM_LIB.SCM(SCH_1):P3V3_AUX_MODE
    6  P3V3_AUX_FB_RC     FB  @SCM_LIB.SCM(SCH_1):P3V3_AUX_FB_RC
    4  P3V3_AUX_CS       CS  @SCM_LIB.SCM(SCH_1):P3V3_AUX_CS
   14  GND            PGND2  @SCM_LIB.SCM(SCH_1):GND
    1  GND            PGND1  @SCM_LIB.SCM(SCH_1):GND
    7  GND             AGND  @SCM_LIB.SCM(SCH_1):GND

MPQ8633AGLEC807Z  I42  PU38   [MPQ8633AGLEC807Z-MPQ8633AGLE-CA]
   20  SW_P5V_AUX_SW     SW  @SCM_LIB.SCM(SCH_1):SW_P5V_AUX_SW
   21  SW_P5V_AUX_FLT   VIN2  @SCM_LIB.SCM(SCH_1):SW_P5V_AUX_FLT
   10  SW_P5V_AUX_FLT   VIN1  @SCM_LIB.SCM(SCH_1):SW_P5V_AUX_FLT
    1  SW_P5V_AUX_BST    BST  @SCM_LIB.SCM(SCH_1):SW_P5V_AUX_BST
    9  PWRGD_P5V_AUX_R  PGOOD  @SCM_LIB.SCM(SCH_1):PWRGD_P5V_AUX_R
   19  P5V_AUX_VCC      VCC  @SCM_LIB.SCM(SCH_1):P5V_AUX_VCC
    5  P5V_AUX_REF    TRK_REF  @SCM_LIB.SCM(SCH_1):P5V_AUX_REF
    7  P5V_AUX_FB        FB  @SCM_LIB.SCM(SCH_1):P5V_AUX_FB
    3  P5V_AUX_CS        CS  @SCM_LIB.SCM(SCH_1):P5V_AUX_CS
    6  GND             RGND  @SCM_LIB.SCM(SCH_1):GND
  11_18  GND             PGND  @SCM_LIB.SCM(SCH_1):GND
    4  GND             MODE  @SCM_LIB.SCM(SCH_1):GND
    2  GND             AGND  @SCM_LIB.SCM(SCH_1):GND
    8  EN_P5V_AUX        EN  @SCM_LIB.SCM(SCH_1):EN_P5V_AUX

RT9059GQW  I60  PU39   [RT9059GQW-RT9059GQW,SMLF,IC,ALA]
    6  PWRGD_P3V3_AUX_R2     EN  @SCM_LIB.SCM(SCH_1):PWRGD_P3V3_AUX_R2
    5  PWRGD_P2V5_AUX_R  PGOOD  @SCM_LIB.SCM(SCH_1):PWRGD_P2V5_AUX_R
    4  PU39_ADJ         ADJ  @SCM_LIB.SCM(SCH_1):PU39_ADJ
   10  P5V_AUX          VDD  @SCM_LIB.SCM(SCH_1):P5V_AUX
    9  P3V3_AUX        VIN3  @SCM_LIB.SCM(SCH_1):P3V3_AUX
    8  P3V3_AUX        VIN2  @SCM_LIB.SCM(SCH_1):P3V3_AUX
    7  P3V3_AUX        VIN1  @SCM_LIB.SCM(SCH_1):P3V3_AUX
    3  P2V5_AUX       VOUT3  @SCM_LIB.SCM(SCH_1):P2V5_AUX
    2  P2V5_AUX       VOUT2  @SCM_LIB.SCM(SCH_1):P2V5_AUX
    1  P2V5_AUX       VOUT1  @SCM_LIB.SCM(SCH_1):P2V5_AUX
   TH  GND               EP  @SCM_LIB.SCM(SCH_1):GND

RT9059GQW  I96  PU40   [RT9059GQW-RT9059GQW,SMLF,IC,ALA]
    6  PWRGD_P2V5_AUX_R2     EN  @SCM_LIB.SCM(SCH_1):PWRGD_P2V5_AUX_R2
    5  PWRGD_P1V8_AUX_R  PGOOD  @SCM_LIB.SCM(SCH_1):PWRGD_P1V8_AUX_R
    4  PU40_ADJ         ADJ  @SCM_LIB.SCM(SCH_1):PU40_ADJ
   10  P5V_AUX          VDD  @SCM_LIB.SCM(SCH_1):P5V_AUX
    9  P3V3_AUX        VIN3  @SCM_LIB.SCM(SCH_1):P3V3_AUX
    8  P3V3_AUX        VIN2  @SCM_LIB.SCM(SCH_1):P3V3_AUX
    7  P3V3_AUX        VIN1  @SCM_LIB.SCM(SCH_1):P3V3_AUX
    3  P1V8_AUX       VOUT3  @SCM_LIB.SCM(SCH_1):P1V8_AUX
    2  P1V8_AUX       VOUT2  @SCM_LIB.SCM(SCH_1):P1V8_AUX
    1  P1V8_AUX       VOUT1  @SCM_LIB.SCM(SCH_1):P1V8_AUX
   TH  GND               EP  @SCM_LIB.SCM(SCH_1):GND

NB695GDZ  I15  PU41   [NB695GDZ-NB695GD-Z,SMLF,IC,AL0A]
    8  SW_P1V2_AUX_SW     SW  @SCM_LIB.SCM(SCH_1):SW_P1V2_AUX_SW
    1  SW_P1V2_AUX_FLT    VIN  @SCM_LIB.SCM(SCH_1):SW_P1V2_AUX_FLT
    9  SW_P1V2_AUX_BST    BST  @SCM_LIB.SCM(SCH_1):SW_P1V2_AUX_BST
   13  PWRGD_P1V2_AUX_R     PG  @SCM_LIB.SCM(SCH_1):PWRGD_P1V2_AUX_R
    6  P1V2_AUX_VCC     LP#  @SCM_LIB.SCM(SCH_1):P1V2_AUX_VCC
   10  P1V2_AUX_VCC     3V3  @SCM_LIB.SCM(SCH_1):P1V2_AUX_VCC
    7  P1V2_AUX_MODE   MODE  @SCM_LIB.SCM(SCH_1):P1V2_AUX_MODE
   12  P1V2_AUX        VOUT  @SCM_LIB.SCM(SCH_1):P1V2_AUX
    2  GND             PGND  @SCM_LIB.SCM(SCH_1):GND
    3  GND               C1  @SCM_LIB.SCM(SCH_1):GND
    4  GND               C0  @SCM_LIB.SCM(SCH_1):GND
   11  GND             AGND  @SCM_LIB.SCM(SCH_1):GND
    5  EN_P1V2_AUX       EN  @SCM_LIB.SCM(SCH_1):EN_P1V2_AUX

NB695GDZ  I15  PU42   [NB695GDZ-NB695GD-Z,SMLF,IC,AL0A]
    8  SW_P1V0_AUX_SW     SW  @SCM_LIB.SCM(SCH_1):SW_P1V0_AUX_SW
    1  SW_P1V0_AUX_FLT    VIN  @SCM_LIB.SCM(SCH_1):SW_P1V0_AUX_FLT
    9  SW_P1V0_AUX_BST    BST  @SCM_LIB.SCM(SCH_1):SW_P1V0_AUX_BST
    5  PWRGD_P1V2_AUX_R2     EN  @SCM_LIB.SCM(SCH_1):PWRGD_P1V2_AUX_R2
   13  PWRGD_P1V0_AUX_R     PG  @SCM_LIB.SCM(SCH_1):PWRGD_P1V0_AUX_R
    6  P1V0_AUX_VCC     LP#  @SCM_LIB.SCM(SCH_1):P1V0_AUX_VCC
    3  P1V0_AUX_VCC      C1  @SCM_LIB.SCM(SCH_1):P1V0_AUX_VCC
   10  P1V0_AUX_VCC     3V3  @SCM_LIB.SCM(SCH_1):P1V0_AUX_VCC
    7  P1V0_AUX_MODE   MODE  @SCM_LIB.SCM(SCH_1):P1V0_AUX_MODE
   12  P1V0_AUX        VOUT  @SCM_LIB.SCM(SCH_1):P1V0_AUX
    2  GND             PGND  @SCM_LIB.SCM(SCH_1):GND
    4  GND               C0  @SCM_LIB.SCM(SCH_1):GND
   11  GND             AGND  @SCM_LIB.SCM(SCH_1):GND

MMBT39047F  I2   Q1     [MMBT39047F-MMBT3904-7-F,SMLF,IA]
    C  RST_BMC_EXTRST_R2_N      3  @SCM_LIB.SCM(SCH_1):RST_BMC_EXTRST_R2_N
    E  GND                2  @SCM_LIB.SCM(SCH_1):GND
    B  BJT_Q3_C           1  @SCM_LIB.SCM(SCH_1):BJT_Q3_C

MOSFET_NCH_DUAL  I2   Q2     [MOSFET_NCH_DUAL-2N7002KDW,SMLFA]
    3  V_BMC_LS_DDC_SCL     D2  @SCM_LIB.SCM(SCH_1):V_BMC_LS_DDC_SCL
    4  V_BMC_DDC_SCL     S2  @SCM_LIB.SCM(SCH_1):V_BMC_DDC_SCL
    5  V_BMC_DDC_LS_GATE     G2  @SCM_LIB.SCM(SCH_1):V_BMC_DDC_LS_GATE

MOSFET_NCH_DUAL  I56  Q2     [MOSFET_NCH_DUAL-2N7002KDW,SMLFA]
    6  V_BMC_LS_DDC_SDA     D1  @SCM_LIB.SCM(SCH_1):V_BMC_LS_DDC_SDA
    1  V_BMC_DDC_SDA     S1  @SCM_LIB.SCM(SCH_1):V_BMC_DDC_SDA
    2  V_BMC_DDC_LS_GATE     G1  @SCM_LIB.SCM(SCH_1):V_BMC_DDC_LS_GATE

MMBT39047F  I4   Q3     [MMBT39047F-MMBT3904-7-F,SMLF,IA]
    E  GND                2  @SCM_LIB.SCM(SCH_1):GND
    C  BJT_Q3_C           3  @SCM_LIB.SCM(SCH_1):BJT_Q3_C
    B  BJT_Q3_B           1  @SCM_LIB.SCM(SCH_1):BJT_Q3_B

MOSFET_N_123  I157  Q7     [MOSFET_N_123-BSS123-7-F,SMLF,IA]
    2  SPI_BMC_CPLD_R_MOSI      S  @SCM_LIB.SCM(SCH_1):SPI_BMC_CPLD_R_MOSI
    3  Q7_D               D  @SCM_LIB.SCM(SCH_1):Q7_D
    1  LPC_ESPI_SEL_R1      G  @SCM_LIB.SCM(SCH_1):LPC_ESPI_SEL_R1

MOSFET_DUAL_6P  I210  Q8     [MOSFET_DUAL_6P-DMN2400UV-7,SMLA]
    4  PGPPA_BMC_AUX_L     S2  @SCM_LIB.SCM(SCH_1):PGPPA_BMC_AUX_L
    1  PGPPA_BMC_AUX_L     S1  @SCM_LIB.SCM(SCH_1):PGPPA_BMC_AUX_L
    6  P3V3_AUX          D1  @SCM_LIB.SCM(SCH_1):P3V3_AUX
    3  P1V8_AUX          D2  @SCM_LIB.SCM(SCH_1):P1V8_AUX
    5  LPC_ESPI_SEL_N     G2  @SCM_LIB.SCM(SCH_1):LPC_ESPI_SEL_N
    2  LPC_ESPI_SEL_LV5     G1  @SCM_LIB.SCM(SCH_1):LPC_ESPI_SEL_LV5

MOSFET_N_GSD  I235  Q9     [MOSFET_N_GSD-DMG6968U-7,SMLF,IA]
    G  LPC_ESPI_SEL_N   GATE  @SCM_LIB.SCM(SCH_1):LPC_ESPI_SEL_N
    D  LPC_ESPI_SEL_LV5  DRAIN  @SCM_LIB.SCM(SCH_1):LPC_ESPI_SEL_LV5
    S  GND            SOURCE  @SCM_LIB.SCM(SCH_1):GND

MOSFET_N_GSD  I227  Q10    [MOSFET_N_GSD-DMG6968U-7,SMLF,IA]
    G  LPC_ESPI_SEL_R   GATE  @SCM_LIB.SCM(SCH_1):LPC_ESPI_SEL_R
    D  LPC_ESPI_SEL_N  DRAIN  @SCM_LIB.SCM(SCH_1):LPC_ESPI_SEL_N
    S  GND            SOURCE  @SCM_LIB.SCM(SCH_1):GND

MOSFET_N_GSD  I179  Q11    [MOSFET_N_GSD-NX7002AK,SMLF,IC,A]
    S  P3V_BAT_SENSOR  SOURCE  @SCM_LIB.SCM(SCH_1):P3V_BAT_SENSOR
    D  P3V_BAT_R1     DRAIN  @SCM_LIB.SCM(SCH_1):P3V_BAT_R1
    G  BATTERY_DETECT_R   GATE  @SCM_LIB.SCM(SCH_1):BATTERY_DETECT_R

MOSFET_DUAL_6P  I105  Q12    [MOSFET_DUAL_6P-2N7002KDW,SMLF,A]
    6  PWR_LED_BUF       D1  @SCM_LIB.SCM(SCH_1):PWR_LED_BUF
    2  PWR_LED           G1  @SCM_LIB.SCM(SCH_1):PWR_LED
    5  P3V3_LED          G2  @SCM_LIB.SCM(SCH_1):P3V3_LED
    3  ID_LED_BUF        D2  @SCM_LIB.SCM(SCH_1):ID_LED_BUF
    1  GND               S1  @SCM_LIB.SCM(SCH_1):GND
    4  FM_ID_LED_N       S2  @SCM_LIB.SCM(SCH_1):FM_ID_LED_N

Q_RES  I14  R1     [Q_RES_0402LF-0,5%,1/16W,EMPTY,A]
    2  M_BMC_DDR4_MBG1      B  @SCM_LIB.SCM(SCH_1):M_BMC_DDR4_MBG1
    1  M_BMC_DDR4_BG1      A  @SCM_LIB.SCM(SCH_1):M_BMC_DDR4_BG1

Q_RES  I13  R2     [Q_RES_0402LF-0,5%,1/16W,CHIP,CA]
    1  M_BMC_DDR4_BG1      A  @SCM_LIB.SCM(SCH_1):M_BMC_DDR4_BG1
    2  GND                B  @SCM_LIB.SCM(SCH_1):GND

Q_RES  I17  R3     [Q_RES_0402LF-0,5%,1/16W,CHIP,CA]
    1  M_BMC_DDR4_ZQU      A  @SCM_LIB.SCM(SCH_1):M_BMC_DDR4_ZQU
    2  GND                B  @SCM_LIB.SCM(SCH_1):GND

Q_RES  I141  R4     [Q_RES_0402LF-1K,1%,1/16W,CHIP,A]
    1  PD_M_BMC_DDR4_PAR      A  @SCM_LIB.SCM(SCH_1):PD_M_BMC_DDR4_PAR
    2  GND                B  @SCM_LIB.SCM(SCH_1):GND

Q_RES  I142  R5     [Q_RES_0402LF-1K,1%,1/16W,CHIP,A]
    1  PD_M_BMC_DDR4_TEN      A  @SCM_LIB.SCM(SCH_1):PD_M_BMC_DDR4_TEN
    2  GND                B  @SCM_LIB.SCM(SCH_1):GND

Q_RES  I143  R6     [Q_RES_0402LF-240,1%,1/16W,CHIPA]
    1  PD_M_BMC_DDR4_ZQ      A  @SCM_LIB.SCM(SCH_1):PD_M_BMC_DDR4_ZQ
    2  GND                B  @SCM_LIB.SCM(SCH_1):GND

Q_RES  I90  R7     [Q_RES_0402LF-60.4,1%,1/16W,CHIA]
    1  M_BMC_DDR4_MCLK_DN      A  @SCM_LIB.SCM(SCH_1):M_BMC_DDR4_MCLK_DN
    2  M_BMC_DDR4_MCLK_C      B  @SCM_LIB.SCM(SCH_1):M_BMC_DDR4_MCLK_C

Q_RES  I89  R8     [Q_RES_0402LF-60.4,1%,1/16W,CHIA]
    1  M_BMC_DDR4_MCLK_DP      A  @SCM_LIB.SCM(SCH_1):M_BMC_DDR4_MCLK_DP
    2  M_BMC_DDR4_MCLK_C      B  @SCM_LIB.SCM(SCH_1):M_BMC_DDR4_MCLK_C

Q_RES  I111  R9     [Q_RES_0402LF-4.7K,5%,1/16W,CHIA]
    2  P1V2_AUX           B  @SCM_LIB.SCM(SCH_1):P1V2_AUX
    1  M_BMC_DDR4_ALERT_N      A  @SCM_LIB.SCM(SCH_1):M_BMC_DDR4_ALERT_N

Q_RES  I42  R10    [Q_RES_0402LF-10K,1%,1/16W,CHIPA]
    1  P3V3_AUX           A  @SCM_LIB.SCM(SCH_1):P3V3_AUX
    2  DP_BMC_AUX_C_N      B  @SCM_LIB.SCM(SCH_1):DP_BMC_AUX_C_N

Q_RES  I44  R11    [Q_RES_0402LF-4.7K,1%,1/16W,CHIA]
    1  P3V3_AUX           A  @SCM_LIB.SCM(SCH_1):P3V3_AUX
    2  FM_BMC_DEBUG_SW_N      B  @SCM_LIB.SCM(SCH_1):FM_BMC_DEBUG_SW_N

Q_RES  I9   R12    [Q_RES_0402LF-4.7K,5%,1/16W,CHIA]
    1  P3V3_AUX           A  @SCM_LIB.SCM(SCH_1):P3V3_AUX
    2  FRU_E0             B  @SCM_LIB.SCM(SCH_1):FRU_E0

Q_RES  I11  R13    [Q_RES_0402LF-4.7K,5%,1/16W,EMPA]
    1  P3V3_AUX           A  @SCM_LIB.SCM(SCH_1):P3V3_AUX
    2  FRU_E1             B  @SCM_LIB.SCM(SCH_1):FRU_E1

Q_RES  I14  R14    [Q_RES_0402LF-4.7K,5%,1/16W,EMPA]
    1  P3V3_AUX           A  @SCM_LIB.SCM(SCH_1):P3V3_AUX
    2  FRU_E2             B  @SCM_LIB.SCM(SCH_1):FRU_E2

Q_RES  I32  R15    [Q_RES_0402LF-1K,1%,1/16W,CHIP,A]
    1  PD_FRU_WC_N        A  @SCM_LIB.SCM(SCH_1):PD_FRU_WC_N
    2  GND                B  @SCM_LIB.SCM(SCH_1):GND

Q_RES  I75  R16    [Q_RES_0402LF-2.21K    ,1%  ,1/A]
    1  V_BMC_LS_DDC_SCL_R      A  @SCM_LIB.SCM(SCH_1):V_BMC_LS_DDC_SCL_R
    2  CRT_VCC5           B  @SCM_LIB.SCM(SCH_1):CRT_VCC5

Q_RES  I68  R17    [Q_RES_0402LF-2.21K    ,1%  ,1/A]
    1  V_BMC_LS_DDC_SDA_R      A  @SCM_LIB.SCM(SCH_1):V_BMC_LS_DDC_SDA_R
    2  CRT_VCC5           B  @SCM_LIB.SCM(SCH_1):CRT_VCC5

Q_RES  I19  R18    [Q_RES_0402LF-0,5%,1/16W,CHIP,CA]
    1  P5V_AUX            A  @SCM_LIB.SCM(SCH_1):P5V_AUX
    2  BMC_DDC_BUF_PWR      B  @SCM_LIB.SCM(SCH_1):BMC_DDC_BUF_PWR

Q_RES  I141  R19    [Q_RES_0402LF-0,5%,1/16W,CHIP,CA]
    1  V_VGAHS_R          A  @SCM_LIB.SCM(SCH_1):V_VGAHS_R
    2  V_VGAHS            B  @SCM_LIB.SCM(SCH_1):V_VGAHS

Q_RES  I140  R20    [Q_RES_0402LF-0,5%,1/16W,CHIP,CA]
    1  V_VGAVS_R          A  @SCM_LIB.SCM(SCH_1):V_VGAVS_R
    2  V_VGAVS            B  @SCM_LIB.SCM(SCH_1):V_VGAVS

Q_RES  I133  R21    [Q_RES_0402LF-0,5%,1/16W,CHIP,CA]
    1  V_DACG_R           A  @SCM_LIB.SCM(SCH_1):V_DACG_R
    2  V_DACG             B  @SCM_LIB.SCM(SCH_1):V_DACG

Q_RES  I151  R22    [Q_RES_0402LF-150,1%,1/16W,CHIPA]
    1  V_DACB_R           A  @SCM_LIB.SCM(SCH_1):V_DACB_R
    2  GND                B  @SCM_LIB.SCM(SCH_1):GND

Q_RES  I150  R23    [Q_RES_0402LF-150,1%,1/16W,CHIPA]
    1  V_DACG_R           A  @SCM_LIB.SCM(SCH_1):V_DACG_R
    2  GND                B  @SCM_LIB.SCM(SCH_1):GND

Q_RES  I134  R24    [Q_RES_0402LF-0,5%,1/16W,CHIP,CA]
    1  V_DACB_R           A  @SCM_LIB.SCM(SCH_1):V_DACB_R
    2  V_DACB             B  @SCM_LIB.SCM(SCH_1):V_DACB

Q_RES  I149  R25    [Q_RES_0402LF-150,1%,1/16W,CHIPA]
    1  V_DACR_R           A  @SCM_LIB.SCM(SCH_1):V_DACR_R
    2  GND                B  @SCM_LIB.SCM(SCH_1):GND

Q_RES  I142  R26    [Q_RES_0402LF-0,5%,1/16W,CHIP,CA]
    1  V_DACR_R           A  @SCM_LIB.SCM(SCH_1):V_DACR_R
    2  V_DACR             B  @SCM_LIB.SCM(SCH_1):V_DACR

Q_RES  I40  R27    [Q_RES_0603-0,5%,1/10W,EMPTY,TMA]
    1  P5V_AUX            A  @SCM_LIB.SCM(SCH_1):P5V_AUX
    2  CRT_VCC5           B  @SCM_LIB.SCM(SCH_1):CRT_VCC5

Q_RES  I99  R28    [Q_RES_0402LF-33       ,1%  ,1/A]
    2  V_BMC_LS_DDC_SCL_R      B  @SCM_LIB.SCM(SCH_1):V_BMC_LS_DDC_SCL_R
    1  V_BMC_LS_DDC_SCL      A  @SCM_LIB.SCM(SCH_1):V_BMC_LS_DDC_SCL

Q_RES  I34  R29    [Q_RES_0402LF-33       ,1%  ,1/A]
    2  V_BMC_LS_DDC_SDA_R      B  @SCM_LIB.SCM(SCH_1):V_BMC_LS_DDC_SDA_R
    1  V_BMC_LS_DDC_SDA      A  @SCM_LIB.SCM(SCH_1):V_BMC_LS_DDC_SDA

Q_RES  I39  R30    [Q_RES_0402LF-0,5%,1/16W,CHIP,CA]
    1  CRT_VCC5           A  @SCM_LIB.SCM(SCH_1):CRT_VCC5
    2  BMC_DDC_BUF_EN      B  @SCM_LIB.SCM(SCH_1):BMC_DDC_BUF_EN

Q_RES  I27  R31    [Q_RES_0402LF-4.7K,1%,1/16W,CHIA]
    2  V_BMC_DDC_SDA      B  @SCM_LIB.SCM(SCH_1):V_BMC_DDC_SDA
    1  P3V3_RGM           A  @SCM_LIB.SCM(SCH_1):P3V3_RGM

Q_RES  I50  R32    [Q_RES_0402LF-4.7K,1%,1/16W,CHIA]
    2  V_BMC_DDC_SCL      B  @SCM_LIB.SCM(SCH_1):V_BMC_DDC_SCL
    1  P3V3_RGM           A  @SCM_LIB.SCM(SCH_1):P3V3_RGM

Q_RES  I117  R33    [Q_RES_0402LF-33       ,1%  ,1/B]
    2  SMB_BMC_TPM_MM15_SDA      B  @SCM_LIB.SCM(SCH_1):SMB_BMC_TPM_MM15_SDA
    1  SMB_BMC_MM15_SDA      A  @SCM_LIB.SCM(SCH_1):SMB_BMC_MM15_SDA

Q_RES  I194  R34    [Q_RES_0402LF-4.7K,5%,1/16W,CHIA]
    2  RST_PLTRST_N       B  @SCM_LIB.SCM(SCH_1):RST_PLTRST_N
    1  P3V3_AUX           A  @SCM_LIB.SCM(SCH_1):P3V3_AUX

Q_RES  I58  R35    [Q_RES_0402LF-0,5%,1/16W,CHIP,CA]
    2  PWRGD_P2V5_AUX_R      B  @SCM_LIB.SCM(SCH_1):PWRGD_P2V5_AUX_R
    1  PWRGD_P2V5_AUX      A  @SCM_LIB.SCM(SCH_1):PWRGD_P2V5_AUX

Q_RES  I458  R36    [Q_RES_0402LF-33       ,1%  ,1/A]
    1  SMB_BMC_MM14_SCL      A  @SCM_LIB.SCM(SCH_1):SMB_BMC_MM14_SCL
    2  SMB_BMC_MM14_R1_SCL      B  @SCM_LIB.SCM(SCH_1):SMB_BMC_MM14_R1_SCL

Q_RES  I133  R37    [Q_RES_0402LF-33       ,1%  ,1/A]
    1  IRQ_SMI_ACTIVE_GF_N      A  @SCM_LIB.SCM(SCH_1):IRQ_SMI_ACTIVE_GF_N
    2  IRQ_SMI_ACTIVE_BMC_N      B  @SCM_LIB.SCM(SCH_1):IRQ_SMI_ACTIVE_BMC_N

Q_RES  I200  R38    [Q_RES_0402LF-4.7K,5%,1/16W,EMPA]
    1  P3V3_AUX           A  @SCM_LIB.SCM(SCH_1):P3V3_AUX
    2  FM_BMC_SUSACK_N      B  @SCM_LIB.SCM(SCH_1):FM_BMC_SUSACK_N

Q_RES  I102  R39    [Q_RES_0402LF-0,5%,1/16W,CHIP,CA]
    1  SPA_SOUT_SW_DBG      A  @SCM_LIB.SCM(SCH_1):SPA_SOUT_SW_DBG
    2  SPA_SOUT_SW_BUF      B  @SCM_LIB.SCM(SCH_1):SPA_SOUT_SW_BUF

Q_RES  I171  R40    [Q_RES_0402LF-2K,1%,1/16W,EMPTYA]
    2  PWRGD_SYS_PWROK      B  @SCM_LIB.SCM(SCH_1):PWRGD_SYS_PWROK
    1  GND                A  @SCM_LIB.SCM(SCH_1):GND

Q_RES  I225  R41    [Q_RES_0402LF-10K,1%,1/16W,CHIPA]
    1  P3V3_AUX           A  @SCM_LIB.SCM(SCH_1):P3V3_AUX
    2  LPC_ESPI_SEL       B  @SCM_LIB.SCM(SCH_1):LPC_ESPI_SEL

Q_RES  I159  R42    [Q_RES_0402LF-10K,1%,1/16W,CHIPA]
    2  Q7_D               B  @SCM_LIB.SCM(SCH_1):Q7_D
    1  P3V3_AUX           A  @SCM_LIB.SCM(SCH_1):P3V3_AUX

Q_RES  I103  R43    [Q_RES_0402LF-0,5%,1/16W,EMPTY,A]
    1  SPA_SOUT_SW_MNUSB      A  @SCM_LIB.SCM(SCH_1):SPA_SOUT_SW_MNUSB
    2  SPA_SOUT_SW_BUF      B  @SCM_LIB.SCM(SCH_1):SPA_SOUT_SW_BUF

Q_RES  I175  R44    [Q_RES_0402LF-4.7K,5%,1/16W,CHIA]
    2  SYS_PWRBTN_N       B  @SCM_LIB.SCM(SCH_1):SYS_PWRBTN_N
    1  P3V3_AUX           A  @SCM_LIB.SCM(SCH_1):P3V3_AUX

Q_RES  I176  R45    [Q_RES_0402LF-4.7K,5%,1/16W,CHIA]
    1  P3V3_AUX           A  @SCM_LIB.SCM(SCH_1):P3V3_AUX
    2  FM_THROTTLE_N      B  @SCM_LIB.SCM(SCH_1):FM_THROTTLE_N

Q_RES  I459  R46    [Q_RES_0402LF-33       ,1%  ,1/A]
    1  SMB_BMC_MM14_SDA      A  @SCM_LIB.SCM(SCH_1):SMB_BMC_MM14_SDA
    2  SMB_BMC_MM14_R1_SDA      B  @SCM_LIB.SCM(SCH_1):SMB_BMC_MM14_R1_SDA

Q_RES  I106  R47    [Q_RES_0402LF-33       ,1%  ,1/B]
    1  SMB_BMC_TPM_MM15_SCL      A  @SCM_LIB.SCM(SCH_1):SMB_BMC_TPM_MM15_SCL
    2  SMB_BMC_MM15_SCL      B  @SCM_LIB.SCM(SCH_1):SMB_BMC_MM15_SCL

Q_RES  I28  R48    [Q_RES_0402LF-33       ,1%  ,1/B]
    2  EMMC_CMD_R         B  @SCM_LIB.SCM(SCH_1):EMMC_CMD_R
    1  BMC_EMMC_CMD       A  @SCM_LIB.SCM(SCH_1):BMC_EMMC_CMD

Q_RES  I72  R49    [Q_RES_0402LF-0,5%,1/16W,CHIP,CA]
    2  PWRGD_P1V0_AUX_R2      B  @SCM_LIB.SCM(SCH_1):PWRGD_P1V0_AUX_R2
    1  PWRGD_P1V0_AUX      A  @SCM_LIB.SCM(SCH_1):PWRGD_P1V0_AUX

Q_RES  I104  R50    [Q_RES_0402LF-10K,1%,1/16W,CHIPA]
    1  P3V3_AUX           A  @SCM_LIB.SCM(SCH_1):P3V3_AUX
    2  FM_TPM_PRSNT_1_N      B  @SCM_LIB.SCM(SCH_1):FM_TPM_PRSNT_1_N

Q_RES  I317  R51    [Q_RES_0402LF-0,5%,1/16W,CHIP,CA]
    2  H_CPU0_PROCHOT_LVC1_R_N      B  @SCM_LIB.SCM(SCH_1):H_CPU0_PROCHOT_LVC1_R_N
    1  H_CPU0_PROCHOT_LVC1_N      A  @SCM_LIB.SCM(SCH_1):H_CPU0_PROCHOT_LVC1_N

Q_RES  I139  R52    [Q_RES_0402LF-33       ,1%  ,1/A]
    2  RGMII_BMC_RX_R_CTRL      B  @SCM_LIB.SCM(SCH_1):RGMII_BMC_RX_R_CTRL
    1  RGMII_BMC_RX_CTRL      A  @SCM_LIB.SCM(SCH_1):RGMII_BMC_RX_CTRL

Q_RES  I138  R53    [Q_RES_0402LF-33       ,1%  ,1/A]
    2  RGMII_BMC_R_RXD_<0>      B  @SCM_LIB.SCM(SCH_1):RGMII_BMC_R_RXD_<0>
    1  RGMII_BMC_RXD_<0>      A  @SCM_LIB.SCM(SCH_1):RGMII_BMC_RXD_<0>

Q_RES  I137  R54    [Q_RES_0402LF-33       ,1%  ,1/A]
    2  RGMII_BMC_R_RXD_<1>      B  @SCM_LIB.SCM(SCH_1):RGMII_BMC_R_RXD_<1>
    1  RGMII_BMC_RXD_<1>      A  @SCM_LIB.SCM(SCH_1):RGMII_BMC_RXD_<1>

Q_RES  I278  R55    [Q_RES_0402LF-4.7K,5%,1/16W,CHIA]
    1  P3V3_AUX           A  @SCM_LIB.SCM(SCH_1):P3V3_AUX
    2  FM_BMC_READY_R_PLD_N      B  @SCM_LIB.SCM(SCH_1):FM_BMC_READY_R_PLD_N

Q_RES  I279  R56    [Q_RES_0402LF-4.7K,5%,1/16W,CHIA]
    1  P3V3_AUX           A  @SCM_LIB.SCM(SCH_1):P3V3_AUX
    2  FM_BIOS_DEBUG_EN_R_N      B  @SCM_LIB.SCM(SCH_1):FM_BIOS_DEBUG_EN_R_N

Q_RES  I280  R57    [Q_RES_0402LF-4.7K,5%,1/16W,CHIA]
    1  P3V3_AUX           A  @SCM_LIB.SCM(SCH_1):P3V3_AUX
    2  FM_RISER1_JTAG_SEL_R_N      B  @SCM_LIB.SCM(SCH_1):FM_RISER1_JTAG_SEL_R_N

Q_RES  I281  R58    [Q_RES_0402LF-4.7K,5%,1/16W,CHIA]
    1  P3V3_AUX           A  @SCM_LIB.SCM(SCH_1):P3V3_AUX
    2  FM_RISER2_JTAG_SEL_R_N      B  @SCM_LIB.SCM(SCH_1):FM_RISER2_JTAG_SEL_R_N

Q_RES  I98  R59    [Q_RES_0402LF-10K,1%,1/16W,CHIPA]
    1  P3V3_AUX           A  @SCM_LIB.SCM(SCH_1):P3V3_AUX
    2  IRQ_TPM_SPI_N      B  @SCM_LIB.SCM(SCH_1):IRQ_TPM_SPI_N

Q_RES  I417  R60    [Q_RES_0402LF-33       ,1%  ,1/A]
    2  BMC_CPLD_GPIO_1_R1      B  @SCM_LIB.SCM(SCH_1):BMC_CPLD_GPIO_1_R1
    1  BMC_CPLD_GPIO_1      A  @SCM_LIB.SCM(SCH_1):BMC_CPLD_GPIO_1

Q_RES  I204  R61    [Q_RES_0402LF-4.7K,5%,1/16W,CHIA]
    1  P3V3_AUX           A  @SCM_LIB.SCM(SCH_1):P3V3_AUX
    2  IRQ_BMC_PCH_NMI_N      B  @SCM_LIB.SCM(SCH_1):IRQ_BMC_PCH_NMI_N

Q_RES  I350  R62    [Q_RES_0402LF-4.7K,5%,1/16W,CHIA]
    1  P3V3_AUX           A  @SCM_LIB.SCM(SCH_1):P3V3_AUX
    2  FM_PCH_BMC_THERMTRIP_N      B  @SCM_LIB.SCM(SCH_1):FM_PCH_BMC_THERMTRIP_N

Q_RES  I231  R63    [Q_RES_0402LF-0,5%,1/16W,EMPTY,A]
    1  SGPIO_CLK_1        A  @SCM_LIB.SCM(SCH_1):SGPIO_CLK_1
    2  GND                B  @SCM_LIB.SCM(SCH_1):GND

Q_RES  I233  R64    [Q_RES_0402LF-0,5%,1/16W,EMPTY,A]
    1  SGPIO_CLK_0        A  @SCM_LIB.SCM(SCH_1):SGPIO_CLK_0
    2  GND                B  @SCM_LIB.SCM(SCH_1):GND

Q_RES  I418  R65    [Q_RES_0402LF-33       ,1%  ,1/A]
    2  BMC_CPLD_GPIO_2_R1      B  @SCM_LIB.SCM(SCH_1):BMC_CPLD_GPIO_2_R1
    1  BMC_CPLD_GPIO_2      A  @SCM_LIB.SCM(SCH_1):BMC_CPLD_GPIO_2

Q_RES  I181  R66    [Q_RES_0402LF-100K,1%,1/16W,CHIA]
    2  PWRGD_PSU_AC_PWROK      B  @SCM_LIB.SCM(SCH_1):PWRGD_PSU_AC_PWROK
    1  GND                A  @SCM_LIB.SCM(SCH_1):GND

Q_RES  I121  R67    [Q_RES_0402LF-4.7K,1%,1/16W,CHIA]
    2  UART_BMC_5_TXD_BUF      B  @SCM_LIB.SCM(SCH_1):UART_BMC_5_TXD_BUF
    1  P3V3_AUX           A  @SCM_LIB.SCM(SCH_1):P3V3_AUX

Q_RES  I179  R68    [Q_RES_0402LF-4.7K,5%,1/16W,CHIA]
    1  P3V3_AUX           A  @SCM_LIB.SCM(SCH_1):P3V3_AUX
    2  IRQ_SGPIO_N        B  @SCM_LIB.SCM(SCH_1):IRQ_SGPIO_N

Q_RES  I227  R69    [Q_RES_0402LF-4.7K,5%,1/16W,CHIA]
    2  RST_SGPIO_RESET_N      B  @SCM_LIB.SCM(SCH_1):RST_SGPIO_RESET_N
    1  P3V3_AUX           A  @SCM_LIB.SCM(SCH_1):P3V3_AUX

Q_RES  I197  R70    [Q_RES_0402LF-4.7K,5%,1/16W,CHIA]
    2  PU_SPI_BMC_BOOT_MISO      B  @SCM_LIB.SCM(SCH_1):PU_SPI_BMC_BOOT_MISO
    1  P3V3_AUX           A  @SCM_LIB.SCM(SCH_1):P3V3_AUX

Q_RES  I277  R71    [Q_RES_0402LF-33       ,1%  ,1/A]
    2  SMB_BMC_MM5_SCL      B  @SCM_LIB.SCM(SCH_1):SMB_BMC_MM5_SCL
    1  SMB_BMC_MM5_R_SCL      A  @SCM_LIB.SCM(SCH_1):SMB_BMC_MM5_R_SCL

Q_RES  I123  R72    [Q_RES_0402LF-4.7K,1%,1/16W,EMPA]
    2  UART_BMC_5_RXD_BUF_R      B  @SCM_LIB.SCM(SCH_1):UART_BMC_5_RXD_BUF_R
    1  P3V3_AUX           A  @SCM_LIB.SCM(SCH_1):P3V3_AUX

Q_RES  I118  R73    [Q_RES_0402LF-1K,1%,1/16W,EMPTYA]
    2  SGPIO_LD_1         B  @SCM_LIB.SCM(SCH_1):SGPIO_LD_1
    1  P3V3_AUX           A  @SCM_LIB.SCM(SCH_1):P3V3_AUX

Q_RES  I117  R74    [Q_RES_0402LF-2K,1%,1/16W,CHIP,A]
    2  SGPIO_DI_1         B  @SCM_LIB.SCM(SCH_1):SGPIO_DI_1
    1  P3V3_AUX           A  @SCM_LIB.SCM(SCH_1):P3V3_AUX

Q_RES  I110  R75    [Q_RES_0402LF-2K,1%,1/16W,CHIP,A]
    2  SGPIO_DO_1         B  @SCM_LIB.SCM(SCH_1):SGPIO_DO_1
    1  P3V3_AUX           A  @SCM_LIB.SCM(SCH_1):P3V3_AUX

Q_RES  I230  R76    [Q_RES_0402LF-2K,1%,1/16W,CHIP,A]
    2  SGPIO_CLK_1        B  @SCM_LIB.SCM(SCH_1):SGPIO_CLK_1
    1  P3V3_AUX           A  @SCM_LIB.SCM(SCH_1):P3V3_AUX

Q_RES  I128  R77    [Q_RES_0402LF-1K,1%,1/16W,EMPTYA]
    2  SGPIO_LD_0         B  @SCM_LIB.SCM(SCH_1):SGPIO_LD_0
    1  P3V3_AUX           A  @SCM_LIB.SCM(SCH_1):P3V3_AUX

Q_RES  I129  R78    [Q_RES_0402LF-2K,1%,1/16W,CHIP,A]
    2  SGPIO_DI_0         B  @SCM_LIB.SCM(SCH_1):SGPIO_DI_0
    1  P3V3_AUX           A  @SCM_LIB.SCM(SCH_1):P3V3_AUX

Q_RES  I130  R79    [Q_RES_0402LF-2K,1%,1/16W,CHIP,A]
    2  SGPIO_DO_0         B  @SCM_LIB.SCM(SCH_1):SGPIO_DO_0
    1  P3V3_AUX           A  @SCM_LIB.SCM(SCH_1):P3V3_AUX

Q_RES  I467  R80    [Q_RES_0402LF-33       ,1%  ,1/B]
    1  SYS_PWRBTN_N       A  @SCM_LIB.SCM(SCH_1):SYS_PWRBTN_N
    2  PWR_BTN_BMC_N      B  @SCM_LIB.SCM(SCH_1):PWR_BTN_BMC_N

Q_RES  I245  R81    [Q_RES_0402LF-4.7K,5%,1/16W,CHIA]
    2  PWR_BTN_BMC_N      B  @SCM_LIB.SCM(SCH_1):PWR_BTN_BMC_N
    1  P3V3_AUX           A  @SCM_LIB.SCM(SCH_1):P3V3_AUX

Q_RES  I232  R82    [Q_RES_0402LF-2K,1%,1/16W,CHIP,A]
    2  SGPIO_CLK_0        B  @SCM_LIB.SCM(SCH_1):SGPIO_CLK_0
    1  P3V3_AUX           A  @SCM_LIB.SCM(SCH_1):P3V3_AUX

Q_RES  I105  R83    [Q_RES_0402LF-0,5%,1/16W,CHIP,CA]
    1  SPA_SIN_SW_DBG      A  @SCM_LIB.SCM(SCH_1):SPA_SIN_SW_DBG
    2  SPA_SIN_SW_BUF      B  @SCM_LIB.SCM(SCH_1):SPA_SIN_SW_BUF

Q_RES  I61  R84    [Q_RES_0402LF-33       ,1%  ,1/A]
    1  V_VGAVS_BUF_R      A  @SCM_LIB.SCM(SCH_1):V_VGAVS_BUF_R
    2  V_VGAVS_BUF        B  @SCM_LIB.SCM(SCH_1):V_VGAVS_BUF

Q_RES  I60  R85    [Q_RES_0402LF-33       ,1%  ,1/A]
    1  V_VGAHS_BUF_R      A  @SCM_LIB.SCM(SCH_1):V_VGAHS_BUF_R
    2  V_VGAHS_BUF        B  @SCM_LIB.SCM(SCH_1):V_VGAHS_BUF

Q_RES  I51  R86    [Q_RES_0402LF-0,5%,1/16W,CHIP,CA]
    2  V_BMC_DDC_LS_GATE      B  @SCM_LIB.SCM(SCH_1):V_BMC_DDC_LS_GATE
    1  P3V3_RGM           A  @SCM_LIB.SCM(SCH_1):P3V3_RGM

Q_RES  I57  R87    [Q_RES_0402LF-150,1%,1/16W,CHIPA]
    1  V_DACB_IO          A  @SCM_LIB.SCM(SCH_1):V_DACB_IO
    2  GND                B  @SCM_LIB.SCM(SCH_1):GND

Q_RES  I59  R88    [Q_RES_0402LF-150,1%,1/16W,CHIPA]
    1  V_DACG_IO          A  @SCM_LIB.SCM(SCH_1):V_DACG_IO
    2  GND                B  @SCM_LIB.SCM(SCH_1):GND

Q_RES  I65  R89    [Q_RES_0402LF-150,1%,1/16W,CHIPA]
    1  V_DACR_IO          A  @SCM_LIB.SCM(SCH_1):V_DACR_IO
    2  GND                B  @SCM_LIB.SCM(SCH_1):GND

Q_RES  I287  R90    [Q_RES_0402LF-33       ,1%  ,1/A]
    1  FM_RISER2_JTAG_SEL_R_N      A  @SCM_LIB.SCM(SCH_1):FM_RISER2_JTAG_SEL_R_N
    2  FM_RISER2_JTAG_SEL_N      B  @SCM_LIB.SCM(SCH_1):FM_RISER2_JTAG_SEL_N

Q_RES  I62  R91    [Q_RES_0402LF-2.2K ,5%,1/16W,CHA]
    2  V_BMC_LS_DDC_SDA      B  @SCM_LIB.SCM(SCH_1):V_BMC_LS_DDC_SDA
    1  CRT_VCC5           A  @SCM_LIB.SCM(SCH_1):CRT_VCC5

Q_RES  I64  R92    [Q_RES_0402LF-2.2K ,5%,1/16W,CHA]
    2  V_BMC_LS_DDC_SCL      B  @SCM_LIB.SCM(SCH_1):V_BMC_LS_DDC_SCL
    1  CRT_VCC5           A  @SCM_LIB.SCM(SCH_1):CRT_VCC5

Q_RES  I276  R93    [Q_RES_0402LF-33       ,1%  ,1/A]
    2  SMB_BMC_MM5_SDA      B  @SCM_LIB.SCM(SCH_1):SMB_BMC_MM5_SDA
    1  SMB_BMC_MM5_R_SDA      A  @SCM_LIB.SCM(SCH_1):SMB_BMC_MM5_R_SDA

Q_RES  I201  R94    [Q_RES_0402LF-100,1%,1/16W,CHIPA]
    1  PD_SPI_BMC_BOOT_MOSI      A  @SCM_LIB.SCM(SCH_1):PD_SPI_BMC_BOOT_MOSI
    2  GND                B  @SCM_LIB.SCM(SCH_1):GND

Q_RES  I106  R95    [Q_RES_0402LF-0,5%,1/16W,EMPTY,A]
    1  SPA_SIN_SW_MNUSB      A  @SCM_LIB.SCM(SCH_1):SPA_SIN_SW_MNUSB
    2  SPA_SIN_SW_BUF      B  @SCM_LIB.SCM(SCH_1):SPA_SIN_SW_BUF

Q_RES  I286  R96    [Q_RES_0402LF-33       ,1%  ,1/A]
    1  BMC_CPLD_GPIO_25_R1      A  @SCM_LIB.SCM(SCH_1):BMC_CPLD_GPIO_25_R1
    2  BMC_CPLD_GPIO_25      B  @SCM_LIB.SCM(SCH_1):BMC_CPLD_GPIO_25

Q_RES  I115  R97    [Q_RES_0402LF-0,5%,1/16W,CHIP,CA]
    1  SPI_BMC_TPM_MOSI_R      A  @SCM_LIB.SCM(SCH_1):SPI_BMC_TPM_MOSI_R
    2  SPI_BMC_MOSI_IO0_R      B  @SCM_LIB.SCM(SCH_1):SPI_BMC_MOSI_IO0_R

Q_RES  I119  R98    [Q_RES_0402LF-0,5%,1/16W,CHIP,CA]
    1  SPI_BMC_TPM_MISO_R      A  @SCM_LIB.SCM(SCH_1):SPI_BMC_TPM_MISO_R
    2  SPI_BMC_MISO_IO1_R      B  @SCM_LIB.SCM(SCH_1):SPI_BMC_MISO_IO1_R

Q_RES  I96  R99    [Q_RES_0402LF-0,5%,1/16W,CHIP,CA]
    1  PWRGD_P3V3_RGM_R      A  @SCM_LIB.SCM(SCH_1):PWRGD_P3V3_RGM_R
    2  PWRGD_P3V3_RGM      B  @SCM_LIB.SCM(SCH_1):PWRGD_P3V3_RGM

Q_RES  I118  R100   [Q_RES_0402LF-0,5%,1/16W,CHIP,CA]
    2  SPI_BMC_TPM_CS2_R_N      B  @SCM_LIB.SCM(SCH_1):SPI_BMC_TPM_CS2_R_N
    1  SPI_BMC_TPM_CS2_N_R      A  @SCM_LIB.SCM(SCH_1):SPI_BMC_TPM_CS2_N_R

Q_RES  I214  R101   [Q_RES_0402LF-4.7K,5%,1/16W,CHIA]
    2  RMII_RXER          B  @SCM_LIB.SCM(SCH_1):RMII_RXER
    1  P3V3_AUX           A  @SCM_LIB.SCM(SCH_1):P3V3_AUX

Q_RES  I118  R102   [Q_RES_0402LF-33       ,1%  ,1/A]
    2  UART_BMC_5_TXD_BUF_R      B  @SCM_LIB.SCM(SCH_1):UART_BMC_5_TXD_BUF_R
    1  UART_BMC_5_TXD_BUF      A  @SCM_LIB.SCM(SCH_1):UART_BMC_5_TXD_BUF

Q_RES  I219  R103   [Q_RES_0402LF-4.7K,5%,1/16W,CHIA]
    2  RMII_TXEN          B  @SCM_LIB.SCM(SCH_1):RMII_TXEN
    1  P3V3_AUX           A  @SCM_LIB.SCM(SCH_1):P3V3_AUX

Q_RES  I117  R104   [Q_RES_0402LF-33       ,1%  ,1/A]
    2  UART_BMC_5_RXD_R      B  @SCM_LIB.SCM(SCH_1):UART_BMC_5_RXD_R
    1  UART_BMC_5_RXD_BUF_R      A  @SCM_LIB.SCM(SCH_1):UART_BMC_5_RXD_BUF_R

Q_RES  I78  R105   [Q_RES_0402LF-10K,1%,1/16W,EMPTA]
    1  P3V3_AUX           A  @SCM_LIB.SCM(SCH_1):P3V3_AUX
    2  FM_MB_STBY_EN      B  @SCM_LIB.SCM(SCH_1):FM_MB_STBY_EN

Q_RES  I12  R106   [Q_RES_0402LF-0,5%,1/16W,CHIP,CA]
    1  RST_BMC_SRST_N      A  @SCM_LIB.SCM(SCH_1):RST_BMC_SRST_N
    2  RST_BMC_EXTRST_R2_N      B  @SCM_LIB.SCM(SCH_1):RST_BMC_EXTRST_R2_N

Q_RES  I251  R107   [Q_RES_0402LF-33       ,1%  ,1/B]
    2  SPI_BMC_BOOT_CS1_R1_N      B  @SCM_LIB.SCM(SCH_1):SPI_BMC_BOOT_CS1_R1_N
    1  QSPI_2_PLD_CS1_N      A  @SCM_LIB.SCM(SCH_1):QSPI_2_PLD_CS1_N

Q_RES  I65  R108   [Q_RES_0402LF-49.9     ,1%  ,1/A]
    1  RST_SRST_PLD_BMC_BUF_N      A  @SCM_LIB.SCM(SCH_1):RST_SRST_PLD_BMC_BUF_N
    2  RST_BMC_SRST_BUF_R_N      B  @SCM_LIB.SCM(SCH_1):RST_BMC_SRST_BUF_R_N

Q_RES  I114  R109   [Q_RES_0402LF-0,5%,1/16W,CHIP,CA]
    1  SPI_BMC_TPM_CLK_R      A  @SCM_LIB.SCM(SCH_1):SPI_BMC_TPM_CLK_R
    2  SPI_BMC_CLK_R      B  @SCM_LIB.SCM(SCH_1):SPI_BMC_CLK_R

Q_RES  I116  R110   [Q_RES_0402LF-0,5%,1/16W,CHIP,CA]
    1  RST_BMC_EXTRST_R3_N      A  @SCM_LIB.SCM(SCH_1):RST_BMC_EXTRST_R3_N
    2  RST_BMC_EXTRST_R2_N      B  @SCM_LIB.SCM(SCH_1):RST_BMC_EXTRST_R2_N

Q_RES  I266  R111   [Q_RES_0402LF-33       ,1%  ,1/A]
    1  FM_BMC_READY_R_PLD_N      A  @SCM_LIB.SCM(SCH_1):FM_BMC_READY_R_PLD_N
    2  FM_BMC_READY_PLD_N      B  @SCM_LIB.SCM(SCH_1):FM_BMC_READY_PLD_N

Q_RES  I267  R112   [Q_RES_0402LF-33       ,1%  ,1/A]
    1  FM_BIOS_DEBUG_EN_R_N      A  @SCM_LIB.SCM(SCH_1):FM_BIOS_DEBUG_EN_R_N
    2  FM_BIOS_DEBUG_EN_N      B  @SCM_LIB.SCM(SCH_1):FM_BIOS_DEBUG_EN_N

Q_RES  I105  R113   [Q_RES_0402LF-0,5%,1/16W,CHIP,CA]
    1  IRQ_TPM_SPI_N      A  @SCM_LIB.SCM(SCH_1):IRQ_TPM_SPI_N
    2  IRQ_BMC_TPM_SPI_R_N      B  @SCM_LIB.SCM(SCH_1):IRQ_BMC_TPM_SPI_R_N

Q_RES  I385  R114   [Q_RES_0402LF-33       ,1%  ,1/A]
    2  FM_MB_STBY_R_EN      B  @SCM_LIB.SCM(SCH_1):FM_MB_STBY_R_EN
    1  FM_MB_STBY_EN      A  @SCM_LIB.SCM(SCH_1):FM_MB_STBY_EN

Q_RES  I4   R115   [Q_RES_0402LF-4.7K,5%,1/16W,CHIA]
    1  PGPPA_BMC_AUX      A  @SCM_LIB.SCM(SCH_1):PGPPA_BMC_AUX
    2  ESPI_HOST_LPC_BMC_LFRAME_N      B  @SCM_LIB.SCM(SCH_1):ESPI_HOST_LPC_BMC_LFRAME_N

Q_RES  I3   R116   [Q_RES_0402LF-4.7K,5%,1/16W,CHIA]
    1  PGPPA_BMC_AUX      A  @SCM_LIB.SCM(SCH_1):PGPPA_BMC_AUX
    2  IRQ_BMC_LPC_SERIRQ_ESPI_GF      B  @SCM_LIB.SCM(SCH_1):IRQ_BMC_LPC_SERIRQ_ESPI_GF

Q_RES  I2   R117   [Q_RES_0402LF-4.7K,5%,1/16W,CHIA]
    2  RST_BMC_LPC_ESPI_N      B  @SCM_LIB.SCM(SCH_1):RST_BMC_LPC_ESPI_N
    1  PGPPA_BMC_AUX      A  @SCM_LIB.SCM(SCH_1):PGPPA_BMC_AUX

Q_RES  I53  R118   [Q_RES_0402LF-100K,1%,1/16W,EMPA]
    2  RST_PLTRST_N       B  @SCM_LIB.SCM(SCH_1):RST_PLTRST_N
    1  GND                A  @SCM_LIB.SCM(SCH_1):GND

Q_RES  I34  R119   [Q_RES_0402LF-33       ,1%  ,1/A]
    2  IRQ_ESPI_LPC_SERIRQ_ALERT0_N      B  @SCM_LIB.SCM(SCH_1):IRQ_ESPI_LPC_SERIRQ_ALERT0_N
    1  IRQ_BMC_LPC_SERIRQ_ESPI_GF      A  @SCM_LIB.SCM(SCH_1):IRQ_BMC_LPC_SERIRQ_ESPI_GF

Q_RES  I33  R120   [Q_RES_0402LF-33       ,1%  ,1/A]
    2  RST_ESPI_LPC_BMC_N      B  @SCM_LIB.SCM(SCH_1):RST_ESPI_LPC_BMC_N
    1  RST_BMC_LPC_ESPI_N      A  @SCM_LIB.SCM(SCH_1):RST_BMC_LPC_ESPI_N

Q_RES  I239  R121   [Q_RES_0402LF-33       ,1%  ,1/A]
    2  FM_CPU_RMCA_CATERR_LVT3_R_N      B  @SCM_LIB.SCM(SCH_1):FM_CPU_RMCA_CATERR_LVT3_R_N
    1  FM_CPU_MSMI_CATERR_LVT3_N      A  @SCM_LIB.SCM(SCH_1):FM_CPU_MSMI_CATERR_LVT3_N

Q_RES  I367  R122   [Q_RES_0402LF-33       ,1%  ,1/A]
    1  UART_1_SCM_TXD      A  @SCM_LIB.SCM(SCH_1):UART_1_SCM_TXD
    2  UART_1_SCM_R_TXD      B  @SCM_LIB.SCM(SCH_1):UART_1_SCM_R_TXD

Q_RES  I404  R123   [Q_RES_0402LF-33       ,1%  ,1/A]
    2  FM_TPM_PRSNT_1_R_N      B  @SCM_LIB.SCM(SCH_1):FM_TPM_PRSNT_1_R_N
    1  FM_TPM_PRSNT_1_N      A  @SCM_LIB.SCM(SCH_1):FM_TPM_PRSNT_1_N

Q_RES  I67  R124   [Q_RES_0402LF-2K,1%,1/16W,CHIP,A]
    2  RST_BMC_SRST_BUF_R_N      B  @SCM_LIB.SCM(SCH_1):RST_BMC_SRST_BUF_R_N
    1  P3V3_AUX           A  @SCM_LIB.SCM(SCH_1):P3V3_AUX

Q_RES  I69  R125   [Q_RES_0402LF-100,1%,1/16W,EMPTA]
    2  RST_BMC_SRST_N      B  @SCM_LIB.SCM(SCH_1):RST_BMC_SRST_N
    1  RST_BMC_SRST_BUF_R_N      A  @SCM_LIB.SCM(SCH_1):RST_BMC_SRST_BUF_R_N

Q_RES  I96  R126   [Q_RES_0402LF-33       ,1%  ,1/B]
    2  SMB_TPM_MM15_SDA      B  @SCM_LIB.SCM(SCH_1):SMB_TPM_MM15_SDA
    1  SMB_BMC_MM15_SDA      A  @SCM_LIB.SCM(SCH_1):SMB_BMC_MM15_SDA

Q_RES  I46  R127   [Q_RES_0402LF-240,1%,1/16W,CHIPA]
    2  IBMC_MIOZ          B  @SCM_LIB.SCM(SCH_1):IBMC_MIOZ
    1  GND                A  @SCM_LIB.SCM(SCH_1):GND

Q_RES  I100  R128   [Q_RES_0402LF-33       ,1%  ,1/A]
    2  ESPI_LPC_LAD0_IO0      B  @SCM_LIB.SCM(SCH_1):ESPI_LPC_LAD0_IO0
    1  ESPI_LPC_D0_IO0      A  @SCM_LIB.SCM(SCH_1):ESPI_LPC_D0_IO0

Q_RES  I101  R129   [Q_RES_0402LF-33       ,1%  ,1/A]
    2  ESPI_LPC_LAD1_IO1      B  @SCM_LIB.SCM(SCH_1):ESPI_LPC_LAD1_IO1
    1  ESPI_LPC_D1_IO1      A  @SCM_LIB.SCM(SCH_1):ESPI_LPC_D1_IO1

Q_RES  I102  R130   [Q_RES_0402LF-33       ,1%  ,1/A]
    2  ESPI_LPC_LAD2_IO2      B  @SCM_LIB.SCM(SCH_1):ESPI_LPC_LAD2_IO2
    1  ESPI_LPC_D2_IO2      A  @SCM_LIB.SCM(SCH_1):ESPI_LPC_D2_IO2

Q_RES  I99  R131   [Q_RES_0402LF-33       ,1%  ,1/A]
    2  ESPI_LPC_LAD3_IO3      B  @SCM_LIB.SCM(SCH_1):ESPI_LPC_LAD3_IO3
    1  ESPI_LPC_D3_IO3      A  @SCM_LIB.SCM(SCH_1):ESPI_LPC_D3_IO3

Q_RES  I98  R132   [Q_RES_0402LF-33       ,1%  ,1/A]
    2  SMB_BMC_MM1_SCL      B  @SCM_LIB.SCM(SCH_1):SMB_BMC_MM1_SCL
    1  SMB_BMC_MM1_R_SCL      A  @SCM_LIB.SCM(SCH_1):SMB_BMC_MM1_R_SCL

Q_RES  I97  R133   [Q_RES_0402LF-33       ,1%  ,1/A]
    2  SMB_BMC_MM1_SDA      B  @SCM_LIB.SCM(SCH_1):SMB_BMC_MM1_SDA
    1  SMB_BMC_MM1_R_SDA      A  @SCM_LIB.SCM(SCH_1):SMB_BMC_MM1_R_SDA

Q_RES  I70  R134   [Q_RES_0402LF-100,1%,1/16W,CHIPA]
    2  RST_RSTB_N         B  @SCM_LIB.SCM(SCH_1):RST_RSTB_N
    1  RST_BMC_SRST_BUF_R_N      A  @SCM_LIB.SCM(SCH_1):RST_BMC_SRST_BUF_R_N

Q_RES  I27  R135   [Q_RES_0402LF-0,5%,1/16W,CHIP,CA]
    1  SMB_BMC_MM16_SCL      A  @SCM_LIB.SCM(SCH_1):SMB_BMC_MM16_SCL
    2  SMB_BMC_MM16_R1_SCL      B  @SCM_LIB.SCM(SCH_1):SMB_BMC_MM16_R1_SCL

Q_RES  I95  R136   [Q_RES_0402LF-33       ,1%  ,1/B]
    1  SMB_TPM_MM15_SCL      A  @SCM_LIB.SCM(SCH_1):SMB_TPM_MM15_SCL
    2  SMB_BMC_MM15_SCL      B  @SCM_LIB.SCM(SCH_1):SMB_BMC_MM15_SCL

Q_RES  I385  R137   [Q_RES_0402LF-33       ,1%  ,1/A]
    2  SMB_BMC_MM12_SCL      B  @SCM_LIB.SCM(SCH_1):SMB_BMC_MM12_SCL
    1  SMB_BMC_MM12_R_SCL      A  @SCM_LIB.SCM(SCH_1):SMB_BMC_MM12_R_SCL

Q_RES  I92  R138   [Q_RES_0402LF-33       ,1%  ,1/A]
    2  SMB_BMC_MM4_SCL      B  @SCM_LIB.SCM(SCH_1):SMB_BMC_MM4_SCL
    1  SMB_BMC_MM4_R_SCL      A  @SCM_LIB.SCM(SCH_1):SMB_BMC_MM4_R_SCL

Q_RES  I91  R139   [Q_RES_0402LF-33       ,1%  ,1/A]
    2  SMB_BMC_MM4_SDA      B  @SCM_LIB.SCM(SCH_1):SMB_BMC_MM4_SDA
    1  SMB_BMC_MM4_R_SDA      A  @SCM_LIB.SCM(SCH_1):SMB_BMC_MM4_R_SDA

Q_RES  I200  R140   [Q_RES_0402LF-4.7K,5%,1/16W,CHIA]
    2  SPI_BMC_BOOT_MOSI      B  @SCM_LIB.SCM(SCH_1):SPI_BMC_BOOT_MOSI
    1  P3V3_AUX           A  @SCM_LIB.SCM(SCH_1):P3V3_AUX

Q_RES  I302  R141   [Q_RES_0402LF-0,5%,1/16W,CHIP,CA]
    1  PWRGD_P5V_AUX_R1      A  @SCM_LIB.SCM(SCH_1):PWRGD_P5V_AUX_R1
    2  PWRGD_P5V_AUX      B  @SCM_LIB.SCM(SCH_1):PWRGD_P5V_AUX

Q_RES  I88  R142   [Q_RES_0402LF-33       ,1%  ,1/A]
    2  SMB_BMC_MM6_SCL      B  @SCM_LIB.SCM(SCH_1):SMB_BMC_MM6_SCL
    1  SMB_BMC_MM6_R_SCL      A  @SCM_LIB.SCM(SCH_1):SMB_BMC_MM6_R_SCL

Q_RES  I89  R143   [Q_RES_0402LF-33       ,1%  ,1/A]
    2  SMB_BMC_MM6_SDA      B  @SCM_LIB.SCM(SCH_1):SMB_BMC_MM6_SDA
    1  SMB_BMC_MM6_R_SDA      A  @SCM_LIB.SCM(SCH_1):SMB_BMC_MM6_R_SDA

Q_RES  I386  R144   [Q_RES_0402LF-33       ,1%  ,1/A]
    2  SMB_BMC_MM12_SDA      B  @SCM_LIB.SCM(SCH_1):SMB_BMC_MM12_SDA
    1  SMB_BMC_MM12_R_SDA      A  @SCM_LIB.SCM(SCH_1):SMB_BMC_MM12_R_SDA

Q_RES  I154  R145   [Q_RES_0402LF-4.7K,5%,1/16W,CHIA]
    2  SMB_BMC_MM12_SCL      B  @SCM_LIB.SCM(SCH_1):SMB_BMC_MM12_SCL
    1  P3V3_AUX           A  @SCM_LIB.SCM(SCH_1):P3V3_AUX

Q_RES  I235  R146   [Q_RES_0402LF-33       ,1%  ,1/A]
    2  SMB_BMC_MM8_SCL      B  @SCM_LIB.SCM(SCH_1):SMB_BMC_MM8_SCL
    1  SMB_BMC_MM8_R_SCL      A  @SCM_LIB.SCM(SCH_1):SMB_BMC_MM8_R_SCL

Q_RES  I236  R147   [Q_RES_0402LF-33       ,1%  ,1/A]
    2  SMB_BMC_MM8_SDA      B  @SCM_LIB.SCM(SCH_1):SMB_BMC_MM8_SDA
    1  SMB_BMC_MM8_R_SDA      A  @SCM_LIB.SCM(SCH_1):SMB_BMC_MM8_R_SDA

Q_RES  I379  R148   [Q_RES_0402LF-33       ,1%  ,1/A]
    1  SGPIO_CLK_1        A  @SCM_LIB.SCM(SCH_1):SGPIO_CLK_1
    2  SGPIO_BMC_M1_CLK      B  @SCM_LIB.SCM(SCH_1):SGPIO_BMC_M1_CLK

Q_RES  I153  R149   [Q_RES_0402LF-4.7K,5%,1/16W,CHIA]
    2  SMB_BMC_MM12_SDA      B  @SCM_LIB.SCM(SCH_1):SMB_BMC_MM12_SDA
    1  P3V3_AUX           A  @SCM_LIB.SCM(SCH_1):P3V3_AUX

Q_RES  I380  R150   [Q_RES_0402LF-33       ,1%  ,1/A]
    1  SGPIO_LD_1         A  @SCM_LIB.SCM(SCH_1):SGPIO_LD_1
    2  SGPIO_BMC_M1_LD      B  @SCM_LIB.SCM(SCH_1):SGPIO_BMC_M1_LD

Q_RES  I381  R151   [Q_RES_0402LF-33       ,1%  ,1/A]
    1  SGPIO_DO_1         A  @SCM_LIB.SCM(SCH_1):SGPIO_DO_1
    2  SGPIO_BMC_M1_DO      B  @SCM_LIB.SCM(SCH_1):SGPIO_BMC_M1_DO

Q_RES  I249  R152   [Q_RES_0402LF-33       ,1%  ,1/A]
    1  SMB_BMC_MM16_SCL      A  @SCM_LIB.SCM(SCH_1):SMB_BMC_MM16_SCL
    2  SMB_BMC_MM16_R_SCL      B  @SCM_LIB.SCM(SCH_1):SMB_BMC_MM16_R_SCL

Q_RES  I248  R153   [Q_RES_0402LF-33       ,1%  ,1/A]
    1  SMB_BMC_MM16_SDA      A  @SCM_LIB.SCM(SCH_1):SMB_BMC_MM16_SDA
    2  SMB_BMC_MM16_R_SDA      B  @SCM_LIB.SCM(SCH_1):SMB_BMC_MM16_R_SDA

Q_RES  I3   R154   [Q_RES_0402LF-0,5%,1/16W,EMPTY,A]
    2  P3V3_P2V5_P1V8_RVDD      B  @SCM_LIB.SCM(SCH_1):P3V3_P2V5_P1V8_RVDD
    1  P1V8_AUX           A  @SCM_LIB.SCM(SCH_1):P1V8_AUX

Q_RES  I5   R155   [Q_RES_0402LF-0,5%,1/16W,CHIP,CA]
    2  P3V3_P2V5_P1V8_RVDD      B  @SCM_LIB.SCM(SCH_1):P3V3_P2V5_P1V8_RVDD
    1  P3V3_AUX           A  @SCM_LIB.SCM(SCH_1):P3V3_AUX

Q_RES  I4   R156   [Q_RES_0402LF-0,5%,1/16W,EMPTY,A]
    2  P3V3_P2V5_P1V8_RVDD      B  @SCM_LIB.SCM(SCH_1):P3V3_P2V5_P1V8_RVDD
    1  P2V5_AUX           A  @SCM_LIB.SCM(SCH_1):P2V5_AUX

Q_RES  I18  R157   [Q_RES_0402LF-33       ,1%  ,1/A]
    1  UART_BMC_1_TXD_R      A  @SCM_LIB.SCM(SCH_1):UART_BMC_1_TXD_R
    2  UART_BMC_1_TXD      B  @SCM_LIB.SCM(SCH_1):UART_BMC_1_TXD

Q_RES  I16  R158   [Q_RES_0402LF-33       ,1%  ,1/A]
    1  FM_DBP_CPU_PREQ_GF_R_N      A  @SCM_LIB.SCM(SCH_1):FM_DBP_CPU_PREQ_GF_R_N
    2  FM_DBP_CPU_PREQ_GF_N      B  @SCM_LIB.SCM(SCH_1):FM_DBP_CPU_PREQ_GF_N

Q_RES  I17  R159   [Q_RES_0402LF-33       ,1%  ,1/A]
    2  FM_JTAG_TCK_MUX_BMC_SEL_R1      B  @SCM_LIB.SCM(SCH_1):FM_JTAG_TCK_MUX_BMC_SEL_R1
    1  FM_JTAG_TCK_MUX_BMC_SEL      A  @SCM_LIB.SCM(SCH_1):FM_JTAG_TCK_MUX_BMC_SEL

Q_RES  I159  R160   [Q_RES_0402LF-33       ,1%  ,1/A]
    2  RST_RSMRST_R_N      B  @SCM_LIB.SCM(SCH_1):RST_RSMRST_R_N
    1  RST_RSMRST_N       A  @SCM_LIB.SCM(SCH_1):RST_RSMRST_N

Q_RES  I218  R161   [Q_RES_0402LF-4.7K,5%,1/16W,CHIA]
    2  RMII_CSRDV         B  @SCM_LIB.SCM(SCH_1):RMII_CSRDV
    1  P3V3_AUX           A  @SCM_LIB.SCM(SCH_1):P3V3_AUX

Q_RES  I245  R162   [Q_RES_0402LF-33       ,1%  ,1/A]
    1  SMB_BMC_MM15_SCL      A  @SCM_LIB.SCM(SCH_1):SMB_BMC_MM15_SCL
    2  SMB_BMC_MM15_R_SCL      B  @SCM_LIB.SCM(SCH_1):SMB_BMC_MM15_R_SCL

Q_RES  I212  R163   [Q_RES_0402LF-4.7K,5%,1/16W,CHIA]
    1  P3V3_AUX           A  @SCM_LIB.SCM(SCH_1):P3V3_AUX
    2  FM_CPU_MSMI_CATERR_LVT3_N      B  @SCM_LIB.SCM(SCH_1):FM_CPU_MSMI_CATERR_LVT3_N

Q_RES  I17  R164   [Q_RES_0402LF-10K,1%,1/16W,EMPTA]
    1  P1V8_AUX           A  @SCM_LIB.SCM(SCH_1):P1V8_AUX
    2  BMC_EMMC_RST_N      B  @SCM_LIB.SCM(SCH_1):BMC_EMMC_RST_N

Q_RES  I315  R165   [Q_RES_0402LF-33       ,1%  ,1/A]
    2  SMB_BMC_MM2_SCL      B  @SCM_LIB.SCM(SCH_1):SMB_BMC_MM2_SCL
    1  SMB_BMC_MM2_R_SCL      A  @SCM_LIB.SCM(SCH_1):SMB_BMC_MM2_R_SCL

Q_RES  I50  R166   [Q_RES_0402LF-33       ,1%  ,1/A]
    1  IRQ_BMC_CPU_NMI_R      A  @SCM_LIB.SCM(SCH_1):IRQ_BMC_CPU_NMI_R
    2  IRQ_BMC_CPU_NMI      B  @SCM_LIB.SCM(SCH_1):IRQ_BMC_CPU_NMI

Q_RES  I33  R167   [Q_RES_0402LF-330,1%,1/16W,CHIPA]
    1  P3V3_AUX           A  @SCM_LIB.SCM(SCH_1):P3V3_AUX
    2  BMC_HEARTBEAT_R_N      B  @SCM_LIB.SCM(SCH_1):BMC_HEARTBEAT_R_N

Q_RES  I268  R168   [Q_RES_0402LF-33       ,1%  ,1/A]
    2  RST_PLTRST_R_N      B  @SCM_LIB.SCM(SCH_1):RST_PLTRST_R_N
    1  RST_PLTRST_N       A  @SCM_LIB.SCM(SCH_1):RST_PLTRST_N

Q_RES  I253  R169   [Q_RES_0402LF-4.7K,5%,1/16W,CHIA]
    2  RST_PCA9548_SENSOR_N      B  @SCM_LIB.SCM(SCH_1):RST_PCA9548_SENSOR_N
    1  P3V3_AUX           A  @SCM_LIB.SCM(SCH_1):P3V3_AUX

Q_RES  I67  R170   [Q_RES_0402LF-33       ,1%  ,1/A]
    2  UART_BMC_5_TXD_R      B  @SCM_LIB.SCM(SCH_1):UART_BMC_5_TXD_R
    1  UART_BMC_5_TXD      A  @SCM_LIB.SCM(SCH_1):UART_BMC_5_TXD

Q_RES  I68  R171   [Q_RES_0402LF-33       ,1%  ,1/A]
    1  RMII_TXEN_R        A  @SCM_LIB.SCM(SCH_1):RMII_TXEN_R
    2  RMII_TXEN          B  @SCM_LIB.SCM(SCH_1):RMII_TXEN

Q_RES  I66  R172   [Q_RES_0402LF-33       ,1%  ,1/A]
    1  RMII_TXD0_R        A  @SCM_LIB.SCM(SCH_1):RMII_TXD0_R
    2  RMII_TXD0          B  @SCM_LIB.SCM(SCH_1):RMII_TXD0

Q_RES  I65  R173   [Q_RES_0402LF-33       ,1%  ,1/A]
    1  RMII_TXD1_R        A  @SCM_LIB.SCM(SCH_1):RMII_TXD1_R
    2  RMII_TXD1          B  @SCM_LIB.SCM(SCH_1):RMII_TXD1

Q_RES  I331  R174   [Q_RES_0402LF-33       ,1%  ,1/A]
    2  SPI_BMC_BIOS_ROM_R_CLK      B  @SCM_LIB.SCM(SCH_1):SPI_BMC_BIOS_ROM_R_CLK
    1  SPI_BMC_BIOS_ROM_CLK      A  @SCM_LIB.SCM(SCH_1):SPI_BMC_BIOS_ROM_CLK

Q_RES  I330  R175   [Q_RES_0402LF-33       ,1%  ,1/A]
    2  SPI_BMC_BIOS_ROM_R_MOSI      B  @SCM_LIB.SCM(SCH_1):SPI_BMC_BIOS_ROM_R_MOSI
    1  SPI_BMC_BIOS_ROM_MOSI      A  @SCM_LIB.SCM(SCH_1):SPI_BMC_BIOS_ROM_MOSI

Q_RES  I332  R176   [Q_RES_0402LF-33       ,1%  ,1/A]
    2  SPI_BMC_BIOS_ROM_R_MISO      B  @SCM_LIB.SCM(SCH_1):SPI_BMC_BIOS_ROM_R_MISO
    1  SPI_BMC_BIOS_ROM_MISO      A  @SCM_LIB.SCM(SCH_1):SPI_BMC_BIOS_ROM_MISO

Q_RES  I87  R177   [Q_RES_0402LF-33       ,1%  ,1/A]
    2  H_CPU1_PROCHOT_LVC1_R_N      B  @SCM_LIB.SCM(SCH_1):H_CPU1_PROCHOT_LVC1_R_N
    1  H_CPU1_PROCHOT_LVC1_N      A  @SCM_LIB.SCM(SCH_1):H_CPU1_PROCHOT_LVC1_N

Q_RES  I94  R178   [Q_RES_0402LF-33       ,1%  ,1/A]
    1  SPI_BMC_CLK_R      A  @SCM_LIB.SCM(SCH_1):SPI_BMC_CLK_R
    2  SPI_BMC_BOOT_CLK      B  @SCM_LIB.SCM(SCH_1):SPI_BMC_BOOT_CLK

Q_RES  I95  R179   [Q_RES_0402LF-33       ,1%  ,1/A]
    1  SPI_BMC_MOSI_IO0_R      A  @SCM_LIB.SCM(SCH_1):SPI_BMC_MOSI_IO0_R
    2  SPI_BMC_BOOT_MOSI      B  @SCM_LIB.SCM(SCH_1):SPI_BMC_BOOT_MOSI

Q_RES  I96  R180   [Q_RES_0402LF-33       ,1%  ,1/A]
    1  SPI_BMC_MISO_IO1_R      A  @SCM_LIB.SCM(SCH_1):SPI_BMC_MISO_IO1_R
    2  SPI_BMC_BOOT_MISO      B  @SCM_LIB.SCM(SCH_1):SPI_BMC_BOOT_MISO

Q_RES  I93  R181   [Q_RES_0402LF-33       ,1%  ,1/A]
    1  SPI_BMC_IO2_R      A  @SCM_LIB.SCM(SCH_1):SPI_BMC_IO2_R
    2  SPI_BMC_BOOT_IO2      B  @SCM_LIB.SCM(SCH_1):SPI_BMC_BOOT_IO2

Q_RES  I92  R182   [Q_RES_0402LF-33       ,1%  ,1/A]
    1  SPI_BMC_IO3_R      A  @SCM_LIB.SCM(SCH_1):SPI_BMC_IO3_R
    2  SPI_BMC_BOOT_IO3      B  @SCM_LIB.SCM(SCH_1):SPI_BMC_BOOT_IO3

Q_RES  I254  R183   [Q_RES_0402LF-33       ,1%  ,1/A]
    1  SPI_BMC_TPM_CS2_R_N      A  @SCM_LIB.SCM(SCH_1):SPI_BMC_TPM_CS2_R_N
    2  SPI_BMC_TPM_CS2_R1_N      B  @SCM_LIB.SCM(SCH_1):SPI_BMC_TPM_CS2_R1_N

Q_RES  I33  R184   [Q_RES_0402LF-33       ,1%  ,1/A]
    1  I3C1_SPD_SCL       A  @SCM_LIB.SCM(SCH_1):I3C1_SPD_SCL
    2  I3C1_SCL_R         B  @SCM_LIB.SCM(SCH_1):I3C1_SCL_R

Q_RES  I32  R185   [Q_RES_0402LF-33       ,1%  ,1/A]
    1  I3C1_SPD_SDA       A  @SCM_LIB.SCM(SCH_1):I3C1_SPD_SDA
    2  I3C1_SDA_R         B  @SCM_LIB.SCM(SCH_1):I3C1_SDA_R

Q_RES  I31  R186   [Q_RES_0402LF-33       ,1%  ,1/A]
    1  I3C2_SPD_SCL       A  @SCM_LIB.SCM(SCH_1):I3C2_SPD_SCL
    2  I3C2_SCL_R         B  @SCM_LIB.SCM(SCH_1):I3C2_SCL_R

Q_RES  I30  R187   [Q_RES_0402LF-33       ,1%  ,1/A]
    1  I3C2_SPD_SDA       A  @SCM_LIB.SCM(SCH_1):I3C2_SPD_SDA
    2  I3C2_SDA_R         B  @SCM_LIB.SCM(SCH_1):I3C2_SDA_R

Q_RES  I82  R188   [Q_RES_0402LF-4.7K,5%,1/16W,CHIA]
    1  P1V2_P1V0_I3C_VDDL1      A  @SCM_LIB.SCM(SCH_1):P1V2_P1V0_I3C_VDDL1
    2  I3C3_SPD_SCL       B  @SCM_LIB.SCM(SCH_1):I3C3_SPD_SCL

Q_RES  I85  R189   [Q_RES_0402LF-4.7K,5%,1/16W,CHIA]
    1  P1V2_P1V0_I3C_VDDL1      A  @SCM_LIB.SCM(SCH_1):P1V2_P1V0_I3C_VDDL1
    2  I3C3_SPD_SDA       B  @SCM_LIB.SCM(SCH_1):I3C3_SPD_SDA

Q_RES  I11  R190   [Q_RES_0402LF-4.7K,5%,1/16W,CHIA]
    1  P1V2_P1V0_I3C_VDDL1      A  @SCM_LIB.SCM(SCH_1):P1V2_P1V0_I3C_VDDL1
    2  I3C2_SPD_SCL       B  @SCM_LIB.SCM(SCH_1):I3C2_SPD_SCL

Q_RES  I10  R191   [Q_RES_0402LF-4.7K,5%,1/16W,CHIA]
    1  P1V2_P1V0_I3C_VDDL1      A  @SCM_LIB.SCM(SCH_1):P1V2_P1V0_I3C_VDDL1
    2  I3C2_SPD_SDA       B  @SCM_LIB.SCM(SCH_1):I3C2_SPD_SDA

Q_RES  I41  R192   [Q_RES_0402LF-49.9     ,1%  ,1/A]
    2  RST_BMC_SRST_BUF_R_N      B  @SCM_LIB.SCM(SCH_1):RST_BMC_SRST_BUF_R_N
    1  PWRGD_P1V0_AUX_DELAY_BUF      A  @SCM_LIB.SCM(SCH_1):PWRGD_P1V0_AUX_DELAY_BUF

Q_RES  I46  R193   [Q_RES_0402LF-100K,1%,1/16W,CHIA]
    2  SPA_SIN_SW_DBG      B  @SCM_LIB.SCM(SCH_1):SPA_SIN_SW_DBG
    1  P3V3_AUX           A  @SCM_LIB.SCM(SCH_1):P3V3_AUX

Q_RES  I86  R194   [Q_RES_0402LF-4.7K,5%,1/16W,CHIA]
    1  P1V2_P1V0_I3C_VDDL1      A  @SCM_LIB.SCM(SCH_1):P1V2_P1V0_I3C_VDDL1
    2  I3C1_SPD_SCL       B  @SCM_LIB.SCM(SCH_1):I3C1_SPD_SCL

Q_RES  I89  R195   [Q_RES_0402LF-4.7K,5%,1/16W,CHIA]
    1  P1V2_P1V0_I3C_VDDL1      A  @SCM_LIB.SCM(SCH_1):P1V2_P1V0_I3C_VDDL1
    2  I3C1_SPD_SDA       B  @SCM_LIB.SCM(SCH_1):I3C1_SPD_SDA

Q_RES  I27  R196   [Q_RES_0402LF-4.7K,5%,1/16W,CHIA]
    1  P1V2_P1V0_I3C_VDDL1      A  @SCM_LIB.SCM(SCH_1):P1V2_P1V0_I3C_VDDL1
    2  I3C4_SPD_SCL       B  @SCM_LIB.SCM(SCH_1):I3C4_SPD_SCL

Q_RES  I25  R197   [Q_RES_0402LF-4.7K,5%,1/16W,CHIA]
    1  P1V2_P1V0_I3C_VDDL1      A  @SCM_LIB.SCM(SCH_1):P1V2_P1V0_I3C_VDDL1
    2  I3C4_SPD_SDA       B  @SCM_LIB.SCM(SCH_1):I3C4_SPD_SDA

Q_RES  I44  R198   [Q_RES_0402LF-33       ,1%  ,1/A]
    2  I3C3_SPD_SCL       B  @SCM_LIB.SCM(SCH_1):I3C3_SPD_SCL
    1  I3C3_SCL_R         A  @SCM_LIB.SCM(SCH_1):I3C3_SCL_R

Q_RES  I43  R199   [Q_RES_0402LF-33       ,1%  ,1/A]
    2  I3C3_SPD_SDA       B  @SCM_LIB.SCM(SCH_1):I3C3_SPD_SDA
    1  I3C3_SDA_R         A  @SCM_LIB.SCM(SCH_1):I3C3_SDA_R

Q_RES  I41  R200   [Q_RES_0402LF-33       ,1%  ,1/A]
    2  I3C4_SPD_SCL       B  @SCM_LIB.SCM(SCH_1):I3C4_SPD_SCL
    1  I3C4_SCL_R         A  @SCM_LIB.SCM(SCH_1):I3C4_SCL_R

Q_RES  I42  R201   [Q_RES_0402LF-33       ,1%  ,1/A]
    2  I3C4_SPD_SDA       B  @SCM_LIB.SCM(SCH_1):I3C4_SPD_SDA
    1  I3C4_SDA_R         A  @SCM_LIB.SCM(SCH_1):I3C4_SDA_R

Q_RES  I125  R202   [Q_RES_0402LF-10K,0.10%,1/16W,CA]
    2  JTAG_SCM_TCK       B  @SCM_LIB.SCM(SCH_1):JTAG_SCM_TCK
    1  GND                A  @SCM_LIB.SCM(SCH_1):GND

Q_RES  I117  R203   [Q_RES_0402LF-10K,0.10%,1/16W,CA]
    1  P3V3_RGM           A  @SCM_LIB.SCM(SCH_1):P3V3_RGM
    2  JTAG_SCM_TMS       B  @SCM_LIB.SCM(SCH_1):JTAG_SCM_TMS

Q_RES  I120  R204   [Q_RES_0402LF-10K,0.10%,1/16W,CA]
    1  P3V3_RGM           A  @SCM_LIB.SCM(SCH_1):P3V3_RGM
    2  JTAG_SCM_TDI       B  @SCM_LIB.SCM(SCH_1):JTAG_SCM_TDI

Q_RES  I79  R205   [Q_RES_0402LF-20K,1%,1/16W,CHIPA]
    2  GND                B  @SCM_LIB.SCM(SCH_1):GND
    1  DEBUG_PORT_PRSNT      A  @SCM_LIB.SCM(SCH_1):DEBUG_PORT_PRSNT

Q_RES  I116  R206   [Q_RES_0402LF-47K,5%,1/16W,EMPTA]
    2  JTAG_SCM_NTRST      B  @SCM_LIB.SCM(SCH_1):JTAG_SCM_NTRST
    1  GND                A  @SCM_LIB.SCM(SCH_1):GND

Q_RES  I4   R207   [Q_RES_0402LF-0,5%,1/16W,CHIP,CA]
    2  P3V3_P1V8_SD1VDD      B  @SCM_LIB.SCM(SCH_1):P3V3_P1V8_SD1VDD
    1  P3V3_AUX           A  @SCM_LIB.SCM(SCH_1):P3V3_AUX

Q_RES  I2   R208   [Q_RES_0402LF-0,5%,1/16W,EMPTY,A]
    2  P3V3_P1V8_SD1VDD      B  @SCM_LIB.SCM(SCH_1):P3V3_P1V8_SD1VDD
    1  P1V8_AUX           A  @SCM_LIB.SCM(SCH_1):P1V8_AUX

Q_RES  I19  R209   [Q_RES_0402LF-10K,1%,1/16W,CHIPA]
    1  PECI_BMC           A  @SCM_LIB.SCM(SCH_1):PECI_BMC
    2  GND                B  @SCM_LIB.SCM(SCH_1):GND

Q_RES  I47  R210   [Q_RES_0402LF-10K,1%,1/16W,CHIPA]
    2  PD_SP_ENTEST       B  @SCM_LIB.SCM(SCH_1):PD_SP_ENTEST
    1  GND                A  @SCM_LIB.SCM(SCH_1):GND

Q_RES  I51  R211   [Q_RES_0402LF-10K,1%,1/16W,CHIPA]
    1  P3V3_RGM           A  @SCM_LIB.SCM(SCH_1):P3V3_RGM
    2  FM_BMC_SSPRST_N      B  @SCM_LIB.SCM(SCH_1):FM_BMC_SSPRST_N

Q_RES  I21  R212   [Q_RES_0402LF-4.7K,5%,1/16W,CHIA]
    2  PU_25M_BMC_CLK_EN      B  @SCM_LIB.SCM(SCH_1):PU_25M_BMC_CLK_EN
    1  P3V3_RGM           A  @SCM_LIB.SCM(SCH_1):P3V3_RGM

Q_RES  I34  R213   [Q_RES_0402LF-0,5%,1/16W,CHIP,CA]
    2  P3V3_P1V8_SD2VDD      B  @SCM_LIB.SCM(SCH_1):P3V3_P1V8_SD2VDD
    1  P3V3_AUX           A  @SCM_LIB.SCM(SCH_1):P3V3_AUX

Q_RES  I32  R214   [Q_RES_0402LF-0,5%,1/16W,EMPTY,A]
    2  P3V3_P1V8_SD2VDD      B  @SCM_LIB.SCM(SCH_1):P3V3_P1V8_SD2VDD
    1  P1V8_AUX           A  @SCM_LIB.SCM(SCH_1):P1V8_AUX

Q_RES  I42  R215   [Q_RES_0402LF-33       ,1%  ,1/A]
    1  BMC_CLK_25M_R      A  @SCM_LIB.SCM(SCH_1):BMC_CLK_25M_R
    2  BMC_CLK_25M        B  @SCM_LIB.SCM(SCH_1):BMC_CLK_25M

Q_RES  I91  R216   [Q_RES_0402LF-0,5%,1/16W,CHIP,CA]
    1  PECI_BMC_R         A  @SCM_LIB.SCM(SCH_1):PECI_BMC_R
    2  PECI_BMC           B  @SCM_LIB.SCM(SCH_1):PECI_BMC

Q_RES  I92  R217   [Q_RES_0402LF-0,5%,1/16W,CHIP,CA]
    1  USB_HOST_BMC_A_R_DP      A  @SCM_LIB.SCM(SCH_1):USB_HOST_BMC_A_R_DP
    2  USB_HOST_BMC_A_DP      B  @SCM_LIB.SCM(SCH_1):USB_HOST_BMC_A_DP

Q_RES  I93  R218   [Q_RES_0402LF-0,5%,1/16W,CHIP,CA]
    1  USB_HOST_BMC_A_R_DN      A  @SCM_LIB.SCM(SCH_1):USB_HOST_BMC_A_R_DN
    2  USB_HOST_BMC_A_DN      B  @SCM_LIB.SCM(SCH_1):USB_HOST_BMC_A_DN

Q_RES  I75  R219   [Q_RES_0402LF-100K,1%,1/16W,EMPB]
    2  GND                B  @SCM_LIB.SCM(SCH_1):GND
    1  DEBUG_PORT_UART_TX      A  @SCM_LIB.SCM(SCH_1):DEBUG_PORT_UART_TX

Q_RES  I62  R220   [Q_RES_0402LF-0,5%,1/16W,CHIP,CA]
    1  PD_INTRUDER_BMC_N      A  @SCM_LIB.SCM(SCH_1):PD_INTRUDER_BMC_N
    2  GND                B  @SCM_LIB.SCM(SCH_1):GND

Q_RES  I81  R221   [Q_RES_0402LF-33       ,1%  ,1/A]
    2  JTAG_MB_TRST_N      B  @SCM_LIB.SCM(SCH_1):JTAG_MB_TRST_N
    1  JTAG_1_BMC_TRST_R      A  @SCM_LIB.SCM(SCH_1):JTAG_1_BMC_TRST_R

Q_RES  I80  R222   [Q_RES_0402LF-33       ,1%  ,1/A]
    2  JTAG_MB_TCK        B  @SCM_LIB.SCM(SCH_1):JTAG_MB_TCK
    1  JTAG_1_BMC_TCK_R      A  @SCM_LIB.SCM(SCH_1):JTAG_1_BMC_TCK_R

Q_RES  I78  R223   [Q_RES_0402LF-33       ,1%  ,1/A]
    2  JTAG_MB_TMS        B  @SCM_LIB.SCM(SCH_1):JTAG_MB_TMS
    1  JTAG_1_BMC_TMS_R      A  @SCM_LIB.SCM(SCH_1):JTAG_1_BMC_TMS_R

Q_RES  I87  R224   [Q_RES_0402LF-33       ,1%  ,1/A]
    2  JTAG_MB_TDO        B  @SCM_LIB.SCM(SCH_1):JTAG_MB_TDO
    1  JTAG_1_BMC_TDO_R      A  @SCM_LIB.SCM(SCH_1):JTAG_1_BMC_TDO_R

Q_RES  I290  R225   [Q_RES_0402LF-33       ,1%  ,1/A]
    2  PWR_BTN_BMC_N      B  @SCM_LIB.SCM(SCH_1):PWR_BTN_BMC_N
    1  FM_PWR_BTN         A  @SCM_LIB.SCM(SCH_1):FM_PWR_BTN

Q_RES  I103  R226   [Q_RES_0402LF-10K,0.10%,1/16W,CA]
    1  P3V3_AUX           A  @SCM_LIB.SCM(SCH_1):P3V3_AUX
    2  JTAG_MB_TDI        B  @SCM_LIB.SCM(SCH_1):JTAG_MB_TDI

Q_RES  I104  R227   [Q_RES_0402LF-10K,0.10%,1/16W,CA]
    1  P3V3_AUX           A  @SCM_LIB.SCM(SCH_1):P3V3_AUX
    2  JTAG_MB_TMS        B  @SCM_LIB.SCM(SCH_1):JTAG_MB_TMS

Q_RES  I107  R228   [Q_RES_0402LF-10K,0.10%,1/16W,CA]
    2  JTAG_MB_TCK        B  @SCM_LIB.SCM(SCH_1):JTAG_MB_TCK
    1  GND                A  @SCM_LIB.SCM(SCH_1):GND

Q_RES  I106  R229   [Q_RES_0402LF-4.7K,1%,1/16W,EMPA]
    2  JTAG_MB_TRST_N      B  @SCM_LIB.SCM(SCH_1):JTAG_MB_TRST_N
    1  GND                A  @SCM_LIB.SCM(SCH_1):GND

Q_RES  I105  R230   [Q_RES_0402LF-10K,0.10%,1/16W,CA]
    1  P3V3_AUX           A  @SCM_LIB.SCM(SCH_1):P3V3_AUX
    2  JTAG_MB_TDO        B  @SCM_LIB.SCM(SCH_1):JTAG_MB_TDO

Q_RES  I131  R231   [Q_RES_0402LF-0,5%,1/16W,CHIP,CA]
    2  P3V3_P1V8_I2C_I3C      B  @SCM_LIB.SCM(SCH_1):P3V3_P1V8_I2C_I3C
    1  P3V3_AUX           A  @SCM_LIB.SCM(SCH_1):P3V3_AUX

Q_RES  I136  R232   [Q_RES_0402LF-0,5%,1/16W,EMPTY,A]
    2  P3V3_P1V8_I2C_I3C      B  @SCM_LIB.SCM(SCH_1):P3V3_P1V8_I2C_I3C
    1  P1V8_AUX           A  @SCM_LIB.SCM(SCH_1):P1V8_AUX

Q_RES  I87  R233   [Q_RES_0402LF -49.9K,1%,1/16W ,A]
    1  GND                A  @SCM_LIB.SCM(SCH_1):GND
    2  A_BMC_ADCREXT0      B  @SCM_LIB.SCM(SCH_1):A_BMC_ADCREXT0

Q_RES  I86  R234   [Q_RES_0402LF -49.9K,1%,1/16W ,A]
    1  GND                A  @SCM_LIB.SCM(SCH_1):GND
    2  A_BMC_ADCREXT1      B  @SCM_LIB.SCM(SCH_1):A_BMC_ADCREXT1

Q_RES  I187  R235   [Q_RES_0402LF-2.74K,1%,1/16W,CHA]
    1  GND                A  @SCM_LIB.SCM(SCH_1):GND
    2  A_BMC_DACREST      B  @SCM_LIB.SCM(SCH_1):A_BMC_DACREST

Q_RES  I244  R236   [Q_RES_0402LF-33       ,1%  ,1/A]
    1  SMB_BMC_MM15_SDA      A  @SCM_LIB.SCM(SCH_1):SMB_BMC_MM15_SDA
    2  SMB_BMC_MM15_R_SDA      B  @SCM_LIB.SCM(SCH_1):SMB_BMC_MM15_R_SDA

Q_RES  I156  R237   [Q_RES_0402LF-33       ,1%  ,1/A]
    2  FM_DBP_BMC_PRDY_R_N      B  @SCM_LIB.SCM(SCH_1):FM_DBP_BMC_PRDY_R_N
    1  FM_DBP_BMC_PRDY_N      A  @SCM_LIB.SCM(SCH_1):FM_DBP_BMC_PRDY_N

Q_RES  I184  R238   [Q_RES_0402LF-4.7K,5%,1/16W,CHIA]
    2  SPI_BMC_TPM_CS2_R_N      B  @SCM_LIB.SCM(SCH_1):SPI_BMC_TPM_CS2_R_N
    1  P3V3_AUX           A  @SCM_LIB.SCM(SCH_1):P3V3_AUX

Q_RES  I185  R239   [Q_RES_0402LF-4.7K,5%,1/16W,CHIA]
    2  PU_BMC_FWSPIABR_N      B  @SCM_LIB.SCM(SCH_1):PU_BMC_FWSPIABR_N
    1  P3V3_AUX           A  @SCM_LIB.SCM(SCH_1):P3V3_AUX

Q_RES  I187  R240   [Q_RES_0402LF-4.7K,5%,1/16W,CHIA]
    2  PU_FWSPIWP_N       B  @SCM_LIB.SCM(SCH_1):PU_FWSPIWP_N
    1  P3V3_AUX           A  @SCM_LIB.SCM(SCH_1):P3V3_AUX

Q_RES  I186  R241   [Q_RES_0402LF-4.7K,5%,1/16W,CHIA]
    2  PU_SPI1ABR         B  @SCM_LIB.SCM(SCH_1):PU_SPI1ABR
    1  P3V3_AUX           A  @SCM_LIB.SCM(SCH_1):P3V3_AUX

Q_RES  I300  R242   [Q_RES_0402LF-33       ,1%  ,1/A]
    1  FM_BMC_CPU_FBRK_OUT_R_N      A  @SCM_LIB.SCM(SCH_1):FM_BMC_CPU_FBRK_OUT_R_N
    2  FM_BMC_CPU_FBRK_OUT_N      B  @SCM_LIB.SCM(SCH_1):FM_BMC_CPU_FBRK_OUT_N

Q_RES  I293  R243   [Q_RES_0402LF-33       ,1%  ,1/A]
    2  PWRGD_PSU_AC_PWROK_R      B  @SCM_LIB.SCM(SCH_1):PWRGD_PSU_AC_PWROK_R
    1  PWRGD_PSU_AC_PWROK      A  @SCM_LIB.SCM(SCH_1):PWRGD_PSU_AC_PWROK

Q_RES  I147  R244   [Q_RES_0402LF-4.7K,5%,1/16W,CHIA]
    2  SMB_BMC_MM1_SCL      B  @SCM_LIB.SCM(SCH_1):SMB_BMC_MM1_SCL
    1  P3V3_AUX           A  @SCM_LIB.SCM(SCH_1):P3V3_AUX

Q_RES  I146  R245   [Q_RES_0402LF-4.7K,5%,1/16W,CHIA]
    2  SMB_BMC_MM1_SDA      B  @SCM_LIB.SCM(SCH_1):SMB_BMC_MM1_SDA
    1  P3V3_AUX           A  @SCM_LIB.SCM(SCH_1):P3V3_AUX

Q_RES  I145  R246   [Q_RES_0402LF-4.7K,5%,1/16W,CHIA]
    2  SMB_BMC_MM2_SCL      B  @SCM_LIB.SCM(SCH_1):SMB_BMC_MM2_SCL
    1  P3V3_AUX           A  @SCM_LIB.SCM(SCH_1):P3V3_AUX

Q_RES  I109  R247   [Q_RES_0402LF-4.7K,5%,1/16W,CHIA]
    2  SMB_BMC_MM2_SDA      B  @SCM_LIB.SCM(SCH_1):SMB_BMC_MM2_SDA
    1  P3V3_AUX           A  @SCM_LIB.SCM(SCH_1):P3V3_AUX

Q_RES  I107  R248   [Q_RES_0402LF-4.7K,5%,1/16W,CHIA]
    2  SMB_BMC_MM3_SCL      B  @SCM_LIB.SCM(SCH_1):SMB_BMC_MM3_SCL
    1  P3V3_AUX           A  @SCM_LIB.SCM(SCH_1):P3V3_AUX

Q_RES  I108  R249   [Q_RES_0402LF-4.7K,5%,1/16W,CHIA]
    2  SMB_BMC_MM3_SDA      B  @SCM_LIB.SCM(SCH_1):SMB_BMC_MM3_SDA
    1  P3V3_AUX           A  @SCM_LIB.SCM(SCH_1):P3V3_AUX

Q_RES  I106  R250   [Q_RES_0402LF-4.7K,5%,1/16W,CHIA]
    2  SMB_BMC_MM4_SCL      B  @SCM_LIB.SCM(SCH_1):SMB_BMC_MM4_SCL
    1  P3V3_AUX           A  @SCM_LIB.SCM(SCH_1):P3V3_AUX

Q_RES  I104  R251   [Q_RES_0402LF-4.7K,5%,1/16W,CHIA]
    2  SMB_BMC_MM4_SDA      B  @SCM_LIB.SCM(SCH_1):SMB_BMC_MM4_SDA
    1  P3V3_AUX           A  @SCM_LIB.SCM(SCH_1):P3V3_AUX

Q_RES  I105  R252   [Q_RES_0402LF-4.7K,5%,1/16W,CHIA]
    2  SMB_BMC_MM5_R_SCL      B  @SCM_LIB.SCM(SCH_1):SMB_BMC_MM5_R_SCL
    1  P3V3_AUX           A  @SCM_LIB.SCM(SCH_1):P3V3_AUX

Q_RES  I103  R253   [Q_RES_0402LF-4.7K,5%,1/16W,CHIA]
    2  SMB_BMC_MM5_R_SDA      B  @SCM_LIB.SCM(SCH_1):SMB_BMC_MM5_R_SDA
    1  P3V3_AUX           A  @SCM_LIB.SCM(SCH_1):P3V3_AUX

Q_RES  I101  R254   [Q_RES_0402LF-4.7K,5%,1/16W,CHIA]
    2  SMB_BMC_MM6_SCL      B  @SCM_LIB.SCM(SCH_1):SMB_BMC_MM6_SCL
    1  P3V3_AUX           A  @SCM_LIB.SCM(SCH_1):P3V3_AUX

Q_RES  I102  R255   [Q_RES_0402LF-4.7K,5%,1/16W,CHIA]
    2  SMB_BMC_MM6_SDA      B  @SCM_LIB.SCM(SCH_1):SMB_BMC_MM6_SDA
    1  P3V3_AUX           A  @SCM_LIB.SCM(SCH_1):P3V3_AUX

Q_RES  I100  R256   [Q_RES_0402LF-4.7K,5%,1/16W,CHIA]
    2  SMB_BMC_MM7_R_SCL      B  @SCM_LIB.SCM(SCH_1):SMB_BMC_MM7_R_SCL
    1  P3V3_AUX           A  @SCM_LIB.SCM(SCH_1):P3V3_AUX

Q_RES  I99  R257   [Q_RES_0402LF-4.7K,5%,1/16W,CHIA]
    2  SMB_BMC_MM7_R_SDA      B  @SCM_LIB.SCM(SCH_1):SMB_BMC_MM7_R_SDA
    1  P3V3_AUX           A  @SCM_LIB.SCM(SCH_1):P3V3_AUX

Q_RES  I98  R258   [Q_RES_0402LF-4.7K,5%,1/16W,CHIA]
    2  SMB_BMC_MM8_SCL      B  @SCM_LIB.SCM(SCH_1):SMB_BMC_MM8_SCL
    1  P3V3_AUX           A  @SCM_LIB.SCM(SCH_1):P3V3_AUX

Q_RES  I96  R259   [Q_RES_0402LF-4.7K,5%,1/16W,CHIA]
    2  SMB_BMC_MM8_SDA      B  @SCM_LIB.SCM(SCH_1):SMB_BMC_MM8_SDA
    1  P3V3_AUX           A  @SCM_LIB.SCM(SCH_1):P3V3_AUX

Q_RES  I97  R260   [Q_RES_0402LF-4.7K,5%,1/16W,CHIA]
    2  SMB_BMC_MM9_SCL      B  @SCM_LIB.SCM(SCH_1):SMB_BMC_MM9_SCL
    1  P3V3_AUX           A  @SCM_LIB.SCM(SCH_1):P3V3_AUX

Q_RES  I94  R261   [Q_RES_0402LF-4.7K,5%,1/16W,CHIA]
    2  SMB_BMC_MM9_SDA      B  @SCM_LIB.SCM(SCH_1):SMB_BMC_MM9_SDA
    1  P3V3_AUX           A  @SCM_LIB.SCM(SCH_1):P3V3_AUX

Q_RES  I93  R262   [Q_RES_0402LF-4.7K,5%,1/16W,CHIA]
    2  SMB_BMC_MM10_SCL      B  @SCM_LIB.SCM(SCH_1):SMB_BMC_MM10_SCL
    1  P3V3_AUX           A  @SCM_LIB.SCM(SCH_1):P3V3_AUX

Q_RES  I316  R263   [Q_RES_0402LF-33       ,1%  ,1/A]
    2  RST_MB_STBY_R_N      B  @SCM_LIB.SCM(SCH_1):RST_MB_STBY_R_N
    1  RST_MB_STBY_N      A  @SCM_LIB.SCM(SCH_1):RST_MB_STBY_N

Q_RES  I89  R264   [Q_RES_0402LF-4.7K,5%,1/16W,CHIA]
    2  SMB_BMC_MM16_SCL      B  @SCM_LIB.SCM(SCH_1):SMB_BMC_MM16_SCL
    1  P3V3_AUX           A  @SCM_LIB.SCM(SCH_1):P3V3_AUX

Q_RES  I88  R265   [Q_RES_0402LF-4.7K,5%,1/16W,CHIA]
    2  SMB_BMC_MM16_SDA      B  @SCM_LIB.SCM(SCH_1):SMB_BMC_MM16_SDA
    1  P3V3_AUX           A  @SCM_LIB.SCM(SCH_1):P3V3_AUX

Q_RES  I95  R266   [Q_RES_0402LF-4.7K,5%,1/16W,EMPA]
    1  P3V3_AUX           A  @SCM_LIB.SCM(SCH_1):P3V3_AUX
    2  FM_ME_BT_DONE      B  @SCM_LIB.SCM(SCH_1):FM_ME_BT_DONE

Q_RES  I85  R267   [Q_RES_0402LF-4.7K,5%,1/16W,EMPA]
    2  VOL_SEN_ALERT_R      B  @SCM_LIB.SCM(SCH_1):VOL_SEN_ALERT_R
    1  P3V3_AUX           A  @SCM_LIB.SCM(SCH_1):P3V3_AUX

Q_RES  I86  R268   [Q_RES_0402LF-4.7K,5%,1/16W,CHIA]
    2  SMB_BMC_ALERT3_N      B  @SCM_LIB.SCM(SCH_1):SMB_BMC_ALERT3_N
    1  P3V3_AUX           A  @SCM_LIB.SCM(SCH_1):P3V3_AUX

Q_RES  I84  R269   [Q_RES_0402LF-4.7K,5%,1/16W,CHIA]
    2  SMB_BMC_ALERT4_N      B  @SCM_LIB.SCM(SCH_1):SMB_BMC_ALERT4_N
    1  P3V3_AUX           A  @SCM_LIB.SCM(SCH_1):P3V3_AUX

Q_RES  I387  R270   [Q_RES_0402LF-33       ,1%  ,1/A]
    2  FM_CPU_MSMI_CATERR_LVT3_PLD_N      B  @SCM_LIB.SCM(SCH_1):FM_CPU_MSMI_CATERR_LVT3_PLD_N
    1  FM_CPU_MSMI_CATERR_LVT3_N      A  @SCM_LIB.SCM(SCH_1):FM_CPU_MSMI_CATERR_LVT3_N

Q_RES  I365  R271   [Q_RES_0402LF-0,5%,1/16W,CHIP,CA]
    2  RST_BMC_SELF_HW_R2      B  @SCM_LIB.SCM(SCH_1):RST_BMC_SELF_HW_R2
    1  RST_BMC_SELF_HW      A  @SCM_LIB.SCM(SCH_1):RST_BMC_SELF_HW

Q_RES  I331  R272   [Q_RES_0402LF-0,5%,1/16W,CHIP,CA]
    1  SMB_BMC_MM15_SCL      A  @SCM_LIB.SCM(SCH_1):SMB_BMC_MM15_SCL
    2  SMB_BMC_MM15_R3_SCL      B  @SCM_LIB.SCM(SCH_1):SMB_BMC_MM15_R3_SCL

Q_RES  I16  R274   [Q_RES_0402LF-100K,1%,1/16W,EMPB]
    1  P3V3_AUX           A  @SCM_LIB.SCM(SCH_1):P3V3_AUX
    2  DEBUG_PORT_UART_RX      B  @SCM_LIB.SCM(SCH_1):DEBUG_PORT_UART_RX

Q_RES  I99  R275   [Q_RES_0402LF-0,5%,1/16W,CHIP,CA]
    2  PWRGD_P1V8_AUX_R      B  @SCM_LIB.SCM(SCH_1):PWRGD_P1V8_AUX_R
    1  PWRGD_P1V8_AUX      A  @SCM_LIB.SCM(SCH_1):PWRGD_P1V8_AUX

Q_RES  I50  R276   [Q_RES_0402LF-0,5%,1/16W,CHIP,CA]
    1  PWRGD_P1V2_AUX_R      A  @SCM_LIB.SCM(SCH_1):PWRGD_P1V2_AUX_R
    2  PWRGD_P1V2_AUX      B  @SCM_LIB.SCM(SCH_1):PWRGD_P1V2_AUX

Q_RES  I54  R277   [Q_RES_0402LF-0,5%,1/16W,CHIP,CA]
    1  PWRGD_P1V0_AUX_R      A  @SCM_LIB.SCM(SCH_1):PWRGD_P1V0_AUX_R
    2  PWRGD_P1V0_AUX      B  @SCM_LIB.SCM(SCH_1):PWRGD_P1V0_AUX

Q_RES  I101  R278   [Q_RES_0402LF-0,5%,1/16W,EMPTY,A]
    2  P1V2_P1V0_I3C_VDDL1      B  @SCM_LIB.SCM(SCH_1):P1V2_P1V0_I3C_VDDL1
    1  P1V2_AUX           A  @SCM_LIB.SCM(SCH_1):P1V2_AUX

Q_RES  I95  R279   [Q_RES_0402LF-0,5%,1/16W,CHIP,CA]
    2  P1V2_P1V0_I3C_VDDL1      B  @SCM_LIB.SCM(SCH_1):P1V2_P1V0_I3C_VDDL1
    1  P1V0_AUX           A  @SCM_LIB.SCM(SCH_1):P1V0_AUX

Q_RES  I94  R280   [Q_RES_0402LF-0,5%,1/16W,EMPTY,A]
    2  P1V2_P1V0_I3C_VDDL2      B  @SCM_LIB.SCM(SCH_1):P1V2_P1V0_I3C_VDDL2
    1  P1V2_AUX           A  @SCM_LIB.SCM(SCH_1):P1V2_AUX

Q_RES  I92  R281   [Q_RES_0402LF-0,5%,1/16W,CHIP,CA]
    2  P1V2_P1V0_I3C_VDDL2      B  @SCM_LIB.SCM(SCH_1):P1V2_P1V0_I3C_VDDL2
    1  P1V0_AUX           A  @SCM_LIB.SCM(SCH_1):P1V0_AUX

Q_RES  I78  R282   [Q_RES_0402LF-0,5%,1/16W,CHIP,CA]
    2  RST_BMC_SELF_HW_R3      B  @SCM_LIB.SCM(SCH_1):RST_BMC_SELF_HW_R3
    1  RST_BMC_HW         A  @SCM_LIB.SCM(SCH_1):RST_BMC_HW

Q_RES  I31  R283   [Q_RES_0402LF-1.5K,1%,1/16W,EMPA]
    2  RGMII_BMC_MDC_R      B  @SCM_LIB.SCM(SCH_1):RGMII_BMC_MDC_R
    1  P3V3_AUX_DVDD      A  @SCM_LIB.SCM(SCH_1):P3V3_AUX_DVDD

Q_RES  I27  R284   [Q_RES_0402LF-4.7K,1%,1/16W,EMPA]
    2  RST_RSTB_N         B  @SCM_LIB.SCM(SCH_1):RST_RSTB_N
    1  P3V3_AUX_DVDD      A  @SCM_LIB.SCM(SCH_1):P3V3_AUX_DVDD

Q_RES  I29  R285   [Q_RES_0402LF-1.5K,1%,1/16W,CHIA]
    2  RGMII_BMC_MDIO_R      B  @SCM_LIB.SCM(SCH_1):RGMII_BMC_MDIO_R
    1  P3V3_AUX_DVDD      A  @SCM_LIB.SCM(SCH_1):P3V3_AUX_DVDD

Q_RES  I203  R286   [Q_RES_0402LF-22,1%,1/16W,CHIP,A]
    1  XTAL_PHY_XI_R      A  @SCM_LIB.SCM(SCH_1):XTAL_PHY_XI_R
    2  XTAL_PHY_XI        B  @SCM_LIB.SCM(SCH_1):XTAL_PHY_XI

Q_RES  I5   R287   [Q_RES_0402LF-499,1%,1/16W,CHIPA]
    2  RST_BMC_EXTRST_R2_N      B  @SCM_LIB.SCM(SCH_1):RST_BMC_EXTRST_R2_N
    1  P3V3_AUX           A  @SCM_LIB.SCM(SCH_1):P3V3_AUX

Q_RES  I200  R288   [Q_RES_0402LF-22,1%,1/16W,CHIP,A]
    1  XTAL_PHY_XO_R      A  @SCM_LIB.SCM(SCH_1):XTAL_PHY_XO_R
    2  XTAL_PHY_XO        B  @SCM_LIB.SCM(SCH_1):XTAL_PHY_XO

Q_RES  I7   R289   [Q_RES_0402LF-10K,1%,1/16W,CHIPA]
    1  P3V3_AUX           A  @SCM_LIB.SCM(SCH_1):P3V3_AUX
    2  BJT_Q3_C           B  @SCM_LIB.SCM(SCH_1):BJT_Q3_C

Q_RES  I8   R290   [Q_RES_0402LF-47K,1%,1/16W,CHIPA]
    2  RST_BMC_EXTRST_R1_N      B  @SCM_LIB.SCM(SCH_1):RST_BMC_EXTRST_R1_N
    1  BJT_Q3_B           A  @SCM_LIB.SCM(SCH_1):BJT_Q3_B

Q_RES  I9   R291   [Q_RES_0402LF-4.7K,1%,1/16W,CHIA]
    2  RST_BMC_EXTRST_R1_N      B  @SCM_LIB.SCM(SCH_1):RST_BMC_EXTRST_R1_N
    1  P3V3_AUX           A  @SCM_LIB.SCM(SCH_1):P3V3_AUX

Q_RES  I51  R292   [Q_RES_0402LF-0,5%,1/16W,CHIP,CA]
    1  PWRGD_P5V_AUX_R      A  @SCM_LIB.SCM(SCH_1):PWRGD_P5V_AUX_R
    2  PWRGD_P5V_AUX      B  @SCM_LIB.SCM(SCH_1):PWRGD_P5V_AUX

Q_RES  I95  R293   [Q_RES_0402LF-0,5%,1/16W,CHIP,CA]
    1  PWRGD_P3V3_AUX_R      A  @SCM_LIB.SCM(SCH_1):PWRGD_P3V3_AUX_R
    2  PWRGD_P3V3_AUX      B  @SCM_LIB.SCM(SCH_1):PWRGD_P3V3_AUX

Q_RES  I28  R294   [Q_RES_0402LF-0,5%,1/16W,CHIP,CA]
    1  SMB_BMC_MM16_SDA      A  @SCM_LIB.SCM(SCH_1):SMB_BMC_MM16_SDA
    2  SMB_BMC_MM16_R1_SDA      B  @SCM_LIB.SCM(SCH_1):SMB_BMC_MM16_R1_SDA

Q_RES  I8   R295   [Q_RES_0402LF-10K,1%,1/16W,EMPTA]
    1  P3V3_AUX           A  @SCM_LIB.SCM(SCH_1):P3V3_AUX
    2  DEBUG_PORT_PRSNT_BUF_EN      B  @SCM_LIB.SCM(SCH_1):DEBUG_PORT_PRSNT_BUF_EN

Q_RES  I11  R296   [Q_RES_0402LF-100K,1%,1/16W,EMPB]
    2  GND                B  @SCM_LIB.SCM(SCH_1):GND
    1  DEBUG_PORT_PRSNT_BUF_EN      A  @SCM_LIB.SCM(SCH_1):DEBUG_PORT_PRSNT_BUF_EN

Q_RES  I90  R297   [Q_RES_0402LF-0,5%,1/16W,CHIP,CA]
    2  RGMII_BMC_RX_CLK_R      B  @SCM_LIB.SCM(SCH_1):RGMII_BMC_RX_CLK_R
    1  RGMII_BMC_RX_CLK      A  @SCM_LIB.SCM(SCH_1):RGMII_BMC_RX_CLK

Q_RES  I31  R298   [Q_RES_0402LF-4.7K,1%,1/16W,CHIA]
    2  SMB_DEBUG_AUX_LVC3_USB_R1_SCL      B  @SCM_LIB.SCM(SCH_1):SMB_DEBUG_AUX_LVC3_USB_R1_SCL
    1  P3V3_AUX           A  @SCM_LIB.SCM(SCH_1):P3V3_AUX

Q_RES  I32  R299   [Q_RES_0402LF-4.7K,1%,1/16W,CHIA]
    2  SMB_DEBUG_AUX_LVC3_USB_R1_SDA      B  @SCM_LIB.SCM(SCH_1):SMB_DEBUG_AUX_LVC3_USB_R1_SDA
    1  P3V3_AUX           A  @SCM_LIB.SCM(SCH_1):P3V3_AUX

Q_RES  I23  R300   [Q_RES_0402LF-0,5%,1/16W,CHIP,CA]
    2  SMB_DEBUG_AUX_LVC3_USB_SCL      B  @SCM_LIB.SCM(SCH_1):SMB_DEBUG_AUX_LVC3_USB_SCL
    1  SMB_DEBUG_AUX_LVC3_USB_R1_SCL      A  @SCM_LIB.SCM(SCH_1):SMB_DEBUG_AUX_LVC3_USB_R1_SCL

Q_RES  I2   R301   [Q_RES_0402LF-0,5%,1/16W,EMPTY,A]
    2  PU_RJ45_ESD        B  @SCM_LIB.SCM(SCH_1):PU_RJ45_ESD
    1  P3V3_AUX_RJ45      A  @SCM_LIB.SCM(SCH_1):P3V3_AUX_RJ45

Q_RES  I24  R302   [Q_RES_0402LF-0,5%,1/16W,CHIP,CA]
    2  SMB_DEBUG_AUX_LVC3_USB_SDA      B  @SCM_LIB.SCM(SCH_1):SMB_DEBUG_AUX_LVC3_USB_SDA
    1  SMB_DEBUG_AUX_LVC3_USB_R1_SDA      A  @SCM_LIB.SCM(SCH_1):SMB_DEBUG_AUX_LVC3_USB_R1_SDA

Q_RES  I335  R303   [Q_RES_0402LF-0,5%,1/16W,CHIP,CA]
    1  SMB_BMC_MM15_SDA      A  @SCM_LIB.SCM(SCH_1):SMB_BMC_MM15_SDA
    2  SMB_BMC_MM15_R3_SDA      B  @SCM_LIB.SCM(SCH_1):SMB_BMC_MM15_R3_SDA

Q_RES  I80  R304   [Q_RES_0402LF-220,5%,1/16W,CHIPA]
    1  PHY_LED3           A  @SCM_LIB.SCM(SCH_1):PHY_LED3
    2  LED3_AD0_ACT       B  @SCM_LIB.SCM(SCH_1):LED3_AD0_ACT

Q_RES  I72  R305   [Q_RES_0402LF-220,5%,1/16W,CHIPA]
    1  PHY_LED1           A  @SCM_LIB.SCM(SCH_1):PHY_LED1
    2  LED1_AD1_100M      B  @SCM_LIB.SCM(SCH_1):LED1_AD1_100M

Q_RES  I71  R306   [Q_RES_0402LF-220,5%,1/16W,CHIPA]
    1  PHY_LED2           A  @SCM_LIB.SCM(SCH_1):PHY_LED2
    2  LED2_RXDELAY_1G      B  @SCM_LIB.SCM(SCH_1):LED2_RXDELAY_1G

Q_RES  I20  R307   [Q_RES_0402LF-4.7K,1%,1/16W,CHIA]
    2  PHY_LED1           B  @SCM_LIB.SCM(SCH_1):PHY_LED1
    1  P3V3_AUX_DVDD      A  @SCM_LIB.SCM(SCH_1):P3V3_AUX_DVDD

Q_RES  I16  R308   [Q_RES_0402LF-4.7K,1%,1/16W,EMPA]
    1  PHY_LED1           A  @SCM_LIB.SCM(SCH_1):PHY_LED1
    2  GND                B  @SCM_LIB.SCM(SCH_1):GND

Q_RES  I22  R309   [Q_RES_0402LF-4.7K,1%,1/16W,CHIA]
    2  PHY_LED2           B  @SCM_LIB.SCM(SCH_1):PHY_LED2
    1  P3V3_AUX_DVDD      A  @SCM_LIB.SCM(SCH_1):P3V3_AUX_DVDD

Q_RES  I18  R310   [Q_RES_0402LF-4.7K,1%,1/16W,EMPA]
    1  PHY_LED2           A  @SCM_LIB.SCM(SCH_1):PHY_LED2
    2  GND                B  @SCM_LIB.SCM(SCH_1):GND

Q_RES  I23  R311   [Q_RES_0402LF-4.7K,1%,1/16W,CHIA]
    2  PHY_LED3           B  @SCM_LIB.SCM(SCH_1):PHY_LED3
    1  P3V3_AUX_DVDD      A  @SCM_LIB.SCM(SCH_1):P3V3_AUX_DVDD

Q_RES  I19  R312   [Q_RES_0402LF-4.7K,1%,1/16W,EMPA]
    1  PHY_LED3           A  @SCM_LIB.SCM(SCH_1):PHY_LED3
    2  GND                B  @SCM_LIB.SCM(SCH_1):GND

Q_RES  I30  R313   [Q_RES_0402LF-470K,1%,1/16W,CHIA]
    1  RST_BMC_SELF_HW_D      A  @SCM_LIB.SCM(SCH_1):RST_BMC_SELF_HW_D
    2  GND                B  @SCM_LIB.SCM(SCH_1):GND

Q_RES  I26  R314   [Q_RES_0402LF-100K,1%,1/16W,CHIB]
    1  RST_BMC_SELF_HW_D_C      A  @SCM_LIB.SCM(SCH_1):RST_BMC_SELF_HW_D_C
    2  GND                B  @SCM_LIB.SCM(SCH_1):GND

Q_RES  I71  R315   [Q_RES_0402LF-0,5%,1/16W,CHIP,CA]
    1  RST_BMC_SRST_BUF_R_N      A  @SCM_LIB.SCM(SCH_1):RST_BMC_SRST_BUF_R_N
    2  RST_BMC_SRST_BUF_R1_N      B  @SCM_LIB.SCM(SCH_1):RST_BMC_SRST_BUF_R1_N

Q_RES  I318  R316   [Q_RES_0402LF-0,5%,1/16W,CHIP,CA]
    2  PWR_LED            B  @SCM_LIB.SCM(SCH_1):PWR_LED
    1  BMC_PWR_LED        A  @SCM_LIB.SCM(SCH_1):BMC_PWR_LED

Q_RES  I300  R317   [Q_RES_0402LF-0,5%,1/16W,CHIP,CA]
    1  PWR_LED_CPLD       A  @SCM_LIB.SCM(SCH_1):PWR_LED_CPLD
    2  PWR_LED            B  @SCM_LIB.SCM(SCH_1):PWR_LED

Q_RES  I301  R318   [Q_RES_0402LF-0,5%,1/16W,CHIP,CA]
    1  PWRGD_P3V3_AUX_R1      A  @SCM_LIB.SCM(SCH_1):PWRGD_P3V3_AUX_R1
    2  PWRGD_P3V3_AUX      B  @SCM_LIB.SCM(SCH_1):PWRGD_P3V3_AUX

Q_RES  I118  R319   [Q_RES_0402LF-0,5%,1/16W,CHIP,CA]
    2  PU_LED_ACT         B  @SCM_LIB.SCM(SCH_1):PU_LED_ACT
    1  P3V3_AUX_DVDD      A  @SCM_LIB.SCM(SCH_1):P3V3_AUX_DVDD

Q_RES  I304  R320   [Q_RES_0402LF-0,5%,1/16W,CHIP,CA]
    1  PWRGD_P2V5_AUX_R1      A  @SCM_LIB.SCM(SCH_1):PWRGD_P2V5_AUX_R1
    2  PWRGD_P2V5_AUX      B  @SCM_LIB.SCM(SCH_1):PWRGD_P2V5_AUX

Q_RES  I303  R321   [Q_RES_0402LF-0,5%,1/16W,CHIP,CA]
    1  PWRGD_P1V8_AUX_R1      A  @SCM_LIB.SCM(SCH_1):PWRGD_P1V8_AUX_R1
    2  PWRGD_P1V8_AUX      B  @SCM_LIB.SCM(SCH_1):PWRGD_P1V8_AUX

Q_RES  I307  R322   [Q_RES_0402LF-0,5%,1/16W,CHIP,CA]
    1  PWRGD_P3V3_RGM_R1      A  @SCM_LIB.SCM(SCH_1):PWRGD_P3V3_RGM_R1
    2  PWRGD_P3V3_RGM      B  @SCM_LIB.SCM(SCH_1):PWRGD_P3V3_RGM

Q_RES  I305  R323   [Q_RES_0402LF-0,5%,1/16W,CHIP,CA]
    1  PWRGD_P1V2_AUX_R1      A  @SCM_LIB.SCM(SCH_1):PWRGD_P1V2_AUX_R1
    2  PWRGD_P1V2_AUX      B  @SCM_LIB.SCM(SCH_1):PWRGD_P1V2_AUX

Q_RES  I28  R324   [Q_RES_0402LF-1K,1%,1/16W,CHIP,A]
    1  P1V2_AUX           A  @SCM_LIB.SCM(SCH_1):P1V2_AUX
    2  P0V6_DDR_VREF_AUX      B  @SCM_LIB.SCM(SCH_1):P0V6_DDR_VREF_AUX

Q_RES  I27  R325   [Q_RES_0402LF-1K,1%,1/16W,CHIP,A]
    1  P0V6_DDR_VREF_AUX      A  @SCM_LIB.SCM(SCH_1):P0V6_DDR_VREF_AUX
    2  GND                B  @SCM_LIB.SCM(SCH_1):GND

Q_RES  I193  R326   [Q_RES_0402LF-120,1%,1/16W,CHIPA]
    2  M_BMC_DDR4_MA<0>      B  @SCM_LIB.SCM(SCH_1):M_BMC_DDR4_MA<0>
    1  GND                A  @SCM_LIB.SCM(SCH_1):GND

Q_RES  I177  R327   [Q_RES_0402LF-120,1%,1/16W,CHIPA]
    2  M_BMC_DDR4_MA<1>      B  @SCM_LIB.SCM(SCH_1):M_BMC_DDR4_MA<1>
    1  GND                A  @SCM_LIB.SCM(SCH_1):GND

Q_RES  I176  R328   [Q_RES_0402LF-120,1%,1/16W,CHIPA]
    2  M_BMC_DDR4_MA<2>      B  @SCM_LIB.SCM(SCH_1):M_BMC_DDR4_MA<2>
    1  GND                A  @SCM_LIB.SCM(SCH_1):GND

Q_RES  I175  R329   [Q_RES_0402LF-120,1%,1/16W,CHIPA]
    2  M_BMC_DDR4_MA<3>      B  @SCM_LIB.SCM(SCH_1):M_BMC_DDR4_MA<3>
    1  GND                A  @SCM_LIB.SCM(SCH_1):GND

Q_RES  I174  R330   [Q_RES_0402LF-120,1%,1/16W,CHIPA]
    2  M_BMC_DDR4_MA<4>      B  @SCM_LIB.SCM(SCH_1):M_BMC_DDR4_MA<4>
    1  GND                A  @SCM_LIB.SCM(SCH_1):GND

Q_RES  I173  R331   [Q_RES_0402LF-120,1%,1/16W,CHIPA]
    2  M_BMC_DDR4_MA<5>      B  @SCM_LIB.SCM(SCH_1):M_BMC_DDR4_MA<5>
    1  GND                A  @SCM_LIB.SCM(SCH_1):GND

Q_RES  I171  R332   [Q_RES_0402LF-120,1%,1/16W,CHIPA]
    2  M_BMC_DDR4_MA<6>      B  @SCM_LIB.SCM(SCH_1):M_BMC_DDR4_MA<6>
    1  GND                A  @SCM_LIB.SCM(SCH_1):GND

Q_RES  I172  R333   [Q_RES_0402LF-120,1%,1/16W,CHIPA]
    2  M_BMC_DDR4_MA<7>      B  @SCM_LIB.SCM(SCH_1):M_BMC_DDR4_MA<7>
    1  GND                A  @SCM_LIB.SCM(SCH_1):GND

Q_RES  I164  R334   [Q_RES_0402LF-120,1%,1/16W,CHIPA]
    2  M_BMC_DDR4_MA<8>      B  @SCM_LIB.SCM(SCH_1):M_BMC_DDR4_MA<8>
    1  GND                A  @SCM_LIB.SCM(SCH_1):GND

Q_RES  I163  R335   [Q_RES_0402LF-120,1%,1/16W,CHIPA]
    2  M_BMC_DDR4_MA<9>      B  @SCM_LIB.SCM(SCH_1):M_BMC_DDR4_MA<9>
    1  GND                A  @SCM_LIB.SCM(SCH_1):GND

Q_RES  I162  R336   [Q_RES_0402LF-120,1%,1/16W,CHIPA]
    2  M_BMC_DDR4_MA<10>      B  @SCM_LIB.SCM(SCH_1):M_BMC_DDR4_MA<10>
    1  GND                A  @SCM_LIB.SCM(SCH_1):GND

Q_RES  I161  R337   [Q_RES_0402LF-120,1%,1/16W,CHIPA]
    2  M_BMC_DDR4_MA<11>      B  @SCM_LIB.SCM(SCH_1):M_BMC_DDR4_MA<11>
    1  GND                A  @SCM_LIB.SCM(SCH_1):GND

Q_RES  I160  R338   [Q_RES_0402LF-120,1%,1/16W,CHIPA]
    2  M_BMC_DDR4_MA<12>      B  @SCM_LIB.SCM(SCH_1):M_BMC_DDR4_MA<12>
    1  GND                A  @SCM_LIB.SCM(SCH_1):GND

Q_RES  I159  R339   [Q_RES_0402LF-120,1%,1/16W,CHIPA]
    2  M_BMC_DDR4_MA<13>      B  @SCM_LIB.SCM(SCH_1):M_BMC_DDR4_MA<13>
    1  GND                A  @SCM_LIB.SCM(SCH_1):GND

Q_RES  I124  R340   [Q_RES_0402LF-120,1%,1/16W,CHIPA]
    2  M_BMC_DDR4_MWE_N      B  @SCM_LIB.SCM(SCH_1):M_BMC_DDR4_MWE_N
    1  GND                A  @SCM_LIB.SCM(SCH_1):GND

Q_RES  I125  R341   [Q_RES_0402LF-120,1%,1/16W,CHIPA]
    2  M_BMC_DDR4_MCAS_N      B  @SCM_LIB.SCM(SCH_1):M_BMC_DDR4_MCAS_N
    1  GND                A  @SCM_LIB.SCM(SCH_1):GND

Q_RES  I122  R342   [Q_RES_0402LF-120,1%,1/16W,CHIPA]
    2  M_BMC_DDR4_MRAS_N      B  @SCM_LIB.SCM(SCH_1):M_BMC_DDR4_MRAS_N
    1  GND                A  @SCM_LIB.SCM(SCH_1):GND

Q_RES  I123  R343   [Q_RES_0402LF-120,1%,1/16W,CHIPA]
    2  M_BMC_DDR4_MCS_N      B  @SCM_LIB.SCM(SCH_1):M_BMC_DDR4_MCS_N
    1  GND                A  @SCM_LIB.SCM(SCH_1):GND

Q_RES  I121  R344   [Q_RES_0402LF-120,1%,1/16W,CHIPA]
    2  M_BMC_DDR4_MACT_N      B  @SCM_LIB.SCM(SCH_1):M_BMC_DDR4_MACT_N
    1  GND                A  @SCM_LIB.SCM(SCH_1):GND

Q_RES  I119  R345   [Q_RES_0402LF-120,1%,1/16W,CHIPA]
    2  M_BMC_DDR4_MBG0      B  @SCM_LIB.SCM(SCH_1):M_BMC_DDR4_MBG0
    1  GND                A  @SCM_LIB.SCM(SCH_1):GND

Q_RES  I120  R346   [Q_RES_0402LF-120,1%,1/16W,CHIPA]
    2  M_BMC_DDR4_MBA0      B  @SCM_LIB.SCM(SCH_1):M_BMC_DDR4_MBA0
    1  GND                A  @SCM_LIB.SCM(SCH_1):GND

Q_RES  I117  R347   [Q_RES_0402LF-120,1%,1/16W,CHIPA]
    2  M_BMC_DDR4_MBA1      B  @SCM_LIB.SCM(SCH_1):M_BMC_DDR4_MBA1
    1  GND                A  @SCM_LIB.SCM(SCH_1):GND

Q_RES  I118  R348   [Q_RES_0402LF-120,1%,1/16W,CHIPA]
    2  M_BMC_DDR4_MODT      B  @SCM_LIB.SCM(SCH_1):M_BMC_DDR4_MODT
    1  GND                A  @SCM_LIB.SCM(SCH_1):GND

Q_RES  I116  R349   [Q_RES_0402LF-120,1%,1/16W,CHIPA]
    2  M_BMC_DDR4_MCKE      B  @SCM_LIB.SCM(SCH_1):M_BMC_DDR4_MCKE
    1  GND                A  @SCM_LIB.SCM(SCH_1):GND

Q_RES  I114  R350   [Q_RES_0402LF-120,1%,1/16W,EMPTA]
    2  M_BMC_DDR4_MBG1      B  @SCM_LIB.SCM(SCH_1):M_BMC_DDR4_MBG1
    1  GND                A  @SCM_LIB.SCM(SCH_1):GND

Q_RES  I194  R351   [Q_RES_0402LF-120,1%,1/16W,CHIPA]
    2  P1V2_AUX           B  @SCM_LIB.SCM(SCH_1):P1V2_AUX
    1  M_BMC_DDR4_MA<0>      A  @SCM_LIB.SCM(SCH_1):M_BMC_DDR4_MA<0>

Q_RES  I184  R352   [Q_RES_0402LF-120,1%,1/16W,CHIPA]
    2  P1V2_AUX           B  @SCM_LIB.SCM(SCH_1):P1V2_AUX
    1  M_BMC_DDR4_MA<1>      A  @SCM_LIB.SCM(SCH_1):M_BMC_DDR4_MA<1>

Q_RES  I183  R353   [Q_RES_0402LF-120,1%,1/16W,CHIPA]
    2  P1V2_AUX           B  @SCM_LIB.SCM(SCH_1):P1V2_AUX
    1  M_BMC_DDR4_MA<2>      A  @SCM_LIB.SCM(SCH_1):M_BMC_DDR4_MA<2>

Q_RES  I181  R354   [Q_RES_0402LF-120,1%,1/16W,CHIPA]
    2  P1V2_AUX           B  @SCM_LIB.SCM(SCH_1):P1V2_AUX
    1  M_BMC_DDR4_MA<3>      A  @SCM_LIB.SCM(SCH_1):M_BMC_DDR4_MA<3>

Q_RES  I182  R355   [Q_RES_0402LF-120,1%,1/16W,CHIPA]
    2  P1V2_AUX           B  @SCM_LIB.SCM(SCH_1):P1V2_AUX
    1  M_BMC_DDR4_MA<4>      A  @SCM_LIB.SCM(SCH_1):M_BMC_DDR4_MA<4>

Q_RES  I180  R356   [Q_RES_0402LF-120,1%,1/16W,CHIPA]
    2  P1V2_AUX           B  @SCM_LIB.SCM(SCH_1):P1V2_AUX
    1  M_BMC_DDR4_MA<5>      A  @SCM_LIB.SCM(SCH_1):M_BMC_DDR4_MA<5>

Q_RES  I179  R357   [Q_RES_0402LF-120,1%,1/16W,CHIPA]
    2  P1V2_AUX           B  @SCM_LIB.SCM(SCH_1):P1V2_AUX
    1  M_BMC_DDR4_MA<6>      A  @SCM_LIB.SCM(SCH_1):M_BMC_DDR4_MA<6>

Q_RES  I178  R358   [Q_RES_0402LF-120,1%,1/16W,CHIPA]
    2  P1V2_AUX           B  @SCM_LIB.SCM(SCH_1):P1V2_AUX
    1  M_BMC_DDR4_MA<7>      A  @SCM_LIB.SCM(SCH_1):M_BMC_DDR4_MA<7>

Q_RES  I170  R359   [Q_RES_0402LF-120,1%,1/16W,CHIPA]
    2  P1V2_AUX           B  @SCM_LIB.SCM(SCH_1):P1V2_AUX
    1  M_BMC_DDR4_MA<8>      A  @SCM_LIB.SCM(SCH_1):M_BMC_DDR4_MA<8>

Q_RES  I169  R360   [Q_RES_0402LF-120,1%,1/16W,CHIPA]
    2  P1V2_AUX           B  @SCM_LIB.SCM(SCH_1):P1V2_AUX
    1  M_BMC_DDR4_MA<9>      A  @SCM_LIB.SCM(SCH_1):M_BMC_DDR4_MA<9>

Q_RES  I167  R361   [Q_RES_0402LF-120,1%,1/16W,CHIPA]
    2  P1V2_AUX           B  @SCM_LIB.SCM(SCH_1):P1V2_AUX
    1  M_BMC_DDR4_MA<10>      A  @SCM_LIB.SCM(SCH_1):M_BMC_DDR4_MA<10>

Q_RES  I168  R362   [Q_RES_0402LF-120,1%,1/16W,CHIPA]
    2  P1V2_AUX           B  @SCM_LIB.SCM(SCH_1):P1V2_AUX
    1  M_BMC_DDR4_MA<11>      A  @SCM_LIB.SCM(SCH_1):M_BMC_DDR4_MA<11>

Q_RES  I166  R363   [Q_RES_0402LF-120,1%,1/16W,CHIPA]
    2  P1V2_AUX           B  @SCM_LIB.SCM(SCH_1):P1V2_AUX
    1  M_BMC_DDR4_MA<12>      A  @SCM_LIB.SCM(SCH_1):M_BMC_DDR4_MA<12>

Q_RES  I165  R364   [Q_RES_0402LF-120,1%,1/16W,CHIPA]
    2  P1V2_AUX           B  @SCM_LIB.SCM(SCH_1):P1V2_AUX
    1  M_BMC_DDR4_MA<13>      A  @SCM_LIB.SCM(SCH_1):M_BMC_DDR4_MA<13>

Q_RES  I138  R365   [Q_RES_0402LF-120,1%,1/16W,CHIPA]
    2  P1V2_AUX           B  @SCM_LIB.SCM(SCH_1):P1V2_AUX
    1  M_BMC_DDR4_MWE_N      A  @SCM_LIB.SCM(SCH_1):M_BMC_DDR4_MWE_N

Q_RES  I137  R366   [Q_RES_0402LF-120,1%,1/16W,CHIPA]
    2  P1V2_AUX           B  @SCM_LIB.SCM(SCH_1):P1V2_AUX
    1  M_BMC_DDR4_MCAS_N      A  @SCM_LIB.SCM(SCH_1):M_BMC_DDR4_MCAS_N

Q_RES  I136  R367   [Q_RES_0402LF-120,1%,1/16W,CHIPA]
    2  P1V2_AUX           B  @SCM_LIB.SCM(SCH_1):P1V2_AUX
    1  M_BMC_DDR4_MRAS_N      A  @SCM_LIB.SCM(SCH_1):M_BMC_DDR4_MRAS_N

Q_RES  I135  R368   [Q_RES_0402LF-120,1%,1/16W,CHIPA]
    2  P1V2_AUX           B  @SCM_LIB.SCM(SCH_1):P1V2_AUX
    1  M_BMC_DDR4_MCS_N      A  @SCM_LIB.SCM(SCH_1):M_BMC_DDR4_MCS_N

Q_RES  I132  R369   [Q_RES_0402LF-120,1%,1/16W,CHIPA]
    2  P1V2_AUX           B  @SCM_LIB.SCM(SCH_1):P1V2_AUX
    1  M_BMC_DDR4_MACT_N      A  @SCM_LIB.SCM(SCH_1):M_BMC_DDR4_MACT_N

Q_RES  I131  R370   [Q_RES_0402LF-120,1%,1/16W,CHIPA]
    2  P1V2_AUX           B  @SCM_LIB.SCM(SCH_1):P1V2_AUX
    1  M_BMC_DDR4_MBG0      A  @SCM_LIB.SCM(SCH_1):M_BMC_DDR4_MBG0

Q_RES  I130  R371   [Q_RES_0402LF-120,1%,1/16W,CHIPA]
    2  P1V2_AUX           B  @SCM_LIB.SCM(SCH_1):P1V2_AUX
    1  M_BMC_DDR4_MBA0      A  @SCM_LIB.SCM(SCH_1):M_BMC_DDR4_MBA0

Q_RES  I129  R372   [Q_RES_0402LF-120,1%,1/16W,CHIPA]
    2  P1V2_AUX           B  @SCM_LIB.SCM(SCH_1):P1V2_AUX
    1  M_BMC_DDR4_MBA1      A  @SCM_LIB.SCM(SCH_1):M_BMC_DDR4_MBA1

Q_RES  I128  R373   [Q_RES_0402LF-120,1%,1/16W,CHIPA]
    2  P1V2_AUX           B  @SCM_LIB.SCM(SCH_1):P1V2_AUX
    1  M_BMC_DDR4_MODT      A  @SCM_LIB.SCM(SCH_1):M_BMC_DDR4_MODT

Q_RES  I127  R374   [Q_RES_0402LF-120,1%,1/16W,CHIPA]
    2  P1V2_AUX           B  @SCM_LIB.SCM(SCH_1):P1V2_AUX
    1  M_BMC_DDR4_MCKE      A  @SCM_LIB.SCM(SCH_1):M_BMC_DDR4_MCKE

Q_RES  I115  R375   [Q_RES_0402LF-120,1%,1/16W,EMPTA]
    2  P1V2_AUX           B  @SCM_LIB.SCM(SCH_1):P1V2_AUX
    1  M_BMC_DDR4_MBG1      A  @SCM_LIB.SCM(SCH_1):M_BMC_DDR4_MBG1

Q_RES  I62  R376   [Q_RES_0402LF-4.7K,1%,1/16W,CHIA]
    2  USB_OC0_EN         B  @SCM_LIB.SCM(SCH_1):USB_OC0_EN
    1  P5V_AUX            A  @SCM_LIB.SCM(SCH_1):P5V_AUX

Q_RES  I63  R377   [Q_RES_0402LF-10K,1%,1/16W,EMPTB]
    1  USB_OC0_EN         A  @SCM_LIB.SCM(SCH_1):USB_OC0_EN
    2  GND                B  @SCM_LIB.SCM(SCH_1):GND

Q_RES  I54  R378   [Q_RES_0402LF-20K,1%,1/16W,CHIPA]
    1  USB_OC0_ILIM       A  @SCM_LIB.SCM(SCH_1):USB_OC0_ILIM
    2  GND                B  @SCM_LIB.SCM(SCH_1):GND

Q_RES  I306  R379   [Q_RES_0402LF-0,5%,1/16W,CHIP,CA]
    1  PWRGD_P1V0_AUX_R1      A  @SCM_LIB.SCM(SCH_1):PWRGD_P1V0_AUX_R1
    2  PWRGD_P1V0_AUX      B  @SCM_LIB.SCM(SCH_1):PWRGD_P1V0_AUX

Q_RES  I98  R380   [Q_RES_0402LF-0,5%,1/16W,CHIP,CA]
    2  PWRGD_P1V8_AUX_R2      B  @SCM_LIB.SCM(SCH_1):PWRGD_P1V8_AUX_R2
    1  PWRGD_P1V8_AUX      A  @SCM_LIB.SCM(SCH_1):PWRGD_P1V8_AUX

Q_RES  I97  R381   [Q_RES_0402LF-0,5%,1/16W,CHIP,CA]
    2  PWRGD_P5V_AUX_R2      B  @SCM_LIB.SCM(SCH_1):PWRGD_P5V_AUX_R2
    1  PWRGD_P5V_AUX      A  @SCM_LIB.SCM(SCH_1):PWRGD_P5V_AUX

Q_RES  I65  R382   [Q_RES_0402LF-0,5%,1/16W,CHIP,CA]
    2  PWRGD_P3V3_AUX_R2      B  @SCM_LIB.SCM(SCH_1):PWRGD_P3V3_AUX_R2
    1  PWRGD_P3V3_AUX      A  @SCM_LIB.SCM(SCH_1):PWRGD_P3V3_AUX

Q_RES  I42  R383   [Q_RES_0402LF-10K,1%,1/16W,CHIPA]
    2  USB_OC0_REAR_N      B  @SCM_LIB.SCM(SCH_1):USB_OC0_REAR_N
    1  P3V3_AUX           A  @SCM_LIB.SCM(SCH_1):P3V3_AUX

Q_RES  I41  R384   [Q_RES_0402LF-0,5%,1/16W,CHIP,CA]
    2  USB_OC0_REAR_R_N      B  @SCM_LIB.SCM(SCH_1):USB_OC0_REAR_R_N
    1  USB_OC0_REAR_N      A  @SCM_LIB.SCM(SCH_1):USB_OC0_REAR_N

Q_RES  I2   R385   [Q_RES_0402LF-0,5%,1/16W,CHIP,CA]
    1  USB_FPNL_DN        A  @SCM_LIB.SCM(SCH_1):USB_FPNL_DN
    2  USB2_01_F_DN       B  @SCM_LIB.SCM(SCH_1):USB2_01_F_DN

Q_RES  I10  R386   [Q_RES_0402LF-0,5%,1/16W,CHIP,CA]
    1  USB_FPNL_DP        A  @SCM_LIB.SCM(SCH_1):USB_FPNL_DP
    2  USB2_01_F_DP       B  @SCM_LIB.SCM(SCH_1):USB2_01_F_DP

Q_RES  I14  R387   [Q_RES_0402LF-4.7K,1%,1/16W,CHIA]
    1  P3V3_AUX           A  @SCM_LIB.SCM(SCH_1):P3V3_AUX
    2  LOADSW_VBIAS       B  @SCM_LIB.SCM(SCH_1):LOADSW_VBIAS

Q_RES  I15  R388   [Q_RES_0402LF-4.7K,1%,1/16W,EMPA]
    1  LOADSW_VBIAS       A  @SCM_LIB.SCM(SCH_1):LOADSW_VBIAS
    2  GND                B  @SCM_LIB.SCM(SCH_1):GND

Q_RES  I16  R389   [Q_RES_0402LF-4.7K,1%,1/16W,CHIA]
    2  PU_LOADSW_EN       B  @SCM_LIB.SCM(SCH_1):PU_LOADSW_EN
    1  P3V3_AUX           A  @SCM_LIB.SCM(SCH_1):P3V3_AUX

Q_RES  I17  R390   [Q_RES_0402LF-4.7K,1%,1/16W,EMPA]
    1  PU_LOADSW_EN       A  @SCM_LIB.SCM(SCH_1):PU_LOADSW_EN
    2  GND                B  @SCM_LIB.SCM(SCH_1):GND

Q_RES  I34  R391   [Q_RES_0402LF-100K,1%,1/16W,CHIA]
    2  GND                B  @SCM_LIB.SCM(SCH_1):GND
    1  DP_BMC_HPD_3V3      A  @SCM_LIB.SCM(SCH_1):DP_BMC_HPD_3V3

Q_RES  I35  R392   [Q_RES_0402LF-100K,1%,1/16W,CHIA]
    2  GND                B  @SCM_LIB.SCM(SCH_1):GND
    1  DP_BMC_AUX_C_P      A  @SCM_LIB.SCM(SCH_1):DP_BMC_AUX_C_P

Q_RES  I102  R393   [Q_RES_0402LF-0,5%,1/16W,CHIP,CA]
    2  PWRGD_P2V5_AUX_R2      B  @SCM_LIB.SCM(SCH_1):PWRGD_P2V5_AUX_R2
    1  PWRGD_P2V5_AUX      A  @SCM_LIB.SCM(SCH_1):PWRGD_P2V5_AUX

Q_RES  I314  R394   [Q_RES_0402LF-33       ,1%  ,1/A]
    2  SMB_BMC_MM2_SDA      B  @SCM_LIB.SCM(SCH_1):SMB_BMC_MM2_SDA
    1  SMB_BMC_MM2_R_SDA      A  @SCM_LIB.SCM(SCH_1):SMB_BMC_MM2_R_SDA

Q_RES  I114  R395   [Q_RES_0402LF-1M,1%,1/16W,CHIP,A]
    2  GND                B  @SCM_LIB.SCM(SCH_1):GND
    1  DP_CONFIG1         A  @SCM_LIB.SCM(SCH_1):DP_CONFIG1

Q_RES  I113  R396   [Q_RES_0402LF-1M,1%,1/16W,CHIP,A]
    2  GND                B  @SCM_LIB.SCM(SCH_1):GND
    1  DP_CONFIG2         A  @SCM_LIB.SCM(SCH_1):DP_CONFIG2

Q_RES  I97  R397   [Q_RES_0402LF-0,5%,1/16W,CHIP,CA]
    2  SPA_SIN_SW_MNUSB_R      B  @SCM_LIB.SCM(SCH_1):SPA_SIN_SW_MNUSB_R
    1  SPA_SIN_SW_MNUSB      A  @SCM_LIB.SCM(SCH_1):SPA_SIN_SW_MNUSB

Q_RES  I96  R398   [Q_RES_0402LF-10K,1%,1/16W,CHIPA]
    2  SPA_SIN_SW_MNUSB_R      B  @SCM_LIB.SCM(SCH_1):SPA_SIN_SW_MNUSB_R
    1  P3V3_PL2303        A  @SCM_LIB.SCM(SCH_1):P3V3_PL2303

Q_RES  I55  R399   [Q_RES_0402LF-0,5%,1/16W,CHIP,CA]
    2  PWRGD_P1V2_AUX_R2      B  @SCM_LIB.SCM(SCH_1):PWRGD_P1V2_AUX_R2
    1  PWRGD_P1V2_AUX      A  @SCM_LIB.SCM(SCH_1):PWRGD_P1V2_AUX

Q_RES  I148  R400   [Q_RES_0402LF-1.24K,1%,1/16W,CHA]
    1  PHY_RDAC           A  @SCM_LIB.SCM(SCH_1):PHY_RDAC
    2  GND                B  @SCM_LIB.SCM(SCH_1):GND

Q_RES  I90  R401   [Q_RES_0201LF-1.5K,1%,1/20W,CHIA]
    2  USB2_PL2303_EXT_DP      B  @SCM_LIB.SCM(SCH_1):USB2_PL2303_EXT_DP
    1  P3V3_PL2303        A  @SCM_LIB.SCM(SCH_1):P3V3_PL2303

Q_RES  I88  R402   [Q_RES_0201LF-27.4,1%,1/20W,CHIA]
    1  USB2_PL2303_EXT_DN      A  @SCM_LIB.SCM(SCH_1):USB2_PL2303_EXT_DN
    2  USB2_EXT_DN        B  @SCM_LIB.SCM(SCH_1):USB2_EXT_DN

Q_RES  I87  R403   [Q_RES_0201LF-27.4,1%,1/20W,CHIA]
    1  USB2_PL2303_EXT_DP      A  @SCM_LIB.SCM(SCH_1):USB2_PL2303_EXT_DP
    2  USB2_EXT_DP        B  @SCM_LIB.SCM(SCH_1):USB2_EXT_DP

Q_RES  I269  R404   [Q_RES_0402LF-33       ,1%  ,1/A]
    1  FM_RISER1_JTAG_SEL_R_N      A  @SCM_LIB.SCM(SCH_1):FM_RISER1_JTAG_SEL_R_N
    2  FM_RISER1_JTAG_SEL_N      B  @SCM_LIB.SCM(SCH_1):FM_RISER1_JTAG_SEL_N

Q_RES  I268  R405   [Q_RES_0402LF-33       ,1%  ,1/A]
    1  PD_BIOS_MUX_EN_R_N      A  @SCM_LIB.SCM(SCH_1):PD_BIOS_MUX_EN_R_N
    2  PD_BIOS_MUX_EN_N      B  @SCM_LIB.SCM(SCH_1):PD_BIOS_MUX_EN_N

Q_RES  I75  R406   [Q_RES_0402LF-0,5%,1/16W,CHIP,CA]
    1  P5V_BUS            A  @SCM_LIB.SCM(SCH_1):P5V_BUS
    2  P5V_AUX_VBUS       B  @SCM_LIB.SCM(SCH_1):P5V_AUX_VBUS

Q_RES  I42  R407   [Q_RES_0402LF-4.7K,5%,1/16W,CHIA]
    2  SMB_BMC_ALERT15_R_N      B  @SCM_LIB.SCM(SCH_1):SMB_BMC_ALERT15_R_N
    1  P3V3_AUX           A  @SCM_LIB.SCM(SCH_1):P3V3_AUX

Q_RES  I19  R408   [Q_RES_0402LF-33       ,1%  ,1/A]
    2  SMB_BMC_ALERT15_R_N      B  @SCM_LIB.SCM(SCH_1):SMB_BMC_ALERT15_R_N
    1  SMB_BMC_ALERT15_N      A  @SCM_LIB.SCM(SCH_1):SMB_BMC_ALERT15_N

Q_RES  I20  R409   [Q_RES_0402LF-33       ,1%  ,1/A]
    1  SMB_BMC_MM15_SDA      A  @SCM_LIB.SCM(SCH_1):SMB_BMC_MM15_SDA
    2  SMB_BMC_MM15_R1_SDA      B  @SCM_LIB.SCM(SCH_1):SMB_BMC_MM15_R1_SDA

Q_RES  I21  R410   [Q_RES_0402LF-33       ,1%  ,1/A]
    1  SMB_BMC_MM15_SCL      A  @SCM_LIB.SCM(SCH_1):SMB_BMC_MM15_SCL
    2  SMB_BMC_MM15_R1_SCL      B  @SCM_LIB.SCM(SCH_1):SMB_BMC_MM15_R1_SCL

Q_RES  I6   R411   [Q_RES_0402LF-100,1%,1/16W,EMPTA]
    2  GND                B  @SCM_LIB.SCM(SCH_1):GND
    1  FRU_E0             A  @SCM_LIB.SCM(SCH_1):FRU_E0

Q_RES  I8   R412   [Q_RES_0402LF-100,1%,1/16W,CHIPA]
    2  GND                B  @SCM_LIB.SCM(SCH_1):GND
    1  FRU_E1             A  @SCM_LIB.SCM(SCH_1):FRU_E1

Q_RES  I12  R413   [Q_RES_0402LF-100,1%,1/16W,CHIPA]
    2  GND                B  @SCM_LIB.SCM(SCH_1):GND
    1  FRU_E2             A  @SCM_LIB.SCM(SCH_1):FRU_E2

Q_RES  I29  R414   [Q_RES_0402LF-4.7K,5%,1/16W,EMPA]
    2  TEMP_A2            B  @SCM_LIB.SCM(SCH_1):TEMP_A2
    1  P3V3_AUX           A  @SCM_LIB.SCM(SCH_1):P3V3_AUX

Q_RES  I27  R415   [Q_RES_0402LF-100,1%,1/16W,CHIPA]
    1  TEMP_A2            A  @SCM_LIB.SCM(SCH_1):TEMP_A2
    2  GND                B  @SCM_LIB.SCM(SCH_1):GND

Q_RES  I30  R416   [Q_RES_0402LF-4.7K,5%,1/16W,CHIA]
    2  TEMP_A1            B  @SCM_LIB.SCM(SCH_1):TEMP_A1
    1  P3V3_AUX           A  @SCM_LIB.SCM(SCH_1):P3V3_AUX

Q_RES  I28  R417   [Q_RES_0402LF-100,1%,1/16W,EMPTA]
    1  TEMP_A1            A  @SCM_LIB.SCM(SCH_1):TEMP_A1
    2  GND                B  @SCM_LIB.SCM(SCH_1):GND

Q_RES  I39  R418   [Q_RES_0402LF-4.7K,5%,1/16W,EMPA]
    2  TEMP_A0            B  @SCM_LIB.SCM(SCH_1):TEMP_A0
    1  P3V3_AUX           A  @SCM_LIB.SCM(SCH_1):P3V3_AUX

Q_RES  I38  R419   [Q_RES_0402LF-100,1%,1/16W,CHIPA]
    1  TEMP_A0            A  @SCM_LIB.SCM(SCH_1):TEMP_A0
    2  GND                B  @SCM_LIB.SCM(SCH_1):GND

Q_RES  I34  R420   [Q_RES_0402LF-33       ,1%  ,1/A]
    2  SMB_BMC_MM15_SCL      B  @SCM_LIB.SCM(SCH_1):SMB_BMC_MM15_SCL
    1  SMB_BMC_MM15_R2_SCL      A  @SCM_LIB.SCM(SCH_1):SMB_BMC_MM15_R2_SCL

Q_RES  I33  R421   [Q_RES_0402LF-33       ,1%  ,1/A]
    2  SMB_BMC_MM15_SDA      B  @SCM_LIB.SCM(SCH_1):SMB_BMC_MM15_SDA
    1  SMB_BMC_MM15_R2_SDA      A  @SCM_LIB.SCM(SCH_1):SMB_BMC_MM15_R2_SDA

Q_RES  I203  R422   [Q_RES_0402LF-4.7K,5%,1/16W,CHIA]
    2  SMB_BMC_MM13_SCL      B  @SCM_LIB.SCM(SCH_1):SMB_BMC_MM13_SCL
    1  P3V3_AUX           A  @SCM_LIB.SCM(SCH_1):P3V3_AUX

Q_RES  I252  R423   [Q_RES_0402LF-33       ,1%  ,1/A]
    2  SMB_BMC_MM13_SCL      B  @SCM_LIB.SCM(SCH_1):SMB_BMC_MM13_SCL
    1  SMB_BMC_MM13_R_SCL      A  @SCM_LIB.SCM(SCH_1):SMB_BMC_MM13_R_SCL

Q_RES  I253  R424   [Q_RES_0402LF-33       ,1%  ,1/A]
    2  SMB_BMC_MM13_SDA      B  @SCM_LIB.SCM(SCH_1):SMB_BMC_MM13_SDA
    1  SMB_BMC_MM13_R_SDA      A  @SCM_LIB.SCM(SCH_1):SMB_BMC_MM13_R_SDA

Q_RES  I254  R425   [Q_RES_0402LF-33       ,1%  ,1/A]
    2  SMB_BMC_MM14_SCL      B  @SCM_LIB.SCM(SCH_1):SMB_BMC_MM14_SCL
    1  SMB_BMC_MM14_R_SCL      A  @SCM_LIB.SCM(SCH_1):SMB_BMC_MM14_R_SCL

Q_RES  I255  R426   [Q_RES_0402LF-33       ,1%  ,1/A]
    2  SMB_BMC_MM14_SDA      B  @SCM_LIB.SCM(SCH_1):SMB_BMC_MM14_SDA
    1  SMB_BMC_MM14_R_SDA      A  @SCM_LIB.SCM(SCH_1):SMB_BMC_MM14_R_SDA

Q_RES  I198  R427   [Q_RES_0402LF-33       ,1%  ,1/A]
    1  UART_BMC_1_RXD_R      A  @SCM_LIB.SCM(SCH_1):UART_BMC_1_RXD_R
    2  UART_BMC_1_RXD      B  @SCM_LIB.SCM(SCH_1):UART_BMC_1_RXD

Q_RES  I210  R428   [Q_RES_0402LF-4.7K,5%,1/16W,CHIA]
    2  SMB_BMC_MM13_SDA      B  @SCM_LIB.SCM(SCH_1):SMB_BMC_MM13_SDA
    1  P3V3_AUX           A  @SCM_LIB.SCM(SCH_1):P3V3_AUX

Q_RES  I209  R429   [Q_RES_0402LF-4.7K,5%,1/16W,CHIA]
    2  SMB_BMC_MM14_SCL      B  @SCM_LIB.SCM(SCH_1):SMB_BMC_MM14_SCL
    1  P3V3_AUX           A  @SCM_LIB.SCM(SCH_1):P3V3_AUX

Q_RES  I188  R430   [Q_RES_0402LF-4.7K,5%,1/16W,CHIA]
    1  P3V3_AUX           A  @SCM_LIB.SCM(SCH_1):P3V3_AUX
    2  FM_BMC_ONCTL_R_N      B  @SCM_LIB.SCM(SCH_1):FM_BMC_ONCTL_R_N

Q_RES  I17  R431   [Q_RES_0402LF-100,1%,1/16W,CHIPA]
    1  PD_BMC_DISABLE      A  @SCM_LIB.SCM(SCH_1):PD_BMC_DISABLE
    2  GND                B  @SCM_LIB.SCM(SCH_1):GND

Q_RES  I290  R432   [Q_RES_0402LF-0,5%,1/16W,EMPTY,A]
    1  FM_PWR_R_BTN       A  @SCM_LIB.SCM(SCH_1):FM_PWR_R_BTN
    2  FM_PWR_BTN         B  @SCM_LIB.SCM(SCH_1):FM_PWR_BTN

Q_RES  I382  R433   [Q_RES_0402LF-33       ,1%  ,1/A]
    1  SGPIO_DI_1         A  @SCM_LIB.SCM(SCH_1):SGPIO_DI_1
    2  SGPIO_BMC_M1_DI      B  @SCM_LIB.SCM(SCH_1):SGPIO_BMC_M1_DI

Q_RES  I389  R434   [Q_RES_0402LF-33       ,1%  ,1/A]
    1  SGPIO_CLK_PLD_0      A  @SCM_LIB.SCM(SCH_1):SGPIO_CLK_PLD_0
    2  SGPIO_CLK_0        B  @SCM_LIB.SCM(SCH_1):SGPIO_CLK_0

Q_RES  I388  R435   [Q_RES_0402LF-33       ,1%  ,1/A]
    1  SGPIO_PLD_DO_0      A  @SCM_LIB.SCM(SCH_1):SGPIO_PLD_DO_0
    2  SGPIO_DO_0         B  @SCM_LIB.SCM(SCH_1):SGPIO_DO_0

Q_RES  I390  R436   [Q_RES_0402LF-33       ,1%  ,1/A]
    1  SGPIO_PLD_LD_0      A  @SCM_LIB.SCM(SCH_1):SGPIO_PLD_LD_0
    2  SGPIO_LD_0         B  @SCM_LIB.SCM(SCH_1):SGPIO_LD_0

Q_RES  I391  R437   [Q_RES_0402LF-33       ,1%  ,1/A]
    1  SGPIO_PLD_DI_0      A  @SCM_LIB.SCM(SCH_1):SGPIO_PLD_DI_0
    2  SGPIO_DI_0         B  @SCM_LIB.SCM(SCH_1):SGPIO_DI_0

Q_RES  I208  R438   [Q_RES_0402LF-4.7K,5%,1/16W,CHIA]
    2  SMB_BMC_MM14_SDA      B  @SCM_LIB.SCM(SCH_1):SMB_BMC_MM14_SDA
    1  P3V3_AUX           A  @SCM_LIB.SCM(SCH_1):P3V3_AUX

Q_RES  I227  R439   [Q_RES_0402LF-33       ,1%  ,1/A]
    2  FM_PECI_SEL_R_N      B  @SCM_LIB.SCM(SCH_1):FM_PECI_SEL_R_N
    1  FM_PECI_SEL_N      A  @SCM_LIB.SCM(SCH_1):FM_PECI_SEL_N

Q_RES  I506  R440   [Q_RES_0402LF-33       ,1%  ,1/A]
    1  FM_INTRUDER_HDR_PCH_R_N      A  @SCM_LIB.SCM(SCH_1):FM_INTRUDER_HDR_PCH_R_N
    2  FM_INTRUDER_HDR_PCH_N      B  @SCM_LIB.SCM(SCH_1):FM_INTRUDER_HDR_PCH_N

Q_RES  I415  R441   [Q_RES_0402LF-4.7K,5%,1/16W,CHIA]
    1  P3V3_AUX           A  @SCM_LIB.SCM(SCH_1):P3V3_AUX
    2  FM_INTRUDER_HDR_PCH_R_N      B  @SCM_LIB.SCM(SCH_1):FM_INTRUDER_HDR_PCH_R_N

Q_RES  I301  R442   [Q_RES_0402LF-33       ,1%  ,1/A]
    2  SMB_BMC_ALERT3_R_N      B  @SCM_LIB.SCM(SCH_1):SMB_BMC_ALERT3_R_N
    1  SMB_BMC_ALERT3_N      A  @SCM_LIB.SCM(SCH_1):SMB_BMC_ALERT3_N

Q_RES  I300  R443   [Q_RES_0402LF-33       ,1%  ,1/A]
    2  SMB_BMC_ALERT4_R_N      B  @SCM_LIB.SCM(SCH_1):SMB_BMC_ALERT4_R_N
    1  SMB_BMC_ALERT4_N      A  @SCM_LIB.SCM(SCH_1):SMB_BMC_ALERT4_N

Q_RES  I306  R444   [Q_RES_0402LF-33       ,1%  ,1/A]
    2  FM_ESPI_PLD_R1_EN      B  @SCM_LIB.SCM(SCH_1):FM_ESPI_PLD_R1_EN
    1  FM_ESPI_PLD_EN      A  @SCM_LIB.SCM(SCH_1):FM_ESPI_PLD_EN

Q_RES  I299  R446   [Q_RES_0402LF-4.7K,5%,1/16W,CHIA]
    1  P3V3_AUX           A  @SCM_LIB.SCM(SCH_1):P3V3_AUX
    2  FM_PECI_SEL_N      B  @SCM_LIB.SCM(SCH_1):FM_PECI_SEL_N

Q_RES  I386  R447   [Q_RES_0402LF-0,5%,1/16W,CHIP,CA]
    2  RST_EXTRST_R_N      B  @SCM_LIB.SCM(SCH_1):RST_EXTRST_R_N
    1  RST_EXTRST_N       A  @SCM_LIB.SCM(SCH_1):RST_EXTRST_N

Q_RES  I320  R448   [Q_RES_0402LF-33       ,1%  ,1/A]
    2  SMB_BMC_ALERT9_R_N      B  @SCM_LIB.SCM(SCH_1):SMB_BMC_ALERT9_R_N
    1  SMB_BMC_ALERT9_N      A  @SCM_LIB.SCM(SCH_1):SMB_BMC_ALERT9_N

Q_RES  I321  R449   [Q_RES_0402LF-33       ,1%  ,1/A]
    2  SMB_BMC_ALERT10_R_N      B  @SCM_LIB.SCM(SCH_1):SMB_BMC_ALERT10_R_N
    1  SMB_BMC_ALERT10_N      A  @SCM_LIB.SCM(SCH_1):SMB_BMC_ALERT10_N

Q_RES  I77  R450   [Q_RES_0402LF-0,5%,1/16W,EMPTY,A]
    2  RST_BMC_SELF_HW_R3      B  @SCM_LIB.SCM(SCH_1):RST_BMC_SELF_HW_R3
    1  RST_BMC_SELF_HW      A  @SCM_LIB.SCM(SCH_1):RST_BMC_SELF_HW

Q_RES  I74  R451   [Q_RES_0402LF-0,5%,1/16W,CHIP,CA]
    2  PWRGD_P1V0_AUX_DELAY_R1      B  @SCM_LIB.SCM(SCH_1):PWRGD_P1V0_AUX_DELAY_R1
    1  PWRGD_P1V0_AUX_DELAY      A  @SCM_LIB.SCM(SCH_1):PWRGD_P1V0_AUX_DELAY

Q_RES  I339  R452   [Q_RES_0402LF-4.7K,5%,1/16W,CHIA]
    2  RST_WDTRST_PLD_N      B  @SCM_LIB.SCM(SCH_1):RST_WDTRST_PLD_N
    1  P3V3_AUX           A  @SCM_LIB.SCM(SCH_1):P3V3_AUX

Q_RES  I438  R453   [Q_RES_0402LF-0,5%,1/16W,CHIP,CA]
    2  SMB_BMC_ALERT3_R1_N      B  @SCM_LIB.SCM(SCH_1):SMB_BMC_ALERT3_R1_N
    1  SMB_BMC_ALERT3_N      A  @SCM_LIB.SCM(SCH_1):SMB_BMC_ALERT3_N

Q_RES  I440  R454   [Q_RES_0402LF-0,5%,1/16W,CHIP,CA]
    2  SMB_BMC_ALERT4_R1_N      B  @SCM_LIB.SCM(SCH_1):SMB_BMC_ALERT4_R1_N
    1  SMB_BMC_ALERT4_N      A  @SCM_LIB.SCM(SCH_1):SMB_BMC_ALERT4_N

Q_RES  I125  R455   [Q_RES_0402LF-4.7K,5%,1/16W,EMPA]
    2  PHYA0              B  @SCM_LIB.SCM(SCH_1):PHYA0
    1  P3V3_AUX           A  @SCM_LIB.SCM(SCH_1):P3V3_AUX

Q_RES  I442  R456   [Q_RES_0402LF-0,5%,1/16W,CHIP,CA]
    2  SMB_BMC_ALERT9_R1_N      B  @SCM_LIB.SCM(SCH_1):SMB_BMC_ALERT9_R1_N
    1  SMB_BMC_ALERT9_N      A  @SCM_LIB.SCM(SCH_1):SMB_BMC_ALERT9_N

Q_RES  I444  R457   [Q_RES_0402LF-0,5%,1/16W,CHIP,CA]
    2  SMB_BMC_ALERT10_R1_N      B  @SCM_LIB.SCM(SCH_1):SMB_BMC_ALERT10_R1_N
    1  SMB_BMC_ALERT10_N      A  @SCM_LIB.SCM(SCH_1):SMB_BMC_ALERT10_N

Q_RES  I421  R458   [Q_RES_0402LF-33       ,1%  ,1/A]
    2  BMC_CPLD_GPIO_3_R1      B  @SCM_LIB.SCM(SCH_1):BMC_CPLD_GPIO_3_R1
    1  BMC_CPLD_GPIO_3      A  @SCM_LIB.SCM(SCH_1):BMC_CPLD_GPIO_3

Q_RES  I310  R459   [Q_RES_0402LF-33       ,1%  ,1/A]
    2  BMC_CPLD_GPIO_4_R1      B  @SCM_LIB.SCM(SCH_1):BMC_CPLD_GPIO_4_R1
    1  BMC_CPLD_GPIO_4      A  @SCM_LIB.SCM(SCH_1):BMC_CPLD_GPIO_4

Q_RES  I312  R460   [Q_RES_0402LF-33       ,1%  ,1/A]
    2  BMC_CPLD_GPIO_5_R1      B  @SCM_LIB.SCM(SCH_1):BMC_CPLD_GPIO_5_R1
    1  BMC_CPLD_GPIO_5      A  @SCM_LIB.SCM(SCH_1):BMC_CPLD_GPIO_5

Q_RES  I314  R461   [Q_RES_0402LF-33       ,1%  ,1/A]
    2  BMC_CPLD_GPIO_6_R1      B  @SCM_LIB.SCM(SCH_1):BMC_CPLD_GPIO_6_R1
    1  BMC_CPLD_GPIO_6      A  @SCM_LIB.SCM(SCH_1):BMC_CPLD_GPIO_6

Q_RES  I325  R462   [Q_RES_0402LF-33       ,1%  ,1/A]
    1  BMC_CPLD_GPIO_14_R1      A  @SCM_LIB.SCM(SCH_1):BMC_CPLD_GPIO_14_R1
    2  BMC_CPLD_GPIO_14      B  @SCM_LIB.SCM(SCH_1):BMC_CPLD_GPIO_14

Q_RES  I331  R463   [Q_RES_0402LF-33       ,1%  ,1/A]
    1  BMC_CPLD_GPIO_11_R1      A  @SCM_LIB.SCM(SCH_1):BMC_CPLD_GPIO_11_R1
    2  BMC_CPLD_GPIO_11      B  @SCM_LIB.SCM(SCH_1):BMC_CPLD_GPIO_11

Q_RES  I75  R464   [Q_RES_0402LF-10K,1%,1/16W,CHIPA]
    1  P3V3_AUX           A  @SCM_LIB.SCM(SCH_1):P3V3_AUX
    2  FM_TPM_PRSNT_0_N      B  @SCM_LIB.SCM(SCH_1):FM_TPM_PRSNT_0_N

Q_RES  I329  R465   [Q_RES_0402LF-33       ,1%  ,1/A]
    1  BMC_CPLD_GPIO_12_R1      A  @SCM_LIB.SCM(SCH_1):BMC_CPLD_GPIO_12_R1
    2  BMC_CPLD_GPIO_12      B  @SCM_LIB.SCM(SCH_1):BMC_CPLD_GPIO_12

Q_RES  I327  R466   [Q_RES_0402LF-33       ,1%  ,1/A]
    1  BMC_CPLD_GPIO_13_R1      A  @SCM_LIB.SCM(SCH_1):BMC_CPLD_GPIO_13_R1
    2  BMC_CPLD_GPIO_13      B  @SCM_LIB.SCM(SCH_1):BMC_CPLD_GPIO_13

Q_RES  I313  R467   [Q_RES_0402LF-2K,1%,1/16W,CHIP,A]
    1  PD_BIOS_MUX_EN_N      A  @SCM_LIB.SCM(SCH_1):PD_BIOS_MUX_EN_N
    2  GND                B  @SCM_LIB.SCM(SCH_1):GND

Q_RES  I318  R468   [Q_RES_0402LF-33       ,1%  ,1/A]
    1  BMC_CPLD_GPIO_7_R1      A  @SCM_LIB.SCM(SCH_1):BMC_CPLD_GPIO_7_R1
    2  BMC_CPLD_GPIO_7      B  @SCM_LIB.SCM(SCH_1):BMC_CPLD_GPIO_7

Q_RES  I319  R469   [Q_RES_0402LF-33       ,1%  ,1/A]
    1  BMC_CPLD_GPIO_8_R1      A  @SCM_LIB.SCM(SCH_1):BMC_CPLD_GPIO_8_R1
    2  BMC_CPLD_GPIO_8      B  @SCM_LIB.SCM(SCH_1):BMC_CPLD_GPIO_8

Q_RES  I136  R470   [Q_RES_0402LF-33       ,1%  ,1/A]
    2  RGMII_BMC_R_RXD_<2>      B  @SCM_LIB.SCM(SCH_1):RGMII_BMC_R_RXD_<2>
    1  RGMII_BMC_RXD_<2>      A  @SCM_LIB.SCM(SCH_1):RGMII_BMC_RXD_<2>

Q_RES  I135  R471   [Q_RES_0402LF-33       ,1%  ,1/A]
    2  RGMII_BMC_R_RXD_<3>      B  @SCM_LIB.SCM(SCH_1):RGMII_BMC_R_RXD_<3>
    1  RGMII_BMC_RXD_<3>      A  @SCM_LIB.SCM(SCH_1):RGMII_BMC_RXD_<3>

Q_RES  I321  R472   [Q_RES_0402LF-33       ,1%  ,1/A]
    1  BMC_CPLD_GPIO_9_R1      A  @SCM_LIB.SCM(SCH_1):BMC_CPLD_GPIO_9_R1
    2  BMC_CPLD_GPIO_9      B  @SCM_LIB.SCM(SCH_1):BMC_CPLD_GPIO_9

Q_RES  I323  R473   [Q_RES_0402LF-33       ,1%  ,1/A]
    1  BMC_CPLD_GPIO_10_R1      A  @SCM_LIB.SCM(SCH_1):BMC_CPLD_GPIO_10_R1
    2  BMC_CPLD_GPIO_10      B  @SCM_LIB.SCM(SCH_1):BMC_CPLD_GPIO_10

Q_RES  I324  R474   [Q_RES_0402LF-33       ,1%  ,1/A]
    2  BMC_CPLD_GPIO_15_R1      B  @SCM_LIB.SCM(SCH_1):BMC_CPLD_GPIO_15_R1
    1  BMC_CPLD_GPIO_15      A  @SCM_LIB.SCM(SCH_1):BMC_CPLD_GPIO_15

Q_RES  I338  R475   [Q_RES_0402LF-33       ,1%  ,1/A]
    2  BMC_CPLD_GPIO_16_R1      B  @SCM_LIB.SCM(SCH_1):BMC_CPLD_GPIO_16_R1
    1  BMC_CPLD_GPIO_16      A  @SCM_LIB.SCM(SCH_1):BMC_CPLD_GPIO_16

Q_RES  I336  R476   [Q_RES_0402LF-33       ,1%  ,1/A]
    2  BMC_CPLD_GPIO_17_R1      B  @SCM_LIB.SCM(SCH_1):BMC_CPLD_GPIO_17_R1
    1  BMC_CPLD_GPIO_17      A  @SCM_LIB.SCM(SCH_1):BMC_CPLD_GPIO_17

Q_RES  I334  R477   [Q_RES_0402LF-33       ,1%  ,1/A]
    2  BMC_CPLD_GPIO_18_R1      B  @SCM_LIB.SCM(SCH_1):BMC_CPLD_GPIO_18_R1
    1  BMC_CPLD_GPIO_18      A  @SCM_LIB.SCM(SCH_1):BMC_CPLD_GPIO_18

Q_RES  I332  R478   [Q_RES_0402LF-33       ,1%  ,1/A]
    2  BMC_CPLD_GPIO_19_R1      B  @SCM_LIB.SCM(SCH_1):BMC_CPLD_GPIO_19_R1
    1  BMC_CPLD_GPIO_19      A  @SCM_LIB.SCM(SCH_1):BMC_CPLD_GPIO_19

Q_RES  I330  R479   [Q_RES_0402LF-33       ,1%  ,1/A]
    2  BMC_CPLD_GPIO_20_R1      B  @SCM_LIB.SCM(SCH_1):BMC_CPLD_GPIO_20_R1
    1  BMC_CPLD_GPIO_20      A  @SCM_LIB.SCM(SCH_1):BMC_CPLD_GPIO_20

Q_RES  I328  R480   [Q_RES_0402LF-33       ,1%  ,1/A]
    2  BMC_CPLD_GPIO_21_R1      B  @SCM_LIB.SCM(SCH_1):BMC_CPLD_GPIO_21_R1
    1  BMC_CPLD_GPIO_21      A  @SCM_LIB.SCM(SCH_1):BMC_CPLD_GPIO_21

Q_RES  I24  R481   [Q_RES_0402LF-33       ,1%  ,1/A]
    1  SPI_PCH_MUXED_CLK      A  @SCM_LIB.SCM(SCH_1):SPI_PCH_MUXED_CLK
    2  SPI_PCH_CLK_FLASH_R1      B  @SCM_LIB.SCM(SCH_1):SPI_PCH_CLK_FLASH_R1

Q_RES  I22  R482   [Q_RES_0402LF-33       ,1%  ,1/A]
    1  SPI_PCH_MUXED_IO0      A  @SCM_LIB.SCM(SCH_1):SPI_PCH_MUXED_IO0
    2  SPI_PCH_IO0_FLASH_R1      B  @SCM_LIB.SCM(SCH_1):SPI_PCH_IO0_FLASH_R1

Q_RES  I23  R483   [Q_RES_0402LF-33       ,1%  ,1/A]
    1  SPI_PCH_MUXED_IO2      A  @SCM_LIB.SCM(SCH_1):SPI_PCH_MUXED_IO2
    2  SPI_PCH_IO2_FLASH_R1      B  @SCM_LIB.SCM(SCH_1):SPI_PCH_IO2_FLASH_R1

Q_RES  I21  R484   [Q_RES_0402LF-33       ,1%  ,1/A]
    1  SPI_PCH_MUXED_IO1      A  @SCM_LIB.SCM(SCH_1):SPI_PCH_MUXED_IO1
    2  SPI_PCH_IO1_FLASH_R1      B  @SCM_LIB.SCM(SCH_1):SPI_PCH_IO1_FLASH_R1

Q_RES  I20  R485   [Q_RES_0402LF-33       ,1%  ,1/A]
    1  SPI_PCH_MUXED_CS0_N      A  @SCM_LIB.SCM(SCH_1):SPI_PCH_MUXED_CS0_N
    2  SPI_PCH_CS0_FLASH_R1_N      B  @SCM_LIB.SCM(SCH_1):SPI_PCH_CS0_FLASH_R1_N

Q_RES  I19  R486   [Q_RES_0402LF-33       ,1%  ,1/A]
    1  SPI_PCH_MUXED_IO3      A  @SCM_LIB.SCM(SCH_1):SPI_PCH_MUXED_IO3
    2  SPI_PCH_IO3_FLASH_R1      B  @SCM_LIB.SCM(SCH_1):SPI_PCH_IO3_FLASH_R1

Q_RES  I51  R487   [Q_RES_0402LF-4.7K,1%,1/16W,EMPA]
    1  SPI_PCH_CS0_FLASH_R1_N      A  @SCM_LIB.SCM(SCH_1):SPI_PCH_CS0_FLASH_R1_N
    2  GND                B  @SCM_LIB.SCM(SCH_1):GND

Q_RES  I33  R488   [Q_RES_0402LF-4.7K,1%,1/16W,CHIA]
    2  SPI_PCH_IO2_FLASH_R1      B  @SCM_LIB.SCM(SCH_1):SPI_PCH_IO2_FLASH_R1
    1  P3V3_AUX           A  @SCM_LIB.SCM(SCH_1):P3V3_AUX

Q_RES  I326  R489   [Q_RES_0402LF-33       ,1%  ,1/A]
    2  BMC_CPLD_GPIO_22_R1      B  @SCM_LIB.SCM(SCH_1):BMC_CPLD_GPIO_22_R1
    1  BMC_CPLD_GPIO_22      A  @SCM_LIB.SCM(SCH_1):BMC_CPLD_GPIO_22

Q_RES  I34  R490   [Q_RES_0402LF-4.7K,1%,1/16W,CHIA]
    2  SPI_PCH_CS0_FLASH_R1_N      B  @SCM_LIB.SCM(SCH_1):SPI_PCH_CS0_FLASH_R1_N
    1  P3V3_AUX           A  @SCM_LIB.SCM(SCH_1):P3V3_AUX

Q_RES  I340  R491   [Q_RES_0402LF-33       ,1%  ,1/A]
    2  BMC_CPLD_GPIO_23_R1      B  @SCM_LIB.SCM(SCH_1):BMC_CPLD_GPIO_23_R1
    1  BMC_CPLD_GPIO_23      A  @SCM_LIB.SCM(SCH_1):BMC_CPLD_GPIO_23

Q_RES  I35  R492   [Q_RES_0402LF-4.7K,1%,1/16W,CHIA]
    2  SPI_PCH_IO3_FLASH_R1      B  @SCM_LIB.SCM(SCH_1):SPI_PCH_IO3_FLASH_R1
    1  P3V3_AUX           A  @SCM_LIB.SCM(SCH_1):P3V3_AUX

Q_RES  I343  R493   [Q_RES_0402LF-33       ,1%  ,1/A]
    2  BMC_CPLD_GPIO_24_R1      B  @SCM_LIB.SCM(SCH_1):BMC_CPLD_GPIO_24_R1
    1  BMC_CPLD_GPIO_24      A  @SCM_LIB.SCM(SCH_1):BMC_CPLD_GPIO_24

Q_RES  I335  R494   [Q_RES_0402LF-33       ,1%  ,1/A]
    1  RST_BMC_SELF_HW_R1      A  @SCM_LIB.SCM(SCH_1):RST_BMC_SELF_HW_R1
    2  RST_BMC_SELF_HW      B  @SCM_LIB.SCM(SCH_1):RST_BMC_SELF_HW

Q_RES  I449  R495   [Q_RES_0402LF-0,5%,1/16W,CHIP,CA]
    2  BMC_CPLD_GPIO_1_R2      B  @SCM_LIB.SCM(SCH_1):BMC_CPLD_GPIO_1_R2
    1  BMC_CPLD_GPIO_1      A  @SCM_LIB.SCM(SCH_1):BMC_CPLD_GPIO_1

Q_RES  I48  R496   [Q_RES_0402LF-4.7K,1%,1/16W,EMPA]
    2  RST_SPI_PCH_FLASH_R1_N      B  @SCM_LIB.SCM(SCH_1):RST_SPI_PCH_FLASH_R1_N
    1  P3V3_AUX           A  @SCM_LIB.SCM(SCH_1):P3V3_AUX

Q_RES  I78  R497   [Q_RES_0402LF-10K,1%,1/16W,CHIPA]
    1  P3V3_AUX           A  @SCM_LIB.SCM(SCH_1):P3V3_AUX
    2  IRQ_TPM_SPI_N      B  @SCM_LIB.SCM(SCH_1):IRQ_TPM_SPI_N

Q_RES  I61  R498   [Q_RES_0402LF-0,5%,1/16W,CHIP,CA]
    2  SPI_SYS_R_MOSI      B  @SCM_LIB.SCM(SCH_1):SPI_SYS_R_MOSI
    1  SPI_SYS_R1_MOSI      A  @SCM_LIB.SCM(SCH_1):SPI_SYS_R1_MOSI

Q_RES  I62  R499   [Q_RES_0402LF-0,5%,1/16W,CHIP,CA]
    2  SPI_SYS_R_MISO      B  @SCM_LIB.SCM(SCH_1):SPI_SYS_R_MISO
    1  SPI_SYS_R1_MISO      A  @SCM_LIB.SCM(SCH_1):SPI_SYS_R1_MISO

Q_RES  I65  R500   [Q_RES_0402LF-0,5%,1/16W,CHIP,CA]
    2  SPI_TPM_CS_R_N      B  @SCM_LIB.SCM(SCH_1):SPI_TPM_CS_R_N
    1  SPI_TPM_CS_N_R      A  @SCM_LIB.SCM(SCH_1):SPI_TPM_CS_N_R

Q_RES  I58  R501   [Q_RES_0402LF-0,5%,1/16W,CHIP,CA]
    2  SPI_SYS_R_CLK      B  @SCM_LIB.SCM(SCH_1):SPI_SYS_R_CLK
    1  SPI_SYS_R1_CLK      A  @SCM_LIB.SCM(SCH_1):SPI_SYS_R1_CLK

Q_RES  I112  R502   [Q_RES_0402LF-4.7K,1%,1/16W,CHIA]
    1  P3V3_AUX           A  @SCM_LIB.SCM(SCH_1):P3V3_AUX
    2  FM_ID_LED_N        B  @SCM_LIB.SCM(SCH_1):FM_ID_LED_N

Q_RES  I60  R503   [Q_RES_0402LF-0,5%,1/16W,CHIP,CA]
    1  RST_PLTRST_TPM_N      A  @SCM_LIB.SCM(SCH_1):RST_PLTRST_TPM_N
    2  RST_PLTRST_N       B  @SCM_LIB.SCM(SCH_1):RST_PLTRST_N

Q_RES  I82  R504   [Q_RES_0402LF-8.2K     ,5%  ,1/A]
    2  REAR_ID_RST_BTN_N      B  @SCM_LIB.SCM(SCH_1):REAR_ID_RST_BTN_N
    1  P3V3_AUX           A  @SCM_LIB.SCM(SCH_1):P3V3_AUX

Q_RES  I74  R505   [Q_RES_0402LF-0,5%,1/16W,CHIP,CA]
    2  IRQ_TPM_SPI_R_N      B  @SCM_LIB.SCM(SCH_1):IRQ_TPM_SPI_R_N
    1  IRQ_TPM_SPI_N      A  @SCM_LIB.SCM(SCH_1):IRQ_TPM_SPI_N

Q_RES  I49  R506   [Q_RES_0402LF-100,1%,1/16W,CHIPA]
    1  PD_BMC_DEBUG       A  @SCM_LIB.SCM(SCH_1):PD_BMC_DEBUG
    2  GND                B  @SCM_LIB.SCM(SCH_1):GND

Q_RES  I50  R507   [Q_RES_0402LF-100,1%,1/16W,CHIPA]
    1  PD_JTAGEN          A  @SCM_LIB.SCM(SCH_1):PD_JTAGEN
    2  GND                B  @SCM_LIB.SCM(SCH_1):GND

Q_RES  I45  R508   [Q_RES_0402LF-10K,1%,1/16W,CHIPA]
    1  P3V3_AUX           A  @SCM_LIB.SCM(SCH_1):P3V3_AUX
    2  MB_JTAG_PLD_R_JTAGEN      B  @SCM_LIB.SCM(SCH_1):MB_JTAG_PLD_R_JTAGEN

Q_RES  I47  R509   [Q_RES_0402LF-33       ,1%  ,1/A]
    1  MB_JTAG_PLD_R_JTAGEN      A  @SCM_LIB.SCM(SCH_1):MB_JTAG_PLD_R_JTAGEN
    2  JTAG_SCM_PLD_JTAGEN      B  @SCM_LIB.SCM(SCH_1):JTAG_SCM_PLD_JTAGEN

Q_RES  I126  R510   [Q_RES_0402LF-33       ,1%  ,1/A]
    1  JTAG_SCM_TCK       A  @SCM_LIB.SCM(SCH_1):JTAG_SCM_TCK
    2  JTAG_SCM_PLD_TCK      B  @SCM_LIB.SCM(SCH_1):JTAG_SCM_PLD_TCK

Q_RES  I127  R511   [Q_RES_0402LF-33       ,1%  ,1/A]
    1  JTAG_SCM_TMS       A  @SCM_LIB.SCM(SCH_1):JTAG_SCM_TMS
    2  JTAG_SCM_PLD_TMS      B  @SCM_LIB.SCM(SCH_1):JTAG_SCM_PLD_TMS

Q_RES  I129  R512   [Q_RES_0402LF-33       ,1%  ,1/A]
    1  JTAG_SCM_TDI       A  @SCM_LIB.SCM(SCH_1):JTAG_SCM_TDI
    2  JTAG_SCM_PLD_TDI      B  @SCM_LIB.SCM(SCH_1):JTAG_SCM_PLD_TDI

Q_RES  I128  R513   [Q_RES_0402LF-33       ,1%  ,1/A]
    1  JTAG_SCM_TDO       A  @SCM_LIB.SCM(SCH_1):JTAG_SCM_TDO
    2  JTAG_SCM_PLD_TDO      B  @SCM_LIB.SCM(SCH_1):JTAG_SCM_PLD_TDO

Q_RES  I94  R514   [Q_RES_0402LF-33       ,1%  ,1/A]
    1  JTAG_SCM_PLD_TCK      A  @SCM_LIB.SCM(SCH_1):JTAG_SCM_PLD_TCK
    2  JTAG_SCM_CONN_TCK      B  @SCM_LIB.SCM(SCH_1):JTAG_SCM_CONN_TCK

Q_RES  I96  R515   [Q_RES_0402LF-33       ,1%  ,1/A]
    1  JTAG_SCM_PLD_TMS      A  @SCM_LIB.SCM(SCH_1):JTAG_SCM_PLD_TMS
    2  JTAG_SCM_CONN_TMS      B  @SCM_LIB.SCM(SCH_1):JTAG_SCM_CONN_TMS

Q_RES  I95  R516   [Q_RES_0402LF-33       ,1%  ,1/A]
    1  JTAG_SCM_PLD_TDI      A  @SCM_LIB.SCM(SCH_1):JTAG_SCM_PLD_TDI
    2  JTAG_SCM_CONN_TDI      B  @SCM_LIB.SCM(SCH_1):JTAG_SCM_CONN_TDI

Q_RES  I97  R517   [Q_RES_0402LF-33       ,1%  ,1/A]
    1  JTAG_SCM_PLD_TDO      A  @SCM_LIB.SCM(SCH_1):JTAG_SCM_PLD_TDO
    2  JTAG_SCM_CONN_TDO      B  @SCM_LIB.SCM(SCH_1):JTAG_SCM_CONN_TDO

Q_RES  I23  R518   [Q_RES_0402LF-33       ,1%  ,1/A]
    1  JTAG_SCM_PLD_R1_JTAGEN      A  @SCM_LIB.SCM(SCH_1):JTAG_SCM_PLD_R1_JTAGEN
    2  JTAG_SCM_PLD_JTAGEN      B  @SCM_LIB.SCM(SCH_1):JTAG_SCM_PLD_JTAGEN

Q_RES  I451  R519   [Q_RES_0402LF-0,5%,1/16W,CHIP,CA]
    2  BMC_CPLD_GPIO_2_R2      B  @SCM_LIB.SCM(SCH_1):BMC_CPLD_GPIO_2_R2
    1  BMC_CPLD_GPIO_2      A  @SCM_LIB.SCM(SCH_1):BMC_CPLD_GPIO_2

Q_RES  I453  R520   [Q_RES_0402LF-0,5%,1/16W,CHIP,CA]
    2  BMC_CPLD_GPIO_3_R2      B  @SCM_LIB.SCM(SCH_1):BMC_CPLD_GPIO_3_R2
    1  BMC_CPLD_GPIO_3      A  @SCM_LIB.SCM(SCH_1):BMC_CPLD_GPIO_3

Q_RES  I91  R521   [Q_RES_0402LF-4.7K,5%,1/16W,CHIA]
    2  SMB_BMC_MM10_SDA      B  @SCM_LIB.SCM(SCH_1):SMB_BMC_MM10_SDA
    1  P3V3_AUX           A  @SCM_LIB.SCM(SCH_1):P3V3_AUX

Q_RES  I458  R522   [Q_RES_0402LF-33       ,1%  ,1/A]
    1  BMC_CPLD_GPIO_4_R2      A  @SCM_LIB.SCM(SCH_1):BMC_CPLD_GPIO_4_R2
    2  BMC_CPLD_GPIO_4      B  @SCM_LIB.SCM(SCH_1):BMC_CPLD_GPIO_4

Q_RES  I119  R523   [Q_RES_0402LF-10K,0.10%,1/16W,CA]
    1  P3V3_RGM           A  @SCM_LIB.SCM(SCH_1):P3V3_RGM
    2  JTAG_SCM_TDO       B  @SCM_LIB.SCM(SCH_1):JTAG_SCM_TDO

Q_RES  I460  R524   [Q_RES_0402LF-33       ,1%  ,1/A]
    1  BMC_CPLD_GPIO_5_R2      A  @SCM_LIB.SCM(SCH_1):BMC_CPLD_GPIO_5_R2
    2  BMC_CPLD_GPIO_5      B  @SCM_LIB.SCM(SCH_1):BMC_CPLD_GPIO_5

Q_RES  I462  R525   [Q_RES_0402LF-33       ,1%  ,1/A]
    1  BMC_CPLD_GPIO_6_R2      A  @SCM_LIB.SCM(SCH_1):BMC_CPLD_GPIO_6_R2
    2  BMC_CPLD_GPIO_6      B  @SCM_LIB.SCM(SCH_1):BMC_CPLD_GPIO_6

Q_RES  I464  R526   [Q_RES_0402LF-33       ,1%  ,1/A]
    1  BMC_CPLD_GPIO_7_R2      A  @SCM_LIB.SCM(SCH_1):BMC_CPLD_GPIO_7_R2
    2  BMC_CPLD_GPIO_7      B  @SCM_LIB.SCM(SCH_1):BMC_CPLD_GPIO_7

Q_RES  I169  R527   [Q_RES_0402LF-0,5%,1/16W,CHIP,CA]
    1  USB_HOST_BMC_B_R_DP      A  @SCM_LIB.SCM(SCH_1):USB_HOST_BMC_B_R_DP
    2  USB_HOST_BMC_B_DP      B  @SCM_LIB.SCM(SCH_1):USB_HOST_BMC_B_DP

Q_RES  I168  R528   [Q_RES_0402LF-0,5%,1/16W,CHIP,CA]
    1  USB_HOST_BMC_B_R_DN      A  @SCM_LIB.SCM(SCH_1):USB_HOST_BMC_B_R_DN
    2  USB_HOST_BMC_B_DN      B  @SCM_LIB.SCM(SCH_1):USB_HOST_BMC_B_DN

Q_RES  I84  R529   [Q_RES_0402LF-0,5%,1/16W,EMPTY,A]
    2  NC                 B  NC
    1  SPI_SYS_R1_CLK      A  @SCM_LIB.SCM(SCH_1):SPI_SYS_R1_CLK

Q_RES  I85  R530   [Q_RES_0402LF-0,5%,1/16W,EMPTY,A]
    2  NC                 B  NC
    1  SPI_SYS_R1_MOSI      A  @SCM_LIB.SCM(SCH_1):SPI_SYS_R1_MOSI

Q_RES  I480  R531   [Q_RES_0402LF-33       ,1%  ,1/A]
    1  BMC_CPLD_GPIO_8_R2      A  @SCM_LIB.SCM(SCH_1):BMC_CPLD_GPIO_8_R2
    2  BMC_CPLD_GPIO_8      B  @SCM_LIB.SCM(SCH_1):BMC_CPLD_GPIO_8

Q_RES  I34  R532   [Q_RES_0402LF-33       ,1%  ,1/B]
    2  EMMC_DT0_R         B  @SCM_LIB.SCM(SCH_1):EMMC_DT0_R
    1  BMC_EMMC_DT0       A  @SCM_LIB.SCM(SCH_1):BMC_EMMC_DT0

Q_RES  I478  R533   [Q_RES_0402LF-33       ,1%  ,1/A]
    1  BMC_CPLD_GPIO_9_R2      A  @SCM_LIB.SCM(SCH_1):BMC_CPLD_GPIO_9_R2
    2  BMC_CPLD_GPIO_9      B  @SCM_LIB.SCM(SCH_1):BMC_CPLD_GPIO_9

Q_RES  I476  R534   [Q_RES_0402LF-33       ,1%  ,1/A]
    1  BMC_CPLD_GPIO_10_R2      A  @SCM_LIB.SCM(SCH_1):BMC_CPLD_GPIO_10_R2
    2  BMC_CPLD_GPIO_10      B  @SCM_LIB.SCM(SCH_1):BMC_CPLD_GPIO_10

Q_RES  I474  R535   [Q_RES_0402LF-33       ,1%  ,1/A]
    1  BMC_CPLD_GPIO_11_R2      A  @SCM_LIB.SCM(SCH_1):BMC_CPLD_GPIO_11_R2
    2  BMC_CPLD_GPIO_11      B  @SCM_LIB.SCM(SCH_1):BMC_CPLD_GPIO_11

Q_RES  I472  R536   [Q_RES_0402LF-33       ,1%  ,1/A]
    1  BMC_CPLD_GPIO_12_R2      A  @SCM_LIB.SCM(SCH_1):BMC_CPLD_GPIO_12_R2
    2  BMC_CPLD_GPIO_12      B  @SCM_LIB.SCM(SCH_1):BMC_CPLD_GPIO_12

Q_RES  I470  R537   [Q_RES_0402LF-33       ,1%  ,1/A]
    1  BMC_CPLD_GPIO_13_R2      A  @SCM_LIB.SCM(SCH_1):BMC_CPLD_GPIO_13_R2
    2  BMC_CPLD_GPIO_13      B  @SCM_LIB.SCM(SCH_1):BMC_CPLD_GPIO_13

Q_RES  I137  R538   [Q_RES_0402LF-22,5%,1/16W,CHIP,A]
    1  RGMII_BMC_TX_R_CLK      A  @SCM_LIB.SCM(SCH_1):RGMII_BMC_TX_R_CLK
    2  RGMII_BMC_TX_CLK      B  @SCM_LIB.SCM(SCH_1):RGMII_BMC_TX_CLK

Q_RES  I138  R539   [Q_RES_0402LF-22,5%,1/16W,CHIP,A]
    1  RGMII_BMC_TX_R_CTRL      A  @SCM_LIB.SCM(SCH_1):RGMII_BMC_TX_R_CTRL
    2  RGMII_BMC_TX_CTRL      B  @SCM_LIB.SCM(SCH_1):RGMII_BMC_TX_CTRL

Q_RES  I468  R540   [Q_RES_0402LF-33       ,1%  ,1/A]
    1  BMC_CPLD_GPIO_14_R2      A  @SCM_LIB.SCM(SCH_1):BMC_CPLD_GPIO_14_R2
    2  BMC_CPLD_GPIO_14      B  @SCM_LIB.SCM(SCH_1):BMC_CPLD_GPIO_14

Q_RES  I466  R541   [Q_RES_0402LF-33       ,1%  ,1/A]
    1  BMC_CPLD_GPIO_15_R2      A  @SCM_LIB.SCM(SCH_1):BMC_CPLD_GPIO_15_R2
    2  BMC_CPLD_GPIO_15      B  @SCM_LIB.SCM(SCH_1):BMC_CPLD_GPIO_15

Q_RES  I340  R542   [Q_RES_0402LF-0,5%,1/16W,CHIP,CA]
    2  BMC_CPLD_GPIO_16_R2      B  @SCM_LIB.SCM(SCH_1):BMC_CPLD_GPIO_16_R2
    1  BMC_CPLD_GPIO_16      A  @SCM_LIB.SCM(SCH_1):BMC_CPLD_GPIO_16

Q_RES  I18  R543   [Q_RES_0402LF-33       ,1%  ,1/A]
    2  SPI_BMC_CLK_FLASH_R2      B  @SCM_LIB.SCM(SCH_1):SPI_BMC_CLK_FLASH_R2
    1  SPI_BMC_BOOT_CLK      A  @SCM_LIB.SCM(SCH_1):SPI_BMC_BOOT_CLK

Q_RES  I16  R544   [Q_RES_0402LF-33       ,1%  ,1/A]
    2  SPI_BMC_IO0_FLASH_R2      B  @SCM_LIB.SCM(SCH_1):SPI_BMC_IO0_FLASH_R2
    1  SPI_BMC_BOOT_MOSI      A  @SCM_LIB.SCM(SCH_1):SPI_BMC_BOOT_MOSI

Q_RES  I17  R545   [Q_RES_0402LF-33       ,1%  ,1/A]
    2  SPI_BMC_IO2_FLASH_R2      B  @SCM_LIB.SCM(SCH_1):SPI_BMC_IO2_FLASH_R2
    1  SPI_BMC_BOOT_IO2      A  @SCM_LIB.SCM(SCH_1):SPI_BMC_BOOT_IO2

Q_RES  I15  R546   [Q_RES_0402LF-33       ,1%  ,1/A]
    2  SPI_BMC_IO1_FLASH_R2      B  @SCM_LIB.SCM(SCH_1):SPI_BMC_IO1_FLASH_R2
    1  SPI_BMC_BOOT_MISO      A  @SCM_LIB.SCM(SCH_1):SPI_BMC_BOOT_MISO

Q_RES  I14  R547   [Q_RES_0402LF-33       ,1%  ,1/A]
    2  SPI_BMC_CS1_FLASH_R2_N      B  @SCM_LIB.SCM(SCH_1):SPI_BMC_CS1_FLASH_R2_N
    1  SPI_BMC_BOOT_CS1_R_N      A  @SCM_LIB.SCM(SCH_1):SPI_BMC_BOOT_CS1_R_N

Q_RES  I13  R548   [Q_RES_0402LF-33       ,1%  ,1/A]
    2  SPI_BMC_IO3_FLASH_R2      B  @SCM_LIB.SCM(SCH_1):SPI_BMC_IO3_FLASH_R2
    1  SPI_BMC_BOOT_IO3      A  @SCM_LIB.SCM(SCH_1):SPI_BMC_BOOT_IO3

Q_RES  I26  R549   [Q_RES_0402LF-33       ,1%  ,1/A]
    2  SPI_BMC_CLK_FLASH_R1      B  @SCM_LIB.SCM(SCH_1):SPI_BMC_CLK_FLASH_R1
    1  SPI_BMC_BOOT_CLK      A  @SCM_LIB.SCM(SCH_1):SPI_BMC_BOOT_CLK

Q_RES  I27  R550   [Q_RES_0402LF-33       ,1%  ,1/A]
    2  SPI_BMC_IO0_FLASH_R1      B  @SCM_LIB.SCM(SCH_1):SPI_BMC_IO0_FLASH_R1
    1  SPI_BMC_BOOT_MOSI      A  @SCM_LIB.SCM(SCH_1):SPI_BMC_BOOT_MOSI

Q_RES  I24  R551   [Q_RES_0402LF-33       ,1%  ,1/A]
    2  SPI_BMC_IO2_FLASH_R1      B  @SCM_LIB.SCM(SCH_1):SPI_BMC_IO2_FLASH_R1
    1  SPI_BMC_BOOT_IO2      A  @SCM_LIB.SCM(SCH_1):SPI_BMC_BOOT_IO2

Q_RES  I25  R552   [Q_RES_0402LF-33       ,1%  ,1/A]
    2  SPI_BMC_IO1_FLASH_R1      B  @SCM_LIB.SCM(SCH_1):SPI_BMC_IO1_FLASH_R1
    1  SPI_BMC_BOOT_MISO      A  @SCM_LIB.SCM(SCH_1):SPI_BMC_BOOT_MISO

Q_RES  I23  R553   [Q_RES_0402LF-33       ,1%  ,1/A]
    2  SPI_BMC_CS0_FLASH_R1_N      B  @SCM_LIB.SCM(SCH_1):SPI_BMC_CS0_FLASH_R1_N
    1  SPI_BMC_BOOT_CS0_R_N      A  @SCM_LIB.SCM(SCH_1):SPI_BMC_BOOT_CS0_R_N

Q_RES  I22  R554   [Q_RES_0402LF-33       ,1%  ,1/A]
    2  SPI_BMC_IO3_FLASH_R1      B  @SCM_LIB.SCM(SCH_1):SPI_BMC_IO3_FLASH_R1
    1  SPI_BMC_BOOT_IO3      A  @SCM_LIB.SCM(SCH_1):SPI_BMC_BOOT_IO3

Q_RES  I28  R555   [Q_RES_0402LF-4.7K,1%,1/16W,CHIA]
    2  SPI_BMC_IO2_FLASH_R1      B  @SCM_LIB.SCM(SCH_1):SPI_BMC_IO2_FLASH_R1
    1  P3V3_AUX           A  @SCM_LIB.SCM(SCH_1):P3V3_AUX

Q_RES  I19  R556   [Q_RES_0402LF-4.7K,1%,1/16W,EMPA]
    2  SPI_BMC_IO2_FLASH_R2      B  @SCM_LIB.SCM(SCH_1):SPI_BMC_IO2_FLASH_R2
    1  P3V3_AUX           A  @SCM_LIB.SCM(SCH_1):P3V3_AUX

Q_RES  I37  R557   [Q_RES_0402LF-4.7K,1%,1/16W,CHIA]
    2  SPI_BMC_CS0_FLASH_R1_N      B  @SCM_LIB.SCM(SCH_1):SPI_BMC_CS0_FLASH_R1_N
    1  P3V3_AUX           A  @SCM_LIB.SCM(SCH_1):P3V3_AUX

Q_RES  I32  R558   [Q_RES_0402LF-4.7K,1%,1/16W,EMPA]
    2  SPI_BMC_CS1_FLASH_R2_N      B  @SCM_LIB.SCM(SCH_1):SPI_BMC_CS1_FLASH_R2_N
    1  P3V3_AUX           A  @SCM_LIB.SCM(SCH_1):P3V3_AUX

Q_RES  I58  R559   [Q_RES_0402LF-4.7K,1%,1/16W,CHIA]
    2  SPI_BMC_IO3_FLASH_R1      B  @SCM_LIB.SCM(SCH_1):SPI_BMC_IO3_FLASH_R1
    1  P3V3_RGM           A  @SCM_LIB.SCM(SCH_1):P3V3_RGM

Q_RES  I56  R560   [Q_RES_0402LF-4.7K,1%,1/16W,EMPA]
    2  SPI_BMC_IO3_FLASH_R2      B  @SCM_LIB.SCM(SCH_1):SPI_BMC_IO3_FLASH_R2
    1  P3V3_RGM           A  @SCM_LIB.SCM(SCH_1):P3V3_RGM

Q_RES  I44  R561   [Q_RES_0402LF-33       ,1%  ,1/B]
    2  RST_SPI_FLASH_N      B  @SCM_LIB.SCM(SCH_1):RST_SPI_FLASH_N
    1  RST_SPI_BMC_FLASH_R2_N      A  @SCM_LIB.SCM(SCH_1):RST_SPI_BMC_FLASH_R2_N

Q_RES  I46  R562   [Q_RES_0402LF-33       ,1%  ,1/B]
    2  RST_SPI_FLASH_N      B  @SCM_LIB.SCM(SCH_1):RST_SPI_FLASH_N
    1  RST_SPI_BMC_FLASH_R1_N      A  @SCM_LIB.SCM(SCH_1):RST_SPI_BMC_FLASH_R1_N

Q_RES  I48  R563   [Q_RES_0402LF-4.7K,1%,1/16W,CHIA]
    2  RST_SPI_FLASH_N      B  @SCM_LIB.SCM(SCH_1):RST_SPI_FLASH_N
    1  P3V3_AUX           A  @SCM_LIB.SCM(SCH_1):P3V3_AUX

Q_RES  I160  R564   [Q_RES_0402LF-0,5%,1/16W,CHIP,CA]
    2  SYS_PWRBTN_N       B  @SCM_LIB.SCM(SCH_1):SYS_PWRBTN_N
    1  SYS_BMC_PWRBTN_R_N      A  @SCM_LIB.SCM(SCH_1):SYS_BMC_PWRBTN_R_N

Q_RES  I127  R565   [Q_RES_0402LF-0,5%,1/16W,CHIP,CA]
    1  ID_RST_BTN_BMC_R_N      A  @SCM_LIB.SCM(SCH_1):ID_RST_BTN_BMC_R_N
    2  ID_RST_BTN_BMC_N      B  @SCM_LIB.SCM(SCH_1):ID_RST_BTN_BMC_N

Q_RES  I128  R566   [Q_RES_0402LF-0,5%,1/16W,CHIP,CA]
    1  RST_BMC_RSTBTN_OUT_R_N      A  @SCM_LIB.SCM(SCH_1):RST_BMC_RSTBTN_OUT_R_N
    2  RST_BMC_RSTBTN_OUT_N      B  @SCM_LIB.SCM(SCH_1):RST_BMC_RSTBTN_OUT_N

Q_RES  I274  R567   [Q_RES_0402LF-33       ,1%  ,1/A]
    2  SMB_BMC_MM7_SCL      B  @SCM_LIB.SCM(SCH_1):SMB_BMC_MM7_SCL
    1  SMB_BMC_MM7_R_SCL      A  @SCM_LIB.SCM(SCH_1):SMB_BMC_MM7_R_SCL

Q_RES  I93  R568   [Q_RES_0402LF-1K,1%,1/16W,CHIP,A]
    2  PWR_LED_P3V3_AUX      B  @SCM_LIB.SCM(SCH_1):PWR_LED_P3V3_AUX
    1  P3V3_AUX           A  @SCM_LIB.SCM(SCH_1):P3V3_AUX

Q_RES  I98  R569   [Q_RES_0402LF-1K,1%,1/16W,CHIP,A]
    1  P3V3_AUX           A  @SCM_LIB.SCM(SCH_1):P3V3_AUX
    2  ID_LED_P3V3_AUX      B  @SCM_LIB.SCM(SCH_1):ID_LED_P3V3_AUX

Q_RES  I275  R570   [Q_RES_0402LF-33       ,1%  ,1/A]
    2  SMB_BMC_MM7_SDA      B  @SCM_LIB.SCM(SCH_1):SMB_BMC_MM7_SDA
    1  SMB_BMC_MM7_R_SDA      A  @SCM_LIB.SCM(SCH_1):SMB_BMC_MM7_R_SDA

Q_RES  I407  R571   [Q_RES_0402LF-0,5%,1/16W,CHIP,CA]
    2  IRQ_BMC_PCH_NMI_R_N      B  @SCM_LIB.SCM(SCH_1):IRQ_BMC_PCH_NMI_R_N
    1  IRQ_BMC_PCH_NMI_N      A  @SCM_LIB.SCM(SCH_1):IRQ_BMC_PCH_NMI_N

Q_RES  I356  R572   [Q_RES_0402LF-0,5%,1/16W,CHIP,CA]
    2  BMC_CPLD_GPIO_17_R2      B  @SCM_LIB.SCM(SCH_1):BMC_CPLD_GPIO_17_R2
    1  BMC_CPLD_GPIO_17      A  @SCM_LIB.SCM(SCH_1):BMC_CPLD_GPIO_17

Q_RES  I354  R573   [Q_RES_0402LF-0,5%,1/16W,CHIP,CA]
    2  BMC_CPLD_GPIO_18_R2      B  @SCM_LIB.SCM(SCH_1):BMC_CPLD_GPIO_18_R2
    1  BMC_CPLD_GPIO_18      A  @SCM_LIB.SCM(SCH_1):BMC_CPLD_GPIO_18

Q_RES  I352  R574   [Q_RES_0402LF-0,5%,1/16W,CHIP,CA]
    2  BMC_CPLD_GPIO_19_R2      B  @SCM_LIB.SCM(SCH_1):BMC_CPLD_GPIO_19_R2
    1  BMC_CPLD_GPIO_19      A  @SCM_LIB.SCM(SCH_1):BMC_CPLD_GPIO_19

Q_RES  I350  R575   [Q_RES_0402LF-0,5%,1/16W,CHIP,CA]
    2  BMC_CPLD_GPIO_20_R2      B  @SCM_LIB.SCM(SCH_1):BMC_CPLD_GPIO_20_R2
    1  BMC_CPLD_GPIO_20      A  @SCM_LIB.SCM(SCH_1):BMC_CPLD_GPIO_20

Q_RES  I348  R576   [Q_RES_0402LF-0,5%,1/16W,CHIP,CA]
    2  BMC_CPLD_GPIO_21_R2      B  @SCM_LIB.SCM(SCH_1):BMC_CPLD_GPIO_21_R2
    1  BMC_CPLD_GPIO_21      A  @SCM_LIB.SCM(SCH_1):BMC_CPLD_GPIO_21

Q_RES  I346  R577   [Q_RES_0402LF-0,5%,1/16W,CHIP,CA]
    2  BMC_CPLD_GPIO_22_R2      B  @SCM_LIB.SCM(SCH_1):BMC_CPLD_GPIO_22_R2
    1  BMC_CPLD_GPIO_22      A  @SCM_LIB.SCM(SCH_1):BMC_CPLD_GPIO_22

Q_RES  I344  R578   [Q_RES_0402LF-0,5%,1/16W,CHIP,CA]
    2  BMC_CPLD_GPIO_23_R2      B  @SCM_LIB.SCM(SCH_1):BMC_CPLD_GPIO_23_R2
    1  BMC_CPLD_GPIO_23      A  @SCM_LIB.SCM(SCH_1):BMC_CPLD_GPIO_23

Q_RES  I342  R579   [Q_RES_0402LF-0,5%,1/16W,CHIP,CA]
    2  BMC_CPLD_GPIO_24_R2      B  @SCM_LIB.SCM(SCH_1):BMC_CPLD_GPIO_24_R2
    1  BMC_CPLD_GPIO_24      A  @SCM_LIB.SCM(SCH_1):BMC_CPLD_GPIO_24

Q_RES  I321  R580   [Q_RES_0402LF-33       ,1%  ,1/A]
    2  SMB_BMC_MM9_SCL      B  @SCM_LIB.SCM(SCH_1):SMB_BMC_MM9_SCL
    1  SMB_BMC_MM9_R_SCL      A  @SCM_LIB.SCM(SCH_1):SMB_BMC_MM9_R_SCL

Q_RES  I2   R581   [Q_RES_0402LF-4.7K,5%,1/16W,CHIA]
    1  P3V3_AUX           A  @SCM_LIB.SCM(SCH_1):P3V3_AUX
    2  BMC_CPLD_GPIO_1      B  @SCM_LIB.SCM(SCH_1):BMC_CPLD_GPIO_1

Q_RES  I318  R582   [Q_RES_0402LF-33       ,1%  ,1/A]
    2  SMB_BMC_MM9_SDA      B  @SCM_LIB.SCM(SCH_1):SMB_BMC_MM9_SDA
    1  SMB_BMC_MM9_R_SDA      A  @SCM_LIB.SCM(SCH_1):SMB_BMC_MM9_R_SDA

Q_RES  I319  R583   [Q_RES_0402LF-33       ,1%  ,1/A]
    2  SMB_BMC_MM10_SCL      B  @SCM_LIB.SCM(SCH_1):SMB_BMC_MM10_SCL
    1  SMB_BMC_MM10_R_SCL      A  @SCM_LIB.SCM(SCH_1):SMB_BMC_MM10_R_SCL

Q_RES  I320  R584   [Q_RES_0402LF-33       ,1%  ,1/A]
    2  SMB_BMC_MM10_SDA      B  @SCM_LIB.SCM(SCH_1):SMB_BMC_MM10_SDA
    1  SMB_BMC_MM10_R_SDA      A  @SCM_LIB.SCM(SCH_1):SMB_BMC_MM10_R_SDA

Q_RES  I87  R585   [Q_RES_0402LF-0,5%,1/16W,EMPTY,A]
    2  NC                 B  NC
    1  SPI_SYS_R1_MISO      A  @SCM_LIB.SCM(SCH_1):SPI_SYS_R1_MISO

Q_RES  I49  R586   [Q_RES_0402LF-4.7K,5%,1/16W,CHIA]
    1  P3V3_AUX           A  @SCM_LIB.SCM(SCH_1):P3V3_AUX
    2  BMC_CPLD_GPIO_2      B  @SCM_LIB.SCM(SCH_1):BMC_CPLD_GPIO_2

Q_RES  I47  R587   [Q_RES_0402LF-4.7K,5%,1/16W,CHIA]
    1  P3V3_AUX           A  @SCM_LIB.SCM(SCH_1):P3V3_AUX
    2  BMC_CPLD_GPIO_3      B  @SCM_LIB.SCM(SCH_1):BMC_CPLD_GPIO_3

Q_RES  I45  R588   [Q_RES_0402LF-4.7K,5%,1/16W,CHIA]
    1  P3V3_AUX           A  @SCM_LIB.SCM(SCH_1):P3V3_AUX
    2  BMC_CPLD_GPIO_4      B  @SCM_LIB.SCM(SCH_1):BMC_CPLD_GPIO_4

Q_RES  I316  R589   [Q_RES_0402LF-33       ,1%  ,1/A]
    2  SMB_BMC_MM3_SCL      B  @SCM_LIB.SCM(SCH_1):SMB_BMC_MM3_SCL
    1  SMB_BMC_MM3_R_SCL      A  @SCM_LIB.SCM(SCH_1):SMB_BMC_MM3_R_SCL

Q_RES  I317  R590   [Q_RES_0402LF-33       ,1%  ,1/A]
    2  SMB_BMC_MM3_SDA      B  @SCM_LIB.SCM(SCH_1):SMB_BMC_MM3_SDA
    1  SMB_BMC_MM3_R_SDA      A  @SCM_LIB.SCM(SCH_1):SMB_BMC_MM3_R_SDA

Q_RES  I43  R591   [Q_RES_0402LF-4.7K,5%,1/16W,CHIA]
    1  P3V3_AUX           A  @SCM_LIB.SCM(SCH_1):P3V3_AUX
    2  BMC_CPLD_GPIO_5      B  @SCM_LIB.SCM(SCH_1):BMC_CPLD_GPIO_5

Q_RES  I41  R592   [Q_RES_0402LF-4.7K,5%,1/16W,CHIA]
    1  P3V3_AUX           A  @SCM_LIB.SCM(SCH_1):P3V3_AUX
    2  BMC_CPLD_GPIO_6      B  @SCM_LIB.SCM(SCH_1):BMC_CPLD_GPIO_6

Q_RES  I39  R593   [Q_RES_0402LF-4.7K,5%,1/16W,CHIA]
    1  P3V3_AUX           A  @SCM_LIB.SCM(SCH_1):P3V3_AUX
    2  BMC_CPLD_GPIO_7      B  @SCM_LIB.SCM(SCH_1):BMC_CPLD_GPIO_7

Q_RES  I360  R594   [Q_RES_0402LF-33       ,1%  ,1/A]
    2  SPI_TPM_CS_R_N      B  @SCM_LIB.SCM(SCH_1):SPI_TPM_CS_R_N
    1  SPI_TPM_CS_N       A  @SCM_LIB.SCM(SCH_1):SPI_TPM_CS_N

Q_RES  I37  R595   [Q_RES_0402LF-4.7K,5%,1/16W,CHIA]
    1  P3V3_AUX           A  @SCM_LIB.SCM(SCH_1):P3V3_AUX
    2  BMC_CPLD_GPIO_8      B  @SCM_LIB.SCM(SCH_1):BMC_CPLD_GPIO_8

Q_RES  I35  R596   [Q_RES_0402LF-4.7K,5%,1/16W,CHIA]
    1  P3V3_AUX           A  @SCM_LIB.SCM(SCH_1):P3V3_AUX
    2  BMC_CPLD_GPIO_9      B  @SCM_LIB.SCM(SCH_1):BMC_CPLD_GPIO_9

Q_RES  I18  R597   [Q_RES_0402LF-750,1%,1/16W,CHIPA]
    2  PU_LED_POSTCODE_7_N      B  @SCM_LIB.SCM(SCH_1):PU_LED_POSTCODE_7_N
    1  P3V3_AUX           A  @SCM_LIB.SCM(SCH_1):P3V3_AUX

Q_RES  I20  R598   [Q_RES_0402LF-750,1%,1/16W,CHIPA]
    2  PU_LED_POSTCODE_6_N      B  @SCM_LIB.SCM(SCH_1):PU_LED_POSTCODE_6_N
    1  P3V3_AUX           A  @SCM_LIB.SCM(SCH_1):P3V3_AUX

Q_RES  I23  R599   [Q_RES_0402LF-750,1%,1/16W,CHIPA]
    2  PU_LED_POSTCODE_5_N      B  @SCM_LIB.SCM(SCH_1):PU_LED_POSTCODE_5_N
    1  P3V3_AUX           A  @SCM_LIB.SCM(SCH_1):P3V3_AUX

Q_RES  I25  R600   [Q_RES_0402LF-750,1%,1/16W,CHIPA]
    2  PU_LED_POSTCODE_4_N      B  @SCM_LIB.SCM(SCH_1):PU_LED_POSTCODE_4_N
    1  P3V3_AUX           A  @SCM_LIB.SCM(SCH_1):P3V3_AUX

Q_RES  I31  R601   [Q_RES_0402LF-750,1%,1/16W,CHIPA]
    2  PU_LED_POSTCODE_3_N      B  @SCM_LIB.SCM(SCH_1):PU_LED_POSTCODE_3_N
    1  P3V3_AUX           A  @SCM_LIB.SCM(SCH_1):P3V3_AUX

Q_RES  I33  R602   [Q_RES_0402LF-750,1%,1/16W,CHIPA]
    2  PU_LED_POSTCODE_2_N      B  @SCM_LIB.SCM(SCH_1):PU_LED_POSTCODE_2_N
    1  P3V3_AUX           A  @SCM_LIB.SCM(SCH_1):P3V3_AUX

Q_RES  I35  R603   [Q_RES_0402LF-750,1%,1/16W,CHIPA]
    2  PU_LED_POSTCODE_1_N      B  @SCM_LIB.SCM(SCH_1):PU_LED_POSTCODE_1_N
    1  P3V3_AUX           A  @SCM_LIB.SCM(SCH_1):P3V3_AUX

Q_RES  I37  R604   [Q_RES_0402LF-750,1%,1/16W,CHIPA]
    2  PU_LED_POSTCODE_0_N      B  @SCM_LIB.SCM(SCH_1):PU_LED_POSTCODE_0_N
    1  P3V3_AUX           A  @SCM_LIB.SCM(SCH_1):P3V3_AUX

Q_RES  I33  R605   [Q_RES_0402LF-4.7K,5%,1/16W,CHIA]
    1  P3V3_AUX           A  @SCM_LIB.SCM(SCH_1):P3V3_AUX
    2  BMC_CPLD_GPIO_10      B  @SCM_LIB.SCM(SCH_1):BMC_CPLD_GPIO_10

Q_RES  I31  R606   [Q_RES_0402LF-4.7K,5%,1/16W,CHIA]
    1  P3V3_AUX           A  @SCM_LIB.SCM(SCH_1):P3V3_AUX
    2  BMC_CPLD_GPIO_11      B  @SCM_LIB.SCM(SCH_1):BMC_CPLD_GPIO_11

Q_RES  I29  R607   [Q_RES_0402LF-4.7K,5%,1/16W,CHIA]
    1  P3V3_AUX           A  @SCM_LIB.SCM(SCH_1):P3V3_AUX
    2  BMC_CPLD_GPIO_12      B  @SCM_LIB.SCM(SCH_1):BMC_CPLD_GPIO_12

Q_RES  I27  R608   [Q_RES_0402LF-4.7K,5%,1/16W,CHIA]
    1  P3V3_AUX           A  @SCM_LIB.SCM(SCH_1):P3V3_AUX
    2  BMC_CPLD_GPIO_13      B  @SCM_LIB.SCM(SCH_1):BMC_CPLD_GPIO_13

Q_RES  I25  R609   [Q_RES_0402LF-4.7K,5%,1/16W,CHIA]
    1  P3V3_AUX           A  @SCM_LIB.SCM(SCH_1):P3V3_AUX
    2  BMC_CPLD_GPIO_14      B  @SCM_LIB.SCM(SCH_1):BMC_CPLD_GPIO_14

Q_RES  I92  R610   [Q_RES_0402LF-4.7K,5%,1/16W,CHIA]
    2  SMB_BMC_MM15_SCL      B  @SCM_LIB.SCM(SCH_1):SMB_BMC_MM15_SCL
    1  P3V3_AUX           A  @SCM_LIB.SCM(SCH_1):P3V3_AUX

Q_RES  I23  R611   [Q_RES_0402LF-4.7K,5%,1/16W,CHIA]
    1  P3V3_AUX           A  @SCM_LIB.SCM(SCH_1):P3V3_AUX
    2  BMC_CPLD_GPIO_15      B  @SCM_LIB.SCM(SCH_1):BMC_CPLD_GPIO_15

Q_RES  I21  R612   [Q_RES_0402LF-4.7K,5%,1/16W,CHIA]
    1  P3V3_AUX           A  @SCM_LIB.SCM(SCH_1):P3V3_AUX
    2  BMC_CPLD_GPIO_16      B  @SCM_LIB.SCM(SCH_1):BMC_CPLD_GPIO_16

Q_RES  I19  R613   [Q_RES_0402LF-4.7K,5%,1/16W,CHIA]
    1  P3V3_AUX           A  @SCM_LIB.SCM(SCH_1):P3V3_AUX
    2  BMC_CPLD_GPIO_17      B  @SCM_LIB.SCM(SCH_1):BMC_CPLD_GPIO_17

Q_RES  I35  R614   [Q_RES_0402LF-100K,1%,1/16W,CHIA]
    1  RST_SRST_PLD_BMC_R_N      A  @SCM_LIB.SCM(SCH_1):RST_SRST_PLD_BMC_R_N
    2  GND                B  @SCM_LIB.SCM(SCH_1):GND

Q_RES  I34  R615   [Q_RES_0402LF-4.7K,5%,1/16W,CHIA]
    2  PU_JTAG_TCK_MUX      B  @SCM_LIB.SCM(SCH_1):PU_JTAG_TCK_MUX
    1  P3V3_AUX           A  @SCM_LIB.SCM(SCH_1):P3V3_AUX

Q_RES  I36  R616   [Q_RES_0402LF-0,5%,1/16W,EMPTY,A]
    1  FM_JTAG_TCK_MUX_BMC_SEL_R      A  @SCM_LIB.SCM(SCH_1):FM_JTAG_TCK_MUX_BMC_SEL_R
    2  FM_JTAG_TCK_MUX_BMC_SEL      B  @SCM_LIB.SCM(SCH_1):FM_JTAG_TCK_MUX_BMC_SEL

Q_RES  I17  R617   [Q_RES_0402LF-4.7K,5%,1/16W,CHIA]
    1  P3V3_AUX           A  @SCM_LIB.SCM(SCH_1):P3V3_AUX
    2  BMC_CPLD_GPIO_18      B  @SCM_LIB.SCM(SCH_1):BMC_CPLD_GPIO_18

Q_RES  I211  R618   [Q_RES_0402LF-10K,1%,1/16W,CHIPA]
    1  GND                A  @SCM_LIB.SCM(SCH_1):GND
    2  FM_MB_STBY_EN      B  @SCM_LIB.SCM(SCH_1):FM_MB_STBY_EN

Q_RES  I15  R619   [Q_RES_0402LF-4.7K,5%,1/16W,CHIA]
    1  P3V3_AUX           A  @SCM_LIB.SCM(SCH_1):P3V3_AUX
    2  BMC_CPLD_GPIO_19      B  @SCM_LIB.SCM(SCH_1):BMC_CPLD_GPIO_19

Q_RES  I33  R620   [Q_RES_0402LF-100K,1%,1/16W,CHIA]
    2  GND                B  @SCM_LIB.SCM(SCH_1):GND
    1  FM_JTAG_TCK_MUX_BMC_SEL      A  @SCM_LIB.SCM(SCH_1):FM_JTAG_TCK_MUX_BMC_SEL

Q_RES  I13  R621   [Q_RES_0402LF-4.7K,5%,1/16W,CHIA]
    1  P3V3_AUX           A  @SCM_LIB.SCM(SCH_1):P3V3_AUX
    2  BMC_CPLD_GPIO_20      B  @SCM_LIB.SCM(SCH_1):BMC_CPLD_GPIO_20

Q_RES  I11  R622   [Q_RES_0402LF-4.7K,5%,1/16W,CHIA]
    1  P3V3_AUX           A  @SCM_LIB.SCM(SCH_1):P3V3_AUX
    2  BMC_CPLD_GPIO_21      B  @SCM_LIB.SCM(SCH_1):BMC_CPLD_GPIO_21

Q_RES  I152  R623   [Q_RES_0402LF-4.7K,1%,1/16W,CHIA]
    2  RST_EXTRST_N       B  @SCM_LIB.SCM(SCH_1):RST_EXTRST_N
    1  P3V3_RGM           A  @SCM_LIB.SCM(SCH_1):P3V3_RGM

Q_RES  I44  R624   [Q_RES_0402LF-4.7K,5%,1/16W,CHIA]
    1  P3V3_AUX           A  @SCM_LIB.SCM(SCH_1):P3V3_AUX
    2  FM_BMC_DEBUG_SW_N      B  @SCM_LIB.SCM(SCH_1):FM_BMC_DEBUG_SW_N

Q_RES  I401  R625   [Q_RES_0402LF-4.7K,1%,1/16W,CHIA]
    2  RST_RSMRST_N       B  @SCM_LIB.SCM(SCH_1):RST_RSMRST_N
    1  P3V3_AUX           A  @SCM_LIB.SCM(SCH_1):P3V3_AUX

Q_RES  I9   R626   [Q_RES_0402LF-4.7K,5%,1/16W,CHIA]
    1  P3V3_AUX           A  @SCM_LIB.SCM(SCH_1):P3V3_AUX
    2  BMC_CPLD_GPIO_22      B  @SCM_LIB.SCM(SCH_1):BMC_CPLD_GPIO_22

Q_RES  I7   R627   [Q_RES_0402LF-4.7K,5%,1/16W,CHIA]
    1  P3V3_AUX           A  @SCM_LIB.SCM(SCH_1):P3V3_AUX
    2  BMC_CPLD_GPIO_23      B  @SCM_LIB.SCM(SCH_1):BMC_CPLD_GPIO_23

Q_RES  I139  R628   [Q_RES_0402LF-22,5%,1/16W,CHIP,A]
    1  RGMII_BMC_TXD_R_<0>      A  @SCM_LIB.SCM(SCH_1):RGMII_BMC_TXD_R_<0>
    2  RGMII_BMC_TXD_<0>      B  @SCM_LIB.SCM(SCH_1):RGMII_BMC_TXD_<0>

Q_RES  I140  R629   [Q_RES_0402LF-22,5%,1/16W,CHIP,A]
    1  RGMII_BMC_TXD_R_<1>      A  @SCM_LIB.SCM(SCH_1):RGMII_BMC_TXD_R_<1>
    2  RGMII_BMC_TXD_<1>      B  @SCM_LIB.SCM(SCH_1):RGMII_BMC_TXD_<1>

Q_RES  I141  R630   [Q_RES_0402LF-22,5%,1/16W,CHIP,A]
    1  RGMII_BMC_TXD_R_<2>      A  @SCM_LIB.SCM(SCH_1):RGMII_BMC_TXD_R_<2>
    2  RGMII_BMC_TXD_<2>      B  @SCM_LIB.SCM(SCH_1):RGMII_BMC_TXD_<2>

Q_RES  I142  R631   [Q_RES_0402LF-22,5%,1/16W,CHIP,A]
    1  RGMII_BMC_TXD_R_<3>      A  @SCM_LIB.SCM(SCH_1):RGMII_BMC_TXD_R_<3>
    2  RGMII_BMC_TXD_<3>      B  @SCM_LIB.SCM(SCH_1):RGMII_BMC_TXD_<3>

Q_RES  I5   R632   [Q_RES_0402LF-4.7K,5%,1/16W,CHIA]
    1  P3V3_AUX           A  @SCM_LIB.SCM(SCH_1):P3V3_AUX
    2  BMC_CPLD_GPIO_24      B  @SCM_LIB.SCM(SCH_1):BMC_CPLD_GPIO_24

Q_RES  I81  R633   [Q_RES_0402LF-1K,1%,1/16W,EMPTYA]
    2  RST_BMC_SELF_HW_R3      B  @SCM_LIB.SCM(SCH_1):RST_BMC_SELF_HW_R3
    1  P3V3_AUX           A  @SCM_LIB.SCM(SCH_1):P3V3_AUX

Q_RES  I362  R634   [Q_RES_0402LF-0,5%,1/16W,CHIP,CA]
    2  BMC_CPLD_GPIO_25_R2      B  @SCM_LIB.SCM(SCH_1):BMC_CPLD_GPIO_25_R2
    1  BMC_CPLD_GPIO_25      A  @SCM_LIB.SCM(SCH_1):BMC_CPLD_GPIO_25

Q_RES  I361  R635   [Q_RES_0402LF-33       ,1%  ,1/A]
    2  RST_WDTRST_PLD_R2_N      B  @SCM_LIB.SCM(SCH_1):RST_WDTRST_PLD_R2_N
    1  RST_WDTRST_PLD_N      A  @SCM_LIB.SCM(SCH_1):RST_WDTRST_PLD_N

Q_RES  I10  R636   [Q_RES_0402LF-0,5%,1/16W,CHIP,CA]
    1  RST_EXTRST_N       A  @SCM_LIB.SCM(SCH_1):RST_EXTRST_N
    2  RST_BMC_EXTRST_R2_N      B  @SCM_LIB.SCM(SCH_1):RST_BMC_EXTRST_R2_N

Q_RES  I337  R637   [Q_RES_0402LF-0,5%,1/16W,CHIP,CA]
    1  RST_WDTRST_PLD_R1_N      A  @SCM_LIB.SCM(SCH_1):RST_WDTRST_PLD_R1_N
    2  RST_WDTRST_PLD_N      B  @SCM_LIB.SCM(SCH_1):RST_WDTRST_PLD_N

Q_RES  I359  R638   [Q_RES_0402LF-33       ,1%  ,1/A]
    1  RST_BMC_HW_R       A  @SCM_LIB.SCM(SCH_1):RST_BMC_HW_R
    2  RST_BMC_HW         B  @SCM_LIB.SCM(SCH_1):RST_BMC_HW

Q_RES  I88  R639   [Q_RES_0402LF-33       ,1%  ,1/A]
    2  JTAG_MB_TDI        B  @SCM_LIB.SCM(SCH_1):JTAG_MB_TDI
    1  JTAG_1_BMC_TDI_R      A  @SCM_LIB.SCM(SCH_1):JTAG_1_BMC_TDI_R

Q_RES  I51  R640   [Q_RES_0402LF-4.7K,5%,1/16W,CHIA]
    1  P3V3_AUX           A  @SCM_LIB.SCM(SCH_1):P3V3_AUX
    2  BMC_CPLD_GPIO_25      B  @SCM_LIB.SCM(SCH_1):BMC_CPLD_GPIO_25

Q_RES  I53  R641   [Q_RES_0402LF-4.7K,5%,1/16W,CHIA]
    2  RST_BMC_SELF_HW_R2      B  @SCM_LIB.SCM(SCH_1):RST_BMC_SELF_HW_R2
    1  P3V3_AUX           A  @SCM_LIB.SCM(SCH_1):P3V3_AUX

Q_RES  I35  R647   [Q_RES_0402LF-33       ,1%  ,1/B]
    2  EMMC_DT1_R         B  @SCM_LIB.SCM(SCH_1):EMMC_DT1_R
    1  BMC_EMMC_DT1       A  @SCM_LIB.SCM(SCH_1):BMC_EMMC_DT1

Q_RES  I36  R648   [Q_RES_0402LF-33       ,1%  ,1/B]
    2  EMMC_DT2_R         B  @SCM_LIB.SCM(SCH_1):EMMC_DT2_R
    1  BMC_EMMC_DT2       A  @SCM_LIB.SCM(SCH_1):BMC_EMMC_DT2

Q_RES  I29  R649   [Q_RES_0402LF-33       ,1%  ,1/B]
    2  EMMC_DT3_R         B  @SCM_LIB.SCM(SCH_1):EMMC_DT3_R
    1  BMC_EMMC_DT3       A  @SCM_LIB.SCM(SCH_1):BMC_EMMC_DT3

Q_RES  I30  R650   [Q_RES_0402LF-33       ,1%  ,1/B]
    2  EMMC_DT4_R         B  @SCM_LIB.SCM(SCH_1):EMMC_DT4_R
    1  BMC_EMMC_DT4       A  @SCM_LIB.SCM(SCH_1):BMC_EMMC_DT4

Q_RES  I31  R651   [Q_RES_0402LF-33       ,1%  ,1/B]
    2  EMMC_DT5_R         B  @SCM_LIB.SCM(SCH_1):EMMC_DT5_R
    1  BMC_EMMC_DT5       A  @SCM_LIB.SCM(SCH_1):BMC_EMMC_DT5

Q_RES  I32  R652   [Q_RES_0402LF-33       ,1%  ,1/B]
    2  EMMC_DT6_R         B  @SCM_LIB.SCM(SCH_1):EMMC_DT6_R
    1  BMC_EMMC_DT6       A  @SCM_LIB.SCM(SCH_1):BMC_EMMC_DT6

Q_RES  I33  R653   [Q_RES_0402LF-33       ,1%  ,1/B]
    2  EMMC_DT7_R         B  @SCM_LIB.SCM(SCH_1):EMMC_DT7_R
    1  BMC_EMMC_DT7       A  @SCM_LIB.SCM(SCH_1):BMC_EMMC_DT7

Q_RES  I27  R654   [Q_RES_0402LF-33       ,1%  ,1/B]
    2  EMMC_CLK_R         B  @SCM_LIB.SCM(SCH_1):EMMC_CLK_R
    1  BMC_EMMC_CLK       A  @SCM_LIB.SCM(SCH_1):BMC_EMMC_CLK

Q_RES  I59  R655   [Q_RES_0402LF-10K,1%,1/16W,EMPTA]
    1  P1V8_AUX           A  @SCM_LIB.SCM(SCH_1):P1V8_AUX
    2  EMMC_DT0_R         B  @SCM_LIB.SCM(SCH_1):EMMC_DT0_R

Q_RES  I60  R656   [Q_RES_0402LF-10K,1%,1/16W,EMPTA]
    1  P1V8_AUX           A  @SCM_LIB.SCM(SCH_1):P1V8_AUX
    2  EMMC_DT1_R         B  @SCM_LIB.SCM(SCH_1):EMMC_DT1_R

Q_RES  I61  R657   [Q_RES_0402LF-10K,1%,1/16W,EMPTA]
    1  P1V8_AUX           A  @SCM_LIB.SCM(SCH_1):P1V8_AUX
    2  EMMC_DT2_R         B  @SCM_LIB.SCM(SCH_1):EMMC_DT2_R

Q_RES  I58  R658   [Q_RES_0402LF-10K,1%,1/16W,EMPTA]
    1  P1V8_AUX           A  @SCM_LIB.SCM(SCH_1):P1V8_AUX
    2  EMMC_DT3_R         B  @SCM_LIB.SCM(SCH_1):EMMC_DT3_R

Q_RES  I57  R659   [Q_RES_0402LF-10K,1%,1/16W,EMPTA]
    1  P1V8_AUX           A  @SCM_LIB.SCM(SCH_1):P1V8_AUX
    2  EMMC_DT4_R         B  @SCM_LIB.SCM(SCH_1):EMMC_DT4_R

Q_RES  I55  R660   [Q_RES_0402LF-10K,1%,1/16W,EMPTA]
    1  P1V8_AUX           A  @SCM_LIB.SCM(SCH_1):P1V8_AUX
    2  EMMC_DT5_R         B  @SCM_LIB.SCM(SCH_1):EMMC_DT5_R

Q_RES  I53  R661   [Q_RES_0402LF-10K,1%,1/16W,EMPTA]
    1  P1V8_AUX           A  @SCM_LIB.SCM(SCH_1):P1V8_AUX
    2  EMMC_DT6_R         B  @SCM_LIB.SCM(SCH_1):EMMC_DT6_R

Q_RES  I54  R662   [Q_RES_0402LF-10K,1%,1/16W,EMPTA]
    1  P1V8_AUX           A  @SCM_LIB.SCM(SCH_1):P1V8_AUX
    2  EMMC_DT7_R         B  @SCM_LIB.SCM(SCH_1):EMMC_DT7_R

Q_RES  I52  R663   [Q_RES_0402LF-10K,1%,1/16W,EMPTA]
    1  P1V8_AUX           A  @SCM_LIB.SCM(SCH_1):P1V8_AUX
    2  EMMC_CMD_R         B  @SCM_LIB.SCM(SCH_1):EMMC_CMD_R

Q_RES  I250  R677   [Q_RES_0402LF-33       ,1%  ,1/B]
    2  SPI_BMC_BOOT_CS0_R1_N      B  @SCM_LIB.SCM(SCH_1):SPI_BMC_BOOT_CS0_R1_N
    1  QSPI_2_PLD_CS0_N      A  @SCM_LIB.SCM(SCH_1):QSPI_2_PLD_CS0_N

Q_RES  I239  R678   [Q_RES_0402LF-33       ,1%  ,1/B]
    1  SPI_BMC_CLK_R      A  @SCM_LIB.SCM(SCH_1):SPI_BMC_CLK_R
    2  QSPI_2_PLD_CLK      B  @SCM_LIB.SCM(SCH_1):QSPI_2_PLD_CLK

Q_RES  I247  R679   [Q_RES_0402LF-33       ,1%  ,1/B]
    1  SPI_BMC_MOSI_IO0_R      A  @SCM_LIB.SCM(SCH_1):SPI_BMC_MOSI_IO0_R
    2  QSPI_2_PLD_IO0      B  @SCM_LIB.SCM(SCH_1):QSPI_2_PLD_IO0

Q_RES  I248  R680   [Q_RES_0402LF-33       ,1%  ,1/B]
    1  SPI_BMC_MISO_IO1_R      A  @SCM_LIB.SCM(SCH_1):SPI_BMC_MISO_IO1_R
    2  QSPI_2_PLD_IO1      B  @SCM_LIB.SCM(SCH_1):QSPI_2_PLD_IO1

Q_RES  I245  R681   [Q_RES_0402LF-33       ,1%  ,1/B]
    1  SPI_BMC_IO2_R      A  @SCM_LIB.SCM(SCH_1):SPI_BMC_IO2_R
    2  QSPI_2_PLD_IO2      B  @SCM_LIB.SCM(SCH_1):QSPI_2_PLD_IO2

Q_RES  I246  R682   [Q_RES_0402LF-33       ,1%  ,1/B]
    1  SPI_BMC_IO3_R      A  @SCM_LIB.SCM(SCH_1):SPI_BMC_IO3_R
    2  QSPI_2_PLD_IO3      B  @SCM_LIB.SCM(SCH_1):QSPI_2_PLD_IO3

Q_RES  I188  R683   [Q_RES_0402LF-4.7K,5%,1/16W,CHIA]
    2  PU_SPI1WP_N        B  @SCM_LIB.SCM(SCH_1):PU_SPI1WP_N
    1  P3V3_AUX           A  @SCM_LIB.SCM(SCH_1):P3V3_AUX

Q_RES  I122  R684   [Q_RES_0402LF-1K,1%,1/16W,EMPTYA]
    2  GND                B  @SCM_LIB.SCM(SCH_1):GND
    1  BMC_EMMC_WP_N      A  @SCM_LIB.SCM(SCH_1):BMC_EMMC_WP_N

Q_RES  I124  R685   [Q_RES_0402LF-1K,1%,1/16W,EMPTYA]
    2  GND                B  @SCM_LIB.SCM(SCH_1):GND
    1  BMC_EMMC_CD_N      A  @SCM_LIB.SCM(SCH_1):BMC_EMMC_CD_N

Q_RES  I125  R686   [Q_RES_0402LF-4.7K,5%,1/16W,EMPA]
    1  P1V8_AUX           A  @SCM_LIB.SCM(SCH_1):P1V8_AUX
    2  BMC_EMMC_WP_N      B  @SCM_LIB.SCM(SCH_1):BMC_EMMC_WP_N

Q_RES  I126  R687   [Q_RES_0402LF-4.7K,5%,1/16W,EMPA]
    1  P1V8_AUX           A  @SCM_LIB.SCM(SCH_1):P1V8_AUX
    2  BMC_EMMC_CD_N      B  @SCM_LIB.SCM(SCH_1):BMC_EMMC_CD_N

Q_RES  I304  R688   [Q_RES_0402LF-33       ,1%  ,1/B]
    1  RST_SGPIO_RESET_N      A  @SCM_LIB.SCM(SCH_1):RST_SGPIO_RESET_N
    2  RST_SGPIO_RESET_BMC_N      B  @SCM_LIB.SCM(SCH_1):RST_SGPIO_RESET_BMC_N

Q_RES  I264  R689   [Q_RES_0402LF-33       ,1%  ,1/B]
    1  IRQ_SGPIO_N        A  @SCM_LIB.SCM(SCH_1):IRQ_SGPIO_N
    2  IRQ_SGPIO_BMC_N      B  @SCM_LIB.SCM(SCH_1):IRQ_SGPIO_BMC_N

Q_RES  I392  R690   [Q_RES_0402LF-33       ,1%  ,1/A]
    1  IRQ_SGPIO_R_N      A  @SCM_LIB.SCM(SCH_1):IRQ_SGPIO_R_N
    2  IRQ_SGPIO_N        B  @SCM_LIB.SCM(SCH_1):IRQ_SGPIO_N

Q_RES  I393  R691   [Q_RES_0402LF-33       ,1%  ,1/A]
    1  RST_SGPIO_RESET_R_N      A  @SCM_LIB.SCM(SCH_1):RST_SGPIO_RESET_R_N
    2  RST_SGPIO_RESET_N      B  @SCM_LIB.SCM(SCH_1):RST_SGPIO_RESET_N

Q_RES  I90  R692   [Q_RES_0402LF-4.7K,5%,1/16W,CHIA]
    2  SMB_BMC_MM15_SDA      B  @SCM_LIB.SCM(SCH_1):SMB_BMC_MM15_SDA
    1  P3V3_AUX           A  @SCM_LIB.SCM(SCH_1):P3V3_AUX

Q_RES  I163  R699   [Q_RES_0402LF-4.7K,5%,1/16W,EMPA]
    2  SPI_BMC_BOOT_CLK      B  @SCM_LIB.SCM(SCH_1):SPI_BMC_BOOT_CLK
    1  P3V3_AUX           A  @SCM_LIB.SCM(SCH_1):P3V3_AUX

Q_RES  I352  R704   [Q_RES_0402LF-33       ,1%  ,1/A]
    2  RST_PCA9548_SENSOR_R_N      B  @SCM_LIB.SCM(SCH_1):RST_PCA9548_SENSOR_R_N
    1  RST_PCA9548_SENSOR_N      A  @SCM_LIB.SCM(SCH_1):RST_PCA9548_SENSOR_N

Q_RES  I353  R705   [Q_RES_0402LF-33       ,1%  ,1/A]
    2  FM_BMC_DBP_PRESENT_R_N      B  @SCM_LIB.SCM(SCH_1):FM_BMC_DBP_PRESENT_R_N
    1  FM_BMC_DBP_PRESENT_N      A  @SCM_LIB.SCM(SCH_1):FM_BMC_DBP_PRESENT_N

Q_RES  I354  R706   [Q_RES_0402LF-4.7K,5%,1/16W,CHIA]
    1  P3V3_AUX           A  @SCM_LIB.SCM(SCH_1):P3V3_AUX
    2  FM_BMC_DBP_PRESENT_N      B  @SCM_LIB.SCM(SCH_1):FM_BMC_DBP_PRESENT_N

Q_RES  I38  R708   [Q_RES_0402LF-0,5%,1/16W,CHIP,CA]
    1  PWRGD_P3V3_RGM      A  @SCM_LIB.SCM(SCH_1):PWRGD_P3V3_RGM
    2  EN_P1V2_AUX        B  @SCM_LIB.SCM(SCH_1):EN_P1V2_AUX

Q_RES  I72  R709   [Q_RES_0402LF-10K,1%,1/16W,CHIPA]
    2  PWRGD_P3V3_RGM_R      B  @SCM_LIB.SCM(SCH_1):PWRGD_P3V3_RGM_R
    1  P3V3_RGM           A  @SCM_LIB.SCM(SCH_1):P3V3_RGM

Q_RES  I55  R710   [Q_RES_0402LF-100K,1%,1/16W,CHIA]
    2  U43_CT             B  @SCM_LIB.SCM(SCH_1):U43_CT
    1  P3V3_AUX           A  @SCM_LIB.SCM(SCH_1):P3V3_AUX

Q_RES  I49  R711   [Q_RES_0402LF-0,5%,1/16W,EMPTY,A]
    1  PWRGD_PSU_AC_PWROK      A  @SCM_LIB.SCM(SCH_1):PWRGD_PSU_AC_PWROK
    2  PWRGD_P1V0_AUX_DELAY      B  @SCM_LIB.SCM(SCH_1):PWRGD_P1V0_AUX_DELAY

Q_RES  I228  R713   [Q_RES_0402LF-33       ,1%  ,1/A]
    1  LPC_ESPI_SEL_R      A  @SCM_LIB.SCM(SCH_1):LPC_ESPI_SEL_R
    2  LPC_ESPI_SEL       B  @SCM_LIB.SCM(SCH_1):LPC_ESPI_SEL

Q_RES  I165  R714   [Q_RES_0402LF-2K,1%,1/16W,CHIP,A]
    2  LPC_ESPI_SEL_R1      B  @SCM_LIB.SCM(SCH_1):LPC_ESPI_SEL_R1
    1  LPC_ESPI_SEL       A  @SCM_LIB.SCM(SCH_1):LPC_ESPI_SEL

Q_RES  I237  R715   [Q_RES_0402LF-10K,1%,1/16W,CHIPA]
    1  P5V_AUX            A  @SCM_LIB.SCM(SCH_1):P5V_AUX
    2  LPC_ESPI_SEL_LV5      B  @SCM_LIB.SCM(SCH_1):LPC_ESPI_SEL_LV5

Q_RES  I230  R716   [Q_RES_0402LF-10K,1%,1/16W,CHIPA]
    1  P3V3_AUX           A  @SCM_LIB.SCM(SCH_1):P3V3_AUX
    2  LPC_ESPI_SEL_N      B  @SCM_LIB.SCM(SCH_1):LPC_ESPI_SEL_N

Q_RES  I174  R717   [Q_RES_0402LF-4.7K,5%,1/16W,CHIA]
    2  RST_BMC_RSTBTN_OUT_N      B  @SCM_LIB.SCM(SCH_1):RST_BMC_RSTBTN_OUT_N
    1  P3V3_AUX           A  @SCM_LIB.SCM(SCH_1):P3V3_AUX

Q_RES  I405  R718   [Q_RES_0402LF-33       ,1%  ,1/A]
    2  RST_PLTRST_R1_N      B  @SCM_LIB.SCM(SCH_1):RST_PLTRST_R1_N
    1  RST_PLTRST_N       A  @SCM_LIB.SCM(SCH_1):RST_PLTRST_N

Q_RES  I333  R724   [Q_RES_0402LF-33       ,1%  ,1/A]
    2  SPI_BMC_BIOS_ROM_R_IO2      B  @SCM_LIB.SCM(SCH_1):SPI_BMC_BIOS_ROM_R_IO2
    1  SPI_BMC_BIOS_ROM_IO2      A  @SCM_LIB.SCM(SCH_1):SPI_BMC_BIOS_ROM_IO2

Q_RES  I334  R725   [Q_RES_0402LF-33       ,1%  ,1/A]
    2  SPI_BMC_BIOS_ROM_R_IO3      B  @SCM_LIB.SCM(SCH_1):SPI_BMC_BIOS_ROM_R_IO3
    1  SPI_BMC_BIOS_ROM_IO3      A  @SCM_LIB.SCM(SCH_1):SPI_BMC_BIOS_ROM_IO3

Q_RES  I336  R728   [Q_RES_0402LF-0,5%,1/16W,CHIP,CA]
    2  SPI_BMC_BIOS_SOURCE_CS0_N      B  @SCM_LIB.SCM(SCH_1):SPI_BMC_BIOS_SOURCE_CS0_N
    1  SPI_BMC_BIOS_CS0_N      A  @SCM_LIB.SCM(SCH_1):SPI_BMC_BIOS_CS0_N

Q_RES  I208  R759   [Q_RES_0402LF-33       ,1%  ,1/A]
    2  UART_BMC_5_RXD_R      B  @SCM_LIB.SCM(SCH_1):UART_BMC_5_RXD_R
    1  UART_BMC_5_RXD      A  @SCM_LIB.SCM(SCH_1):UART_BMC_5_RXD

Q_RES  I366  R760   [Q_RES_0402LF-33       ,1%  ,1/A]
    2  UART_1_SCM_R_RXD      B  @SCM_LIB.SCM(SCH_1):UART_1_SCM_R_RXD
    1  UART_1_SCM_RXD      A  @SCM_LIB.SCM(SCH_1):UART_1_SCM_RXD

Q_RES  I365  R761   [Q_RES_0402LF-33       ,1%  ,1/A]
    1  UART_2_BMC_TXD      A  @SCM_LIB.SCM(SCH_1):UART_2_BMC_TXD
    2  UART_2_BMC_R_TXD      B  @SCM_LIB.SCM(SCH_1):UART_2_BMC_R_TXD

Q_RES  I364  R762   [Q_RES_0402LF-33       ,1%  ,1/A]
    2  UART_2_BMC_R_RXD      B  @SCM_LIB.SCM(SCH_1):UART_2_BMC_R_RXD
    1  UART_2_BMC_RXD      A  @SCM_LIB.SCM(SCH_1):UART_2_BMC_RXD

Q_RES  I243  R763   [Q_RES_0402LF-33       ,1%  ,1/A]
    2  FM_PLT_BMC_THERMTRIP_N_R      B  @SCM_LIB.SCM(SCH_1):FM_PLT_BMC_THERMTRIP_N_R
    1  FM_PCH_BMC_THERMTRIP_N      A  @SCM_LIB.SCM(SCH_1):FM_PCH_BMC_THERMTRIP_N

Q_RES  I41  R764   [Q_RES_0402LF-0,5%,1/16W,EMPTY,A]
    1  PWRGD_P1V8_AUX      A  @SCM_LIB.SCM(SCH_1):PWRGD_P1V8_AUX
    2  EN_P1V2_AUX        B  @SCM_LIB.SCM(SCH_1):EN_P1V2_AUX

Q_RES  I66  R765   [Q_RES_0402LF-33       ,1%  ,1/B]
    1  UART_BMC_5_TXD_R      A  @SCM_LIB.SCM(SCH_1):UART_BMC_5_TXD_R
    2  UART_1_SCM_TXD      B  @SCM_LIB.SCM(SCH_1):UART_1_SCM_TXD

Q_RES  I72  R766   [Q_RES_0402LF-33       ,1%  ,1/B]
    1  UART_BMC_5_RXD_R      A  @SCM_LIB.SCM(SCH_1):UART_BMC_5_RXD_R
    2  UART_1_SCM_RXD      B  @SCM_LIB.SCM(SCH_1):UART_1_SCM_RXD

Q_RES  I403  R767   [Q_RES_0402LF-33       ,1%  ,1/A]
    2  FM_TPM_PRSNT_0_R_N      B  @SCM_LIB.SCM(SCH_1):FM_TPM_PRSNT_0_R_N
    1  FM_TPM_PRSNT_0_N      A  @SCM_LIB.SCM(SCH_1):FM_TPM_PRSNT_0_N

Q_RES  I89  R768   [Q_RES_0402LF-8.2K     ,5%  ,1/A]
    2  REAR_PWR_BTN_N      B  @SCM_LIB.SCM(SCH_1):REAR_PWR_BTN_N
    1  P3V3_AUX           A  @SCM_LIB.SCM(SCH_1):P3V3_AUX

Q_RES  I315  R769   [Q_RES_0402LF-33       ,1%  ,1/A]
    2  FM_THROTTLE_R_N      B  @SCM_LIB.SCM(SCH_1):FM_THROTTLE_R_N
    1  FM_THROTTLE_N      A  @SCM_LIB.SCM(SCH_1):FM_THROTTLE_N

Q_RES  I314  R773   [Q_RES_0402LF-33       ,1%  ,1/A]
    2  FM_SLPS3_GF_R_N      B  @SCM_LIB.SCM(SCH_1):FM_SLPS3_GF_R_N
    1  FM_SLPS3_GF_N      A  @SCM_LIB.SCM(SCH_1):FM_SLPS3_GF_N

Q_RES  I213  R774   [Q_RES_0402LF-4.7K,5%,1/16W,CHIA]
    1  P3V3_AUX           A  @SCM_LIB.SCM(SCH_1):P3V3_AUX
    2  FM_SLPS3_GF_N      B  @SCM_LIB.SCM(SCH_1):FM_SLPS3_GF_N

Q_RES  I183  R775   [Q_RES_0402LF-1K,1%,1/16W,CHIP,A]
    2  BATTERY_DETECT_R      B  @SCM_LIB.SCM(SCH_1):BATTERY_DETECT_R
    1  BATTERY_DETECT      A  @SCM_LIB.SCM(SCH_1):BATTERY_DETECT

Q_RES  I184  R776   [Q_RES_0201LF-47K,1%,1/20W,CHIPA]
    2  GND                B  @SCM_LIB.SCM(SCH_1):GND
    1  BATTERY_DETECT_R      A  @SCM_LIB.SCM(SCH_1):BATTERY_DETECT_R

Q_RES  I289  R777   [Q_RES_0402LF-200K,1%,1/16W,CHIA]
    2  P3V_BAT_R1         B  @SCM_LIB.SCM(SCH_1):P3V_BAT_R1
    1  P3V_BAT_R          A  @SCM_LIB.SCM(SCH_1):P3V_BAT_R

Q_RES  I181  R778   [Q_RES_0402LF-100K,1%,1/16W,CHIA]
    1  P3V_BAT_SENSOR      A  @SCM_LIB.SCM(SCH_1):P3V_BAT_SENSOR
    2  GND                B  @SCM_LIB.SCM(SCH_1):GND

Q_RES  I259  R779   [Q_RES_0402LF-0,5%,1/16W,CHIP,CA]
    1  P2V5_AUX           A  @SCM_LIB.SCM(SCH_1):P2V5_AUX
    2  ADCVREFEXT1        B  @SCM_LIB.SCM(SCH_1):ADCVREFEXT1

Q_RES  I256  R780   [Q_RES_0402LF-0,5%,1/16W,EMPTY,A]
    1  P2V5_AUX           A  @SCM_LIB.SCM(SCH_1):P2V5_AUX
    2  ADCVREFEXT0        B  @SCM_LIB.SCM(SCH_1):ADCVREFEXT0

Q_RES  I263  R781   [Q_RES_0402LF-0,5%,1/16W,EMPTY,A]
    1  P1V8_AUX           A  @SCM_LIB.SCM(SCH_1):P1V8_AUX
    2  ADCVREFEXT1        B  @SCM_LIB.SCM(SCH_1):ADCVREFEXT1

Q_RES  I264  R782   [Q_RES_0402LF-0,5%,1/16W,EMPTY,A]
    1  P1V2_AUX           A  @SCM_LIB.SCM(SCH_1):P1V2_AUX
    2  ADCVREFEXT1        B  @SCM_LIB.SCM(SCH_1):ADCVREFEXT1

Q_RES  I260  R783   [Q_RES_0402LF-0,5%,1/16W,CHIP,CA]
    1  P1V8_AUX           A  @SCM_LIB.SCM(SCH_1):P1V8_AUX
    2  ADCVREFEXT0        B  @SCM_LIB.SCM(SCH_1):ADCVREFEXT0

Q_RES  I267  R784   [Q_RES_0402LF-0,5%,1/16W,EMPTY,A]
    1  P1V2_AUX           A  @SCM_LIB.SCM(SCH_1):P1V2_AUX
    2  ADCVREFEXT0        B  @SCM_LIB.SCM(SCH_1):ADCVREFEXT0

Q_RES  I202  R785   [Q_RES_0402LF-15.8K,1%,1/16W,CHA]
    2  P12V_SENSOR        B  @SCM_LIB.SCM(SCH_1):P12V_SENSOR
    1  P12V_AUX           A  @SCM_LIB.SCM(SCH_1):P12V_AUX

Q_RES  I203  R786   [Q_RES_0402LF-2K,1%,1/16W,CHIP,A]
    1  P12V_SENSOR        A  @SCM_LIB.SCM(SCH_1):P12V_SENSOR
    2  GND                B  @SCM_LIB.SCM(SCH_1):GND

Q_RES  I223  R787   [Q_RES_0402LF-5.36K,1%,1/16W,CHA]
    2  P5V_SENSOR         B  @SCM_LIB.SCM(SCH_1):P5V_SENSOR
    1  P5V_AUX            A  @SCM_LIB.SCM(SCH_1):P5V_AUX

Q_RES  I211  R788   [Q_RES_0402LF-2K,1%,1/16W,CHIP,A]
    1  P5V_SENSOR         A  @SCM_LIB.SCM(SCH_1):P5V_SENSOR
    2  GND                B  @SCM_LIB.SCM(SCH_1):GND

Q_RES  I219  R789   [Q_RES_0402LF-2.87K,1%,1/16W,CHA]
    2  P3V3_SENSOR        B  @SCM_LIB.SCM(SCH_1):P3V3_SENSOR
    1  P3V3_AUX           A  @SCM_LIB.SCM(SCH_1):P3V3_AUX

Q_RES  I220  R790   [Q_RES_0402LF-2K,1%,1/16W,CHIP,A]
    1  P3V3_SENSOR        A  @SCM_LIB.SCM(SCH_1):P3V3_SENSOR
    2  GND                B  @SCM_LIB.SCM(SCH_1):GND

Q_RES  I245  R791   [Q_RES_0402LF-1.69K,1%,1/16W,CHA]
    2  P2V5_SENSOR        B  @SCM_LIB.SCM(SCH_1):P2V5_SENSOR
    1  P2V5_AUX           A  @SCM_LIB.SCM(SCH_1):P2V5_AUX

Q_RES  I236  R792   [Q_RES_0402LF-2K,1%,1/16W,CHIP,A]
    1  P2V5_SENSOR        A  @SCM_LIB.SCM(SCH_1):P2V5_SENSOR
    2  GND                B  @SCM_LIB.SCM(SCH_1):GND

Q_RES  I244  R793   [Q_RES_0402LF-665,1%,1/16W,CHIPA]
    2  P1V8_SENSOR        B  @SCM_LIB.SCM(SCH_1):P1V8_SENSOR
    1  P1V8_AUX           A  @SCM_LIB.SCM(SCH_1):P1V8_AUX

Q_RES  I242  R794   [Q_RES_0402LF-2K,1%,1/16W,CHIP,A]
    1  P1V8_SENSOR        A  @SCM_LIB.SCM(SCH_1):P1V8_SENSOR
    2  GND                B  @SCM_LIB.SCM(SCH_1):GND

Q_RES  I252  R795   [Q_RES_0402LF-1K,1%,1/16W,CHIP,A]
    2  P1V2_SENSOR        B  @SCM_LIB.SCM(SCH_1):P1V2_SENSOR
    1  P1V2_AUX           A  @SCM_LIB.SCM(SCH_1):P1V2_AUX

Q_RES  I255  R796   [Q_RES_0402LF-1K,1%,1/16W,CHIP,A]
    2  P1V0_SENSOR        B  @SCM_LIB.SCM(SCH_1):P1V0_SENSOR
    1  P1V0_AUX           A  @SCM_LIB.SCM(SCH_1):P1V0_AUX

Q_RES  I261  R797   [Q_RES_0402LF-2.87K,1%,1/16W,CHA]
    2  PGPPA_BMC_AUX_SENSOR      B  @SCM_LIB.SCM(SCH_1):PGPPA_BMC_AUX_SENSOR
    1  PGPPA_BMC_AUX      A  @SCM_LIB.SCM(SCH_1):PGPPA_BMC_AUX

Q_RES  I262  R798   [Q_RES_0402LF-2K,1%,1/16W,CHIP,A]
    1  PGPPA_BMC_AUX_SENSOR      A  @SCM_LIB.SCM(SCH_1):PGPPA_BMC_AUX_SENSOR
    2  GND                B  @SCM_LIB.SCM(SCH_1):GND

Q_RES  I215  R799   [Q_RES_0402LF-33       ,1%  ,1/A]
    2  SPI_BMC_BIOS_CS0_R1_N      B  @SCM_LIB.SCM(SCH_1):SPI_BMC_BIOS_CS0_R1_N
    1  SPI_BMC_BIOS_CS0_N      A  @SCM_LIB.SCM(SCH_1):SPI_BMC_BIOS_CS0_N

Q_RES  I217  R801   [Q_RES_0402LF-33       ,1%  ,1/A]
    1  SPI_BMC_BOOT_CS0_R_N      A  @SCM_LIB.SCM(SCH_1):SPI_BMC_BOOT_CS0_R_N
    2  SPI_BMC_BOOT_CS0_R1_N      B  @SCM_LIB.SCM(SCH_1):SPI_BMC_BOOT_CS0_R1_N

Q_RES  I218  R802   [Q_RES_0402LF-33       ,1%  ,1/A]
    1  SPI_BMC_BOOT_CS1_R_N      A  @SCM_LIB.SCM(SCH_1):SPI_BMC_BOOT_CS1_R_N
    2  SPI_BMC_BOOT_CS1_R1_N      B  @SCM_LIB.SCM(SCH_1):SPI_BMC_BOOT_CS1_R1_N

Q_RES  I308  R803   [Q_RES_0402LF-33       ,1%  ,1/A]
    2  RGMII_BMC_MDC_R      B  @SCM_LIB.SCM(SCH_1):RGMII_BMC_MDC_R
    1  RGMII_BMC_MDC      A  @SCM_LIB.SCM(SCH_1):RGMII_BMC_MDC

Q_RES  I309  R804   [Q_RES_0402LF-33       ,1%  ,1/A]
    2  RGMII_BMC_MDIO_R      B  @SCM_LIB.SCM(SCH_1):RGMII_BMC_MDIO_R
    1  RGMII_BMC_MDIO      A  @SCM_LIB.SCM(SCH_1):RGMII_BMC_MDIO

Q_RES  I436  R806   [Q_RES_0402LF-4.7K,5%,1/16W,CHIA]
    2  PU_25M_FPGA_CLK_EN      B  @SCM_LIB.SCM(SCH_1):PU_25M_FPGA_CLK_EN
    1  P3V3_AUX           A  @SCM_LIB.SCM(SCH_1):P3V3_AUX

Q_RES  I429  R807   [Q_RES_0402LF-33       ,1%  ,1/A]
    1  CLK_25M_OSC_FPGA_R      A  @SCM_LIB.SCM(SCH_1):CLK_25M_OSC_FPGA_R
    2  CLK_25M_OSC_FPGA      B  @SCM_LIB.SCM(SCH_1):CLK_25M_OSC_FPGA

Q_RES  I273  R808   [Q_RES_0402LF-10K,0.10%,1/16W,CA]
    1  PU_FPGA_CONFIG_DONE      A  @SCM_LIB.SCM(SCH_1):PU_FPGA_CONFIG_DONE
    2  P3V3_AUX           B  @SCM_LIB.SCM(SCH_1):P3V3_AUX

Q_RES  I274  R809   [Q_RES_0402LF-10K,0.10%,1/16W,CA]
    1  PU_FPGA_NCONFIG      A  @SCM_LIB.SCM(SCH_1):PU_FPGA_NCONFIG
    2  P3V3_AUX           B  @SCM_LIB.SCM(SCH_1):P3V3_AUX

Q_RES  I275  R810   [Q_RES_0402LF-10K,0.10%,1/16W,CA]
    1  PU_FPGA_NSTATUS      A  @SCM_LIB.SCM(SCH_1):PU_FPGA_NSTATUS
    2  P3V3_AUX           B  @SCM_LIB.SCM(SCH_1):P3V3_AUX

Q_RES  I277  R811   [Q_RES_0402LF-10K,0.10%,1/16W,CA]
    1  PD_FPGA_CONFIG_SEL      A  @SCM_LIB.SCM(SCH_1):PD_FPGA_CONFIG_SEL
    2  GND                B  @SCM_LIB.SCM(SCH_1):GND

Q_RES  I128  R812   [Q_RES_0402LF-33       ,1%  ,1/A]
    2  PWR_LED_BUF_R      B  @SCM_LIB.SCM(SCH_1):PWR_LED_BUF_R
    1  PWR_LED_BUF        A  @SCM_LIB.SCM(SCH_1):PWR_LED_BUF

Q_RES  I129  R813   [Q_RES_0402LF-33       ,1%  ,1/A]
    2  ID_LED_BUF_R       B  @SCM_LIB.SCM(SCH_1):ID_LED_BUF_R
    1  ID_LED_BUF         A  @SCM_LIB.SCM(SCH_1):ID_LED_BUF

Q_RES  I130  R814   [Q_RES_0402LF-10K,0.10%,1/16W,CA]
    2  PWR_LED_BUF_R      B  @SCM_LIB.SCM(SCH_1):PWR_LED_BUF_R
    1  P3V3_AUX           A  @SCM_LIB.SCM(SCH_1):P3V3_AUX

Q_RES  I132  R815   [Q_RES_0402LF-10K,0.10%,1/16W,CA]
    1  P3V3_AUX           A  @SCM_LIB.SCM(SCH_1):P3V3_AUX
    2  ID_LED_BUF_R       B  @SCM_LIB.SCM(SCH_1):ID_LED_BUF_R

Q_RES  I125  R816   [Q_RES_0402LF-10,1%,1/16W,CHIP,A]
    1  P3V3_LED           A  @SCM_LIB.SCM(SCH_1):P3V3_LED
    2  P3V3_AUX           B  @SCM_LIB.SCM(SCH_1):P3V3_AUX

Q_RES  I393  R817   [Q_RES_0402LF-100K,1%,1/16W,EMPB]
    1  SMB_BMC_MM13_R_SCL      A  @SCM_LIB.SCM(SCH_1):SMB_BMC_MM13_R_SCL
    2  GND                B  @SCM_LIB.SCM(SCH_1):GND

Q_RES  I392  R818   [Q_RES_0402LF-100K,1%,1/16W,EMPB]
    1  SMB_BMC_MM13_R_SDA      A  @SCM_LIB.SCM(SCH_1):SMB_BMC_MM13_R_SDA
    2  GND                B  @SCM_LIB.SCM(SCH_1):GND

Q_RES  I391  R819   [Q_RES_0402LF-100K,1%,1/16W,EMPB]
    1  SMB_BMC_MM14_R_SCL      A  @SCM_LIB.SCM(SCH_1):SMB_BMC_MM14_R_SCL
    2  GND                B  @SCM_LIB.SCM(SCH_1):GND

Q_RES  I390  R820   [Q_RES_0402LF-100K,1%,1/16W,EMPB]
    1  SMB_BMC_MM14_R_SDA      A  @SCM_LIB.SCM(SCH_1):SMB_BMC_MM14_R_SDA
    2  GND                B  @SCM_LIB.SCM(SCH_1):GND

Q_RES  I220  R821   [Q_RES_0402LF-4.7K,5%,1/16W,EMPA]
    1  P3V3_AUX           A  @SCM_LIB.SCM(SCH_1):P3V3_AUX
    2  FM_BMC_ONCTL_R_N      B  @SCM_LIB.SCM(SCH_1):FM_BMC_ONCTL_R_N

Q_RES  I456  R822   [Q_RES_0402LF-0,5%,1/16W,CHIP,CA]
    1  FM_PRSNT_1_N       A  @SCM_LIB.SCM(SCH_1):FM_PRSNT_1_N
    2  FM_PRSNT_0_R_N      B  @SCM_LIB.SCM(SCH_1):FM_PRSNT_0_R_N

Q_RES  I234  R823   [Q_RES_0402LF-100K,1%,1/16W,CHIA]
    1  GND                A  @SCM_LIB.SCM(SCH_1):GND
    2  FM_VIRTUAL_RESEAT      B  @SCM_LIB.SCM(SCH_1):FM_VIRTUAL_RESEAT

Q_RES  I223  R824   [Q_RES_0402LF-33       ,1%  ,1/A]
    2  FM_VIRTUAL_RESEAT_BMC      B  @SCM_LIB.SCM(SCH_1):FM_VIRTUAL_RESEAT_BMC
    1  FM_VIRTUAL_RESEAT      A  @SCM_LIB.SCM(SCH_1):FM_VIRTUAL_RESEAT

Q_RES  I313  R825   [Q_RES_0402LF-33       ,1%  ,1/A]
    2  RST_ROT_CPU_R_N      B  @SCM_LIB.SCM(SCH_1):RST_ROT_CPU_R_N
    1  RST_ROT_CPU_N      A  @SCM_LIB.SCM(SCH_1):RST_ROT_CPU_N

Q_RES  I241  R828   [Q_RES_0402LF-4.7K,5%,1/16W,CHIA]
    2  RST_ROT_CPU_N      B  @SCM_LIB.SCM(SCH_1):RST_ROT_CPU_N
    1  P3V3_AUX           A  @SCM_LIB.SCM(SCH_1):P3V3_AUX

Q_RES  I62  R829   [Q_RES_0402LF-25.5K,1%,1/16W,CHA]
    2  PU39_ADJ           B  @SCM_LIB.SCM(SCH_1):PU39_ADJ
    1  P2V5_AUX           A  @SCM_LIB.SCM(SCH_1):P2V5_AUX

Q_RES  I61  R830   [Q_RES_0402LF-12K,1%,1/16W,CHIPA]
    1  PU39_ADJ           A  @SCM_LIB.SCM(SCH_1):PU39_ADJ
    2  GND                B  @SCM_LIB.SCM(SCH_1):GND

Q_RES  I98  R831   [Q_RES_0402LF-15K,1%,1/16W,CHIPA]
    2  PU40_ADJ           B  @SCM_LIB.SCM(SCH_1):PU40_ADJ
    1  P1V8_AUX           A  @SCM_LIB.SCM(SCH_1):P1V8_AUX

Q_RES  I97  R832   [Q_RES_0402LF-12K,1%,1/16W,CHIPA]
    1  PU40_ADJ           A  @SCM_LIB.SCM(SCH_1):PU40_ADJ
    2  GND                B  @SCM_LIB.SCM(SCH_1):GND

Q_RES  I312  R833   [Q_RES_0402LF-33       ,1%  ,1/A]
    2  FM_ESPI_PLD_R_EN      B  @SCM_LIB.SCM(SCH_1):FM_ESPI_PLD_R_EN
    1  FM_ESPI_PLD_EN      A  @SCM_LIB.SCM(SCH_1):FM_ESPI_PLD_EN

Q_RES  I225  R836   [Q_RES_0402LF-33       ,1%  ,1/A]
    2  PWRGD_PSU_AC_PWROK_BMC      B  @SCM_LIB.SCM(SCH_1):PWRGD_PSU_AC_PWROK_BMC
    1  PWRGD_PSU_AC_PWROK      A  @SCM_LIB.SCM(SCH_1):PWRGD_PSU_AC_PWROK

Q_RES  I406  R837   [Q_RES_0402LF-33       ,1%  ,1/B]
    2  PWRGD_PSU_AC_PWROK_PLD      B  @SCM_LIB.SCM(SCH_1):PWRGD_PSU_AC_PWROK_PLD
    1  PWRGD_PSU_AC_PWROK      A  @SCM_LIB.SCM(SCH_1):PWRGD_PSU_AC_PWROK

Q_RES  I140  R839   [Q_RES_0402LF-8.2K     ,5%  ,1/A]
    1  PWR_LED            A  @SCM_LIB.SCM(SCH_1):PWR_LED
    2  GND                B  @SCM_LIB.SCM(SCH_1):GND

Q_RES  I295  R840   [Q_RES_0402LF-33       ,1%  ,1/A]
    2  PWRGD_SYS_PWROK_BMC      B  @SCM_LIB.SCM(SCH_1):PWRGD_SYS_PWROK_BMC
    1  PWRGD_SYS_PWROK      A  @SCM_LIB.SCM(SCH_1):PWRGD_SYS_PWROK

Q_RES  I289  R841   [Q_RES_0402LF-33       ,1%  ,1/A]
    1  PWRGD_SYS_PWROK_PLD      A  @SCM_LIB.SCM(SCH_1):PWRGD_SYS_PWROK_PLD
    2  PWRGD_SYS_PWROK      B  @SCM_LIB.SCM(SCH_1):PWRGD_SYS_PWROK

Q_RES  I168  R842   [Q_RES_0402LF-4.7K,5%,1/16W,CHIA]
    2  SMB_BMC_ALERT9_N      B  @SCM_LIB.SCM(SCH_1):SMB_BMC_ALERT9_N
    1  P3V3_AUX           A  @SCM_LIB.SCM(SCH_1):P3V3_AUX

Q_RES  I177  R843   [Q_RES_0402LF-4.7K,5%,1/16W,CHIA]
    2  SMB_BMC_ALERT10_N      B  @SCM_LIB.SCM(SCH_1):SMB_BMC_ALERT10_N
    1  P3V3_AUX           A  @SCM_LIB.SCM(SCH_1):P3V3_AUX

Q_RES  I179  R844   [Q_RES_0402LF-4.7K,5%,1/16W,CHIA]
    2  SMB_BMC_ALERT12_N      B  @SCM_LIB.SCM(SCH_1):SMB_BMC_ALERT12_N
    1  P3V3_AUX           A  @SCM_LIB.SCM(SCH_1):P3V3_AUX

Q_RES  I178  R845   [Q_RES_0402LF-4.7K,5%,1/16W,EMPA]
    1  P3V3_AUX           A  @SCM_LIB.SCM(SCH_1):P3V3_AUX
    2  FM_MASTER_MB_N      B  @SCM_LIB.SCM(SCH_1):FM_MASTER_MB_N

Q_RES  I181  R846   [Q_RES_0402LF-4.7K,5%,1/16W,EMPA]
    1  P3V3_AUX           A  @SCM_LIB.SCM(SCH_1):P3V3_AUX
    2  FM_BMC_EN_DET_R      B  @SCM_LIB.SCM(SCH_1):FM_BMC_EN_DET_R

Q_RES  I182  R848   [Q_RES_0402LF-4.7K,5%,1/16W,CHIA]
    2  SMB_BMC_ALERT16_N      B  @SCM_LIB.SCM(SCH_1):SMB_BMC_ALERT16_N
    1  P3V3_AUX           A  @SCM_LIB.SCM(SCH_1):P3V3_AUX

Q_RES  I184  R851   [Q_RES_0402LF-4.7K,5%,1/16W,CHIA]
    2  SMB_BMC_ALERT15_N      B  @SCM_LIB.SCM(SCH_1):SMB_BMC_ALERT15_N
    1  P3V3_AUX           A  @SCM_LIB.SCM(SCH_1):P3V3_AUX

Q_RES  I357  R852   [Q_RES_0402LF-33       ,1%  ,1/A]
    1  FM_BMC_MUX_CS_SPI_SEL_0      A  @SCM_LIB.SCM(SCH_1):FM_BMC_MUX_CS_SPI_SEL_0
    2  FM_BMC_BIOS_MUX_CS_SPI_R_SEL_0      B  @SCM_LIB.SCM(SCH_1):FM_BMC_BIOS_MUX_CS_SPI_R_SEL_0

Q_RES  I339  R859   [Q_RES_0402LF-33       ,1%  ,1/A]
    1  SPI_SYS_R_CLK      A  @SCM_LIB.SCM(SCH_1):SPI_SYS_R_CLK
    2  SPI_SYS_MUX_CLK      B  @SCM_LIB.SCM(SCH_1):SPI_SYS_MUX_CLK

Q_RES  I337  R860   [Q_RES_0402LF-33       ,1%  ,1/A]
    1  SPI_SYS_R_MOSI      A  @SCM_LIB.SCM(SCH_1):SPI_SYS_R_MOSI
    2  SPI_SYS_MUX_MOSI      B  @SCM_LIB.SCM(SCH_1):SPI_SYS_MUX_MOSI

Q_RES  I338  R861   [Q_RES_0402LF-33       ,1%  ,1/A]
    1  SPI_SYS_R_MISO      A  @SCM_LIB.SCM(SCH_1):SPI_SYS_R_MISO
    2  SPI_SYS_MUX_MISO      B  @SCM_LIB.SCM(SCH_1):SPI_SYS_MUX_MISO

Q_RES  I340  R862   [Q_RES_0402LF-33       ,1%  ,1/A]
    1  SPI_SYS_WP_R_IO2      A  @SCM_LIB.SCM(SCH_1):SPI_SYS_WP_R_IO2
    2  SPI_SYS_MUX_WP_IO2      B  @SCM_LIB.SCM(SCH_1):SPI_SYS_MUX_WP_IO2

Q_RES  I341  R863   [Q_RES_0402LF-33       ,1%  ,1/A]
    2  SPI_SYS_MUX_HOLD_IO3      B  @SCM_LIB.SCM(SCH_1):SPI_SYS_MUX_HOLD_IO3
    1  SPI_SYS_HOLD_R_IO3      A  @SCM_LIB.SCM(SCH_1):SPI_SYS_HOLD_R_IO3

Q_RES  I342  R864   [Q_RES_0402LF-33       ,1%  ,1/A]
    1  SPI_SYS_CS0_N      A  @SCM_LIB.SCM(SCH_1):SPI_SYS_CS0_N
    2  SPI_PCH_SECURE_CS0_N      B  @SCM_LIB.SCM(SCH_1):SPI_PCH_SECURE_CS0_N

Q_RES  I311  R866   [Q_RES_0402LF-10K,1%,1/16W,CHIPA]
    2  GND                B  @SCM_LIB.SCM(SCH_1):GND
    1  FM_BMC_BIOS_MUX_CS_SPI_R_SEL_0      A  @SCM_LIB.SCM(SCH_1):FM_BMC_BIOS_MUX_CS_SPI_R_SEL_0

Q_RES  I315  R870   [Q_RES_0402LF-4.7K,5%,1/16W,EMPA]
    2  PD_BIOS_MUX_EN_N      B  @SCM_LIB.SCM(SCH_1):PD_BIOS_MUX_EN_N
    1  P3V3_AUX           A  @SCM_LIB.SCM(SCH_1):P3V3_AUX

SW4S_DHNF02FTVTR  I1   SW1    [SW4S_DHNF02FTVTR-SW4S_DHNF-02FA]
    2  PU_JTAG_TCK_MUX      2  @SCM_LIB.SCM(SCH_1):PU_JTAG_TCK_MUX
    1  PD_BMC_DISABLE      1  @SCM_LIB.SCM(SCH_1):PD_BMC_DISABLE
    4  FM_JTAG_TCK_MUX_BMC_SEL_R      4  @SCM_LIB.SCM(SCH_1):FM_JTAG_TCK_MUX_BMC_SEL_R
    3  FM_BMC_DISABLE      3  @SCM_LIB.SCM(SCH_1):FM_BMC_DISABLE

SW4S_DHNF02FTVTR  I195  SW2    [SW4S_DHNF02FTVTR-SW4S_DHNF-02FA]
    3  SPI_BMC_BOOT_MOSI      3  @SCM_LIB.SCM(SCH_1):SPI_BMC_BOOT_MOSI
    4  SPI_BMC_BOOT_MISO      4  @SCM_LIB.SCM(SCH_1):SPI_BMC_BOOT_MISO
    2  PU_SPI_BMC_BOOT_MISO      2  @SCM_LIB.SCM(SCH_1):PU_SPI_BMC_BOOT_MISO
    1  PD_SPI_BMC_BOOT_MOSI      1  @SCM_LIB.SCM(SCH_1):PD_SPI_BMC_BOOT_MOSI

SW4S_DHNF02FTVTR  I37  SW3    [SW4S_DHNF02FTVTR-SW4S_DHNF-02FA]
    2  PD_JTAGEN          2  @SCM_LIB.SCM(SCH_1):PD_JTAGEN
    1  PD_BMC_DEBUG       1  @SCM_LIB.SCM(SCH_1):PD_BMC_DEBUG
    4  MB_JTAG_PLD_R_JTAGEN      4  @SCM_LIB.SCM(SCH_1):MB_JTAG_PLD_R_JTAGEN
    3  FM_BMC_DEBUG_SW_N      3  @SCM_LIB.SCM(SCH_1):FM_BMC_DEBUG_SW_N

SW2S_TA31E2KQTR  I136  SW6    [SW2S_TA31E2KQTR-SW2S_TA3-1E2K-A]
    2  REAR_PWR_BTN_N      2  @SCM_LIB.SCM(SCH_1):REAR_PWR_BTN_N
   G3  GND               G3  @SCM_LIB.SCM(SCH_1):GND
   G2  GND               G2  @SCM_LIB.SCM(SCH_1):GND
   G1  GND               G1  @SCM_LIB.SCM(SCH_1):GND
    1  GND                1  @SCM_LIB.SCM(SCH_1):GND

SW2S_TA31E2KQTR  I137  SW7    [SW2S_TA31E2KQTR-SW2S_TA3-1E2K-A]
    2  REAR_ID_RST_BTN_N      2  @SCM_LIB.SCM(SCH_1):REAR_ID_RST_BTN_N
   G3  GND               G3  @SCM_LIB.SCM(SCH_1):GND
   G2  GND               G2  @SCM_LIB.SCM(SCH_1):GND
   G1  GND               G1  @SCM_LIB.SCM(SCH_1):GND
    1  GND                1  @SCM_LIB.SCM(SCH_1):GND

K4A8G165WCBCTD  I196  U1     [K4A8G165WCBCTD-K4A8G165WC-BCTDA]
   F9  PD_M_BMC_DDR4_ZQ     ZQ  @SCM_LIB.SCM(SCH_1):PD_M_BMC_DDR4_ZQ
   N9  PD_M_BMC_DDR4_TEN    TEN  @SCM_LIB.SCM(SCH_1):PD_M_BMC_DDR4_TEN
   T3  PD_M_BMC_DDR4_PAR    PAR  @SCM_LIB.SCM(SCH_1):PD_M_BMC_DDR4_PAR
   R9  P2V5_AUX        VPP1  @SCM_LIB.SCM(SCH_1):P2V5_AUX
   B1  P2V5_AUX        VPP0  @SCM_LIB.SCM(SCH_1):P2V5_AUX
   J8  P1V2_AUX       VDDQ9  @SCM_LIB.SCM(SCH_1):P1V2_AUX
   J2  P1V2_AUX       VDDQ8  @SCM_LIB.SCM(SCH_1):P1V2_AUX
   G9  P1V2_AUX       VDDQ7  @SCM_LIB.SCM(SCH_1):P1V2_AUX
   G1  P1V2_AUX       VDDQ6  @SCM_LIB.SCM(SCH_1):P1V2_AUX
   F8  P1V2_AUX       VDDQ5  @SCM_LIB.SCM(SCH_1):P1V2_AUX
   F2  P1V2_AUX       VDDQ4  @SCM_LIB.SCM(SCH_1):P1V2_AUX
   D9  P1V2_AUX       VDDQ3  @SCM_LIB.SCM(SCH_1):P1V2_AUX
   C1  P1V2_AUX       VDDQ2  @SCM_LIB.SCM(SCH_1):P1V2_AUX
   A9  P1V2_AUX       VDDQ1  @SCM_LIB.SCM(SCH_1):P1V2_AUX
   A1  P1V2_AUX       VDDQ0  @SCM_LIB.SCM(SCH_1):P1V2_AUX
   T9  P1V2_AUX        VDD9  @SCM_LIB.SCM(SCH_1):P1V2_AUX
   R1  P1V2_AUX        VDD8  @SCM_LIB.SCM(SCH_1):P1V2_AUX
   L9  P1V2_AUX        VDD7  @SCM_LIB.SCM(SCH_1):P1V2_AUX
   L1  P1V2_AUX        VDD6  @SCM_LIB.SCM(SCH_1):P1V2_AUX
   J9  P1V2_AUX        VDD5  @SCM_LIB.SCM(SCH_1):P1V2_AUX
   J1  P1V2_AUX        VDD4  @SCM_LIB.SCM(SCH_1):P1V2_AUX
   G7  P1V2_AUX        VDD3  @SCM_LIB.SCM(SCH_1):P1V2_AUX
   D1  P1V2_AUX        VDD2  @SCM_LIB.SCM(SCH_1):P1V2_AUX
   B9  P1V2_AUX        VDD1  @SCM_LIB.SCM(SCH_1):P1V2_AUX
   B3  P1V2_AUX        VDD0  @SCM_LIB.SCM(SCH_1):P1V2_AUX
   M1  P0V6_DDR_VREF_AUX  VREFCA  @SCM_LIB.SCM(SCH_1):P0V6_DDR_VREF_AUX
   E9  M_BMC_DDR4_ZQU   VSS2  @SCM_LIB.SCM(SCH_1):M_BMC_DDR4_ZQU
   P1  M_BMC_DDR4_RST_N  RESET_N  @SCM_LIB.SCM(SCH_1):M_BMC_DDR4_RST_N
   L2  M_BMC_DDR4_MWE_N  WE_N||A14  @SCM_LIB.SCM(SCH_1):M_BMC_DDR4_MWE_N
   L8  M_BMC_DDR4_MRAS_N  RAS_N  @SCM_LIB.SCM(SCH_1):M_BMC_DDR4_MRAS_N
   K3  M_BMC_DDR4_MODT    ODT  @SCM_LIB.SCM(SCH_1):M_BMC_DDR4_MODT
   E2  M_BMC_DDR4_MDM1  DMU_N||DBIU_N  @SCM_LIB.SCM(SCH_1):M_BMC_DDR4_MDM1
   E7  M_BMC_DDR4_MDM0  DML_N||DBIL_N  @SCM_LIB.SCM(SCH_1):M_BMC_DDR4_MDM0
   L7  M_BMC_DDR4_MCS_N   CS_N  @SCM_LIB.SCM(SCH_1):M_BMC_DDR4_MCS_N
   K7  M_BMC_DDR4_MCLK_DP   CK_T  @SCM_LIB.SCM(SCH_1):M_BMC_DDR4_MCLK_DP
   K8  M_BMC_DDR4_MCLK_DN   CK_C  @SCM_LIB.SCM(SCH_1):M_BMC_DDR4_MCLK_DN
   K2  M_BMC_DDR4_MCKE    CKE  @SCM_LIB.SCM(SCH_1):M_BMC_DDR4_MCKE
   M8  M_BMC_DDR4_MCAS_N  CAS_N||A15  @SCM_LIB.SCM(SCH_1):M_BMC_DDR4_MCAS_N
   M2  M_BMC_DDR4_MBG0    BG0  @SCM_LIB.SCM(SCH_1):M_BMC_DDR4_MBG0
   N8  M_BMC_DDR4_MBA1    BA1  @SCM_LIB.SCM(SCH_1):M_BMC_DDR4_MBA1
   N2  M_BMC_DDR4_MBA0    BA0  @SCM_LIB.SCM(SCH_1):M_BMC_DDR4_MBA0
   L3  M_BMC_DDR4_MACT_N  ACT_N  @SCM_LIB.SCM(SCH_1):M_BMC_DDR4_MACT_N
   R7  M_BMC_DDR4_MA<9>     A9  @SCM_LIB.SCM(SCH_1):M_BMC_DDR4_MA<9>
   R2  M_BMC_DDR4_MA<8>     A8  @SCM_LIB.SCM(SCH_1):M_BMC_DDR4_MA<8>
   R8  M_BMC_DDR4_MA<7>     A7  @SCM_LIB.SCM(SCH_1):M_BMC_DDR4_MA<7>
   P2  M_BMC_DDR4_MA<6>     A6  @SCM_LIB.SCM(SCH_1):M_BMC_DDR4_MA<6>
   P8  M_BMC_DDR4_MA<5>     A5  @SCM_LIB.SCM(SCH_1):M_BMC_DDR4_MA<5>
   N3  M_BMC_DDR4_MA<4>     A4  @SCM_LIB.SCM(SCH_1):M_BMC_DDR4_MA<4>
   N7  M_BMC_DDR4_MA<3>     A3  @SCM_LIB.SCM(SCH_1):M_BMC_DDR4_MA<3>
   R3  M_BMC_DDR4_MA<2>     A2  @SCM_LIB.SCM(SCH_1):M_BMC_DDR4_MA<2>
   P7  M_BMC_DDR4_MA<1>     A1  @SCM_LIB.SCM(SCH_1):M_BMC_DDR4_MA<1>
   T8  M_BMC_DDR4_MA<13>    A13  @SCM_LIB.SCM(SCH_1):M_BMC_DDR4_MA<13>
   M7  M_BMC_DDR4_MA<12>  A12||BC_N  @SCM_LIB.SCM(SCH_1):M_BMC_DDR4_MA<12>
   T2  M_BMC_DDR4_MA<11>    A11  @SCM_LIB.SCM(SCH_1):M_BMC_DDR4_MA<11>
   M3  M_BMC_DDR4_MA<10>  A10||AP  @SCM_LIB.SCM(SCH_1):M_BMC_DDR4_MA<10>
   P3  M_BMC_DDR4_MA<0>     A0  @SCM_LIB.SCM(SCH_1):M_BMC_DDR4_MA<0>
   B7  M_BMC_DDR4_DQS1_P  DQSU_T  @SCM_LIB.SCM(SCH_1):M_BMC_DDR4_DQS1_P
   A7  M_BMC_DDR4_DQS1_N  DQSU_C  @SCM_LIB.SCM(SCH_1):M_BMC_DDR4_DQS1_N
   G3  M_BMC_DDR4_DQS0_P  DQSL_T  @SCM_LIB.SCM(SCH_1):M_BMC_DDR4_DQS0_P
   F3  M_BMC_DDR4_DQS0_N  DQSL_C  @SCM_LIB.SCM(SCH_1):M_BMC_DDR4_DQS0_N
   B8  M_BMC_DDR4_DQ<9>   DQU1  @SCM_LIB.SCM(SCH_1):M_BMC_DDR4_DQ<9>
   A3  M_BMC_DDR4_DQ<8>   DQU0  @SCM_LIB.SCM(SCH_1):M_BMC_DDR4_DQ<8>
   J7  M_BMC_DDR4_DQ<7>   DQL7  @SCM_LIB.SCM(SCH_1):M_BMC_DDR4_DQ<7>
   J3  M_BMC_DDR4_DQ<6>   DQL6  @SCM_LIB.SCM(SCH_1):M_BMC_DDR4_DQ<6>
   H8  M_BMC_DDR4_DQ<5>   DQL5  @SCM_LIB.SCM(SCH_1):M_BMC_DDR4_DQ<5>
   H2  M_BMC_DDR4_DQ<4>   DQL4  @SCM_LIB.SCM(SCH_1):M_BMC_DDR4_DQ<4>
   H7  M_BMC_DDR4_DQ<3>   DQL3  @SCM_LIB.SCM(SCH_1):M_BMC_DDR4_DQ<3>
   H3  M_BMC_DDR4_DQ<2>   DQL2  @SCM_LIB.SCM(SCH_1):M_BMC_DDR4_DQ<2>
   F7  M_BMC_DDR4_DQ<1>   DQL1  @SCM_LIB.SCM(SCH_1):M_BMC_DDR4_DQ<1>
   D7  M_BMC_DDR4_DQ<15>   DQU7  @SCM_LIB.SCM(SCH_1):M_BMC_DDR4_DQ<15>
   D3  M_BMC_DDR4_DQ<14>   DQU6  @SCM_LIB.SCM(SCH_1):M_BMC_DDR4_DQ<14>
   C8  M_BMC_DDR4_DQ<13>   DQU5  @SCM_LIB.SCM(SCH_1):M_BMC_DDR4_DQ<13>
   C2  M_BMC_DDR4_DQ<12>   DQU4  @SCM_LIB.SCM(SCH_1):M_BMC_DDR4_DQ<12>
   C7  M_BMC_DDR4_DQ<11>   DQU3  @SCM_LIB.SCM(SCH_1):M_BMC_DDR4_DQ<11>
   C3  M_BMC_DDR4_DQ<10>   DQU2  @SCM_LIB.SCM(SCH_1):M_BMC_DDR4_DQ<10>
   G2  M_BMC_DDR4_DQ<0>   DQL0  @SCM_LIB.SCM(SCH_1):M_BMC_DDR4_DQ<0>
   M9  M_BMC_DDR4_BG1   VSS6  @SCM_LIB.SCM(SCH_1):M_BMC_DDR4_BG1
   P9  M_BMC_DDR4_ALERT_N  ALERT_N  @SCM_LIB.SCM(SCH_1):M_BMC_DDR4_ALERT_N
   H9  GND            VSSQ9  @SCM_LIB.SCM(SCH_1):GND
   H1  GND            VSSQ8  @SCM_LIB.SCM(SCH_1):GND
   F1  GND            VSSQ7  @SCM_LIB.SCM(SCH_1):GND
   E8  GND            VSSQ6  @SCM_LIB.SCM(SCH_1):GND
   E3  GND            VSSQ5  @SCM_LIB.SCM(SCH_1):GND
   D8  GND            VSSQ4  @SCM_LIB.SCM(SCH_1):GND
   D2  GND            VSSQ3  @SCM_LIB.SCM(SCH_1):GND
   C9  GND            VSSQ2  @SCM_LIB.SCM(SCH_1):GND
   A8  GND            VSSQ1  @SCM_LIB.SCM(SCH_1):GND
   A2  GND            VSSQ0  @SCM_LIB.SCM(SCH_1):GND
   T1  GND             VSS8  @SCM_LIB.SCM(SCH_1):GND
   N1  GND             VSS7  @SCM_LIB.SCM(SCH_1):GND
   K9  GND             VSS5  @SCM_LIB.SCM(SCH_1):GND
   K1  GND             VSS4  @SCM_LIB.SCM(SCH_1):GND
   G8  GND             VSS3  @SCM_LIB.SCM(SCH_1):GND
   E1  GND             VSS1  @SCM_LIB.SCM(SCH_1):GND
   B2  GND             VSS0  @SCM_LIB.SCM(SCH_1):GND
   T7  GND              NC1  @SCM_LIB.SCM(SCH_1):GND

SN74LVC1G3157DCKR  I20  U2     [SN74LVC1G3157DCKR-SN74LVC1G315A]
    3  UART_BMC_5_TXD_R     B0  @SCM_LIB.SCM(SCH_1):UART_BMC_5_TXD_R
    1  UART_BMC_1_TXD_R     B1  @SCM_LIB.SCM(SCH_1):UART_BMC_1_TXD_R
    4  SPA_SOUT_SW_BUF      A  @SCM_LIB.SCM(SCH_1):SPA_SOUT_SW_BUF
    5  P3V3_AUX         VCC  @SCM_LIB.SCM(SCH_1):P3V3_AUX
    2  GND              GND  @SCM_LIB.SCM(SCH_1):GND
    6  FM_BMC_DEBUG_SW_N      S  @SCM_LIB.SCM(SCH_1):FM_BMC_DEBUG_SW_N

SN74LVC1G3157DCKR  I43  U3     [SN74LVC1G3157DCKR-SN74LVC1G315A]
    3  UART_BMC_5_RXD_R     B0  @SCM_LIB.SCM(SCH_1):UART_BMC_5_RXD_R
    1  UART_BMC_1_RXD_R     B1  @SCM_LIB.SCM(SCH_1):UART_BMC_1_RXD_R
    4  SPA_SIN_SW_BUF      A  @SCM_LIB.SCM(SCH_1):SPA_SIN_SW_BUF
    5  P3V3_AUX         VCC  @SCM_LIB.SCM(SCH_1):P3V3_AUX
    2  GND              GND  @SCM_LIB.SCM(SCH_1):GND
    6  FM_BMC_DEBUG_SW_N      S  @SCM_LIB.SCM(SCH_1):FM_BMC_DEBUG_SW_N

TMP75AIDGKR  I23  U4     [TMP75AIDGKR-TMP75AIDGKR,SMLF,IA]
    5  TEMP_A2           A2  @SCM_LIB.SCM(SCH_1):TEMP_A2
    6  TEMP_A1           A1  @SCM_LIB.SCM(SCH_1):TEMP_A1
    7  TEMP_A0           A0  @SCM_LIB.SCM(SCH_1):TEMP_A0
    1  SMB_BMC_MM15_R1_SDA    SDA  @SCM_LIB.SCM(SCH_1):SMB_BMC_MM15_R1_SDA
    2  SMB_BMC_MM15_R1_SCL    SCL  @SCM_LIB.SCM(SCH_1):SMB_BMC_MM15_R1_SCL
    3  SMB_BMC_ALERT15_R_N  ALERT  @SCM_LIB.SCM(SCH_1):SMB_BMC_ALERT15_R_N
    8  P3V3_AUX          V+  @SCM_LIB.SCM(SCH_1):P3V3_AUX
    4  GND              GND  @SCM_LIB.SCM(SCH_1):GND

AST2600A1GP  I116  U5     [AST2600A1GP-AST2600A1-GP,SMLF,A]
  Y22  GND            GND_Y22  @SCM_LIB.SCM(SCH_1):GND
   Y6  GND            GND_Y6  @SCM_LIB.SCM(SCH_1):GND
  W25  GND            GND_W25  @SCM_LIB.SCM(SCH_1):GND
  W22  GND            GND_W22  @SCM_LIB.SCM(SCH_1):GND
  W12  GND            GND_W12  @SCM_LIB.SCM(SCH_1):GND
  W11  GND            GND_W11  @SCM_LIB.SCM(SCH_1):GND
  W10  GND            GND_W10  @SCM_LIB.SCM(SCH_1):GND
   W9  GND            GND_W9  @SCM_LIB.SCM(SCH_1):GND
   W8  GND            GND_W8  @SCM_LIB.SCM(SCH_1):GND
   W6  GND            GND_W6  @SCM_LIB.SCM(SCH_1):GND
   W5  GND            GND_W5  @SCM_LIB.SCM(SCH_1):GND
  V19  GND            GND_V19  @SCM_LIB.SCM(SCH_1):GND
  V18  GND            GND_V18  @SCM_LIB.SCM(SCH_1):GND
  V17  GND            GND_V17  @SCM_LIB.SCM(SCH_1):GND
  V16  GND            GND_V16  @SCM_LIB.SCM(SCH_1):GND
  V15  GND            GND_V15  @SCM_LIB.SCM(SCH_1):GND
  V14  GND            GND_V14  @SCM_LIB.SCM(SCH_1):GND
  V12  GND            GND_V12  @SCM_LIB.SCM(SCH_1):GND
  V11  GND            GND_V11  @SCM_LIB.SCM(SCH_1):GND
   V5  GND            GND_V5  @SCM_LIB.SCM(SCH_1):GND
  U23  GND            GND_U23  @SCM_LIB.SCM(SCH_1):GND
  U22  GND            GND_U22  @SCM_LIB.SCM(SCH_1):GND
  U19  GND            GND_U19  @SCM_LIB.SCM(SCH_1):GND
  U14  GND            GND_U14  @SCM_LIB.SCM(SCH_1):GND
  U12  GND            GND_U12  @SCM_LIB.SCM(SCH_1):GND
  U11  GND            GND_U11  @SCM_LIB.SCM(SCH_1):GND
  U10  GND            GND_U10  @SCM_LIB.SCM(SCH_1):GND
   U9  GND            GND_U9  @SCM_LIB.SCM(SCH_1):GND
   U8  GND            GND_U8  @SCM_LIB.SCM(SCH_1):GND
   U2  GND            GND_U2  @SCM_LIB.SCM(SCH_1):GND
  T19  GND            GND_T19  @SCM_LIB.SCM(SCH_1):GND
  T18  GND            GND_T18  @SCM_LIB.SCM(SCH_1):GND
  T17  GND            GND_T17  @SCM_LIB.SCM(SCH_1):GND
  T16  GND            GND_T16  @SCM_LIB.SCM(SCH_1):GND
  T15  GND            GND_T15  @SCM_LIB.SCM(SCH_1):GND
  T12  GND            GND_T12  @SCM_LIB.SCM(SCH_1):GND
  T11  GND            GND_T11  @SCM_LIB.SCM(SCH_1):GND
   T4  GND            GND_T4  @SCM_LIB.SCM(SCH_1):GND
  R25  GND            GND_R25  @SCM_LIB.SCM(SCH_1):GND
  R19  GND            GND_R19  @SCM_LIB.SCM(SCH_1):GND
  R18  GND            GND_R18  @SCM_LIB.SCM(SCH_1):GND
  R17  GND            GND_R17  @SCM_LIB.SCM(SCH_1):GND
  R16  GND            GND_R16  @SCM_LIB.SCM(SCH_1):GND
  R15  GND            GND_R15  @SCM_LIB.SCM(SCH_1):GND
  R11  GND            GND_R11  @SCM_LIB.SCM(SCH_1):GND
   R8  GND            GND_R8  @SCM_LIB.SCM(SCH_1):GND
   R2  GND            GND_R2  @SCM_LIB.SCM(SCH_1):GND
  P19  GND            GND_P19  @SCM_LIB.SCM(SCH_1):GND
  P18  GND            GND_P18  @SCM_LIB.SCM(SCH_1):GND
  P17  GND            GND_P17  @SCM_LIB.SCM(SCH_1):GND
  P16  GND            GND_P16  @SCM_LIB.SCM(SCH_1):GND
  P15  GND            GND_P15  @SCM_LIB.SCM(SCH_1):GND
  P10  GND            GND_P10  @SCM_LIB.SCM(SCH_1):GND
   P9  GND            GND_P9  @SCM_LIB.SCM(SCH_1):GND
   P4  GND            GND_P4  @SCM_LIB.SCM(SCH_1):GND
  N19  GND            GND_N19  @SCM_LIB.SCM(SCH_1):GND
  N18  GND            GND_N18  @SCM_LIB.SCM(SCH_1):GND
  N17  GND            GND_N17  @SCM_LIB.SCM(SCH_1):GND
  N16  GND            GND_N16  @SCM_LIB.SCM(SCH_1):GND
  N15  GND            GND_N15  @SCM_LIB.SCM(SCH_1):GND
  N10  GND            GND_N10  @SCM_LIB.SCM(SCH_1):GND
   N9  GND            GND_N9  @SCM_LIB.SCM(SCH_1):GND
   N6  GND            GND_N6  @SCM_LIB.SCM(SCH_1):GND
   N2  GND            GND_N2  @SCM_LIB.SCM(SCH_1):GND
  M19  GND            GND_M19  @SCM_LIB.SCM(SCH_1):GND
  M18  GND            GND_M18  @SCM_LIB.SCM(SCH_1):GND
  M17  GND            GND_M17  @SCM_LIB.SCM(SCH_1):GND
  M16  GND            GND_M16  @SCM_LIB.SCM(SCH_1):GND
  M15  GND            GND_M15  @SCM_LIB.SCM(SCH_1):GND
  M12  GND            GND_M12  @SCM_LIB.SCM(SCH_1):GND
  M10  GND            GND_M10  @SCM_LIB.SCM(SCH_1):GND
   M9  GND            GND_M9  @SCM_LIB.SCM(SCH_1):GND
   M4  GND            GND_M4  @SCM_LIB.SCM(SCH_1):GND
  L25  GND            GND_L25  @SCM_LIB.SCM(SCH_1):GND
  L19  GND            GND_L19  @SCM_LIB.SCM(SCH_1):GND
  L18  GND            GND_L18  @SCM_LIB.SCM(SCH_1):GND
  L17  GND            GND_L17  @SCM_LIB.SCM(SCH_1):GND
  L16  GND            GND_L16  @SCM_LIB.SCM(SCH_1):GND
  L15  GND            GND_L15  @SCM_LIB.SCM(SCH_1):GND
  L12  GND            GND_L12  @SCM_LIB.SCM(SCH_1):GND
  L11  GND            GND_L11  @SCM_LIB.SCM(SCH_1):GND
   L8  GND            GND_L8  @SCM_LIB.SCM(SCH_1):GND
   L2  GND            GND_L2  @SCM_LIB.SCM(SCH_1):GND
  K22  GND            GND_K22  @SCM_LIB.SCM(SCH_1):GND
  K15  GND            GND_K15  @SCM_LIB.SCM(SCH_1):GND
  K14  GND            GND_K14  @SCM_LIB.SCM(SCH_1):GND
  K13  GND            GND_K13  @SCM_LIB.SCM(SCH_1):GND
   K9  GND            GND_K9  @SCM_LIB.SCM(SCH_1):GND
   K8  GND            GND_K8  @SCM_LIB.SCM(SCH_1):GND
   K4  GND            GND_K4  @SCM_LIB.SCM(SCH_1):GND
  J19  GND            GND_J19  @SCM_LIB.SCM(SCH_1):GND
  J18  GND            GND_J18  @SCM_LIB.SCM(SCH_1):GND
  J17  GND            GND_J17  @SCM_LIB.SCM(SCH_1):GND
  J16  GND            GND_J16  @SCM_LIB.SCM(SCH_1):GND
  J15  GND            GND_J15  @SCM_LIB.SCM(SCH_1):GND
  J14  GND            GND_J14  @SCM_LIB.SCM(SCH_1):GND
  J13  GND            GND_J13  @SCM_LIB.SCM(SCH_1):GND
  J11  GND            GND_J11  @SCM_LIB.SCM(SCH_1):GND
   J2  GND            GND_J2  @SCM_LIB.SCM(SCH_1):GND
  H13  GND            GND_H13  @SCM_LIB.SCM(SCH_1):GND
  H11  GND            GND_H11  @SCM_LIB.SCM(SCH_1):GND
  H10  GND            GND_H10  @SCM_LIB.SCM(SCH_1):GND
   H9  GND            GND_H9  @SCM_LIB.SCM(SCH_1):GND
   H4  GND            GND_H4  @SCM_LIB.SCM(SCH_1):GND
  G25  GND            GND_G25  @SCM_LIB.SCM(SCH_1):GND
   G2  GND            GND_G2  @SCM_LIB.SCM(SCH_1):GND
  F21  GND            GND_F21  @SCM_LIB.SCM(SCH_1):GND
  F18  GND            GND_F18  @SCM_LIB.SCM(SCH_1):GND
  F17  GND            GND_F17  @SCM_LIB.SCM(SCH_1):GND
  F16  GND            GND_F16  @SCM_LIB.SCM(SCH_1):GND
  F14  GND            GND_F14  @SCM_LIB.SCM(SCH_1):GND
  F12  GND            GND_F12  @SCM_LIB.SCM(SCH_1):GND
  F10  GND            GND_F10  @SCM_LIB.SCM(SCH_1):GND
   F8  GND            GND_F8  @SCM_LIB.SCM(SCH_1):GND
   F6  GND            GND_F6  @SCM_LIB.SCM(SCH_1):GND
   E8  GND            GND_E8  @SCM_LIB.SCM(SCH_1):GND
  D25  GND            GND_D25  @SCM_LIB.SCM(SCH_1):GND
   C3  GND            GND_C3  @SCM_LIB.SCM(SCH_1):GND
  B23  GND            GND_B23  @SCM_LIB.SCM(SCH_1):GND
  B19  GND            GND_B19  @SCM_LIB.SCM(SCH_1):GND
  B15  GND            GND_B15  @SCM_LIB.SCM(SCH_1):GND
  B11  GND            GND_B11  @SCM_LIB.SCM(SCH_1):GND
   B5  GND            GND_B5  @SCM_LIB.SCM(SCH_1):GND
  AF26  GND            GND_AF26  @SCM_LIB.SCM(SCH_1):GND
  AF4  GND            GND_AF4  @SCM_LIB.SCM(SCH_1):GND
  AF1  GND            GND_AF1  @SCM_LIB.SCM(SCH_1):GND
  AE23  GND            GND_AE23  @SCM_LIB.SCM(SCH_1):GND
  AE20  GND            GND_AE20  @SCM_LIB.SCM(SCH_1):GND
  AE17  GND            GND_AE17  @SCM_LIB.SCM(SCH_1):GND
  AE13  GND            GND_AE13  @SCM_LIB.SCM(SCH_1):GND
  AE9  GND            GND_AE9  @SCM_LIB.SCM(SCH_1):GND
  AE6  GND            GND_AE6  @SCM_LIB.SCM(SCH_1):GND
  AE3  GND            GND_AE3  @SCM_LIB.SCM(SCH_1):GND
  AD4  GND            GND_AD4  @SCM_LIB.SCM(SCH_1):GND
  AD1  GND            GND_AD1  @SCM_LIB.SCM(SCH_1):GND
  AC25  GND            GND_AC25  @SCM_LIB.SCM(SCH_1):GND
  AC6  GND            GND_AC6  @SCM_LIB.SCM(SCH_1):GND
  AC2  GND            GND_AC2  @SCM_LIB.SCM(SCH_1):GND
  AA22  GND            GND_AA22  @SCM_LIB.SCM(SCH_1):GND
  AA20  GND            GND_AA20  @SCM_LIB.SCM(SCH_1):GND
  AA19  GND            GND_AA19  @SCM_LIB.SCM(SCH_1):GND
  AA15  GND            GND_AA15  @SCM_LIB.SCM(SCH_1):GND
  AA14  GND            GND_AA14  @SCM_LIB.SCM(SCH_1):GND
  AA10  GND            GND_AA10  @SCM_LIB.SCM(SCH_1):GND
  AA8  GND            GND_AA8  @SCM_LIB.SCM(SCH_1):GND
  AA7  GND            GND_AA7  @SCM_LIB.SCM(SCH_1):GND
  AA6  GND            GND_AA6  @SCM_LIB.SCM(SCH_1):GND
  AA3  GND            GND_AA3  @SCM_LIB.SCM(SCH_1):GND
  AA1  GND            GND_AA1  @SCM_LIB.SCM(SCH_1):GND
  A26  GND            GND_A26  @SCM_LIB.SCM(SCH_1):GND
   A5  GND            GND_A5  @SCM_LIB.SCM(SCH_1):GND
   A1  GND            GND_A1  @SCM_LIB.SCM(SCH_1):GND

AST2600A1GP  I181  U5     [AST2600A1GP-AST2600A1-GP,SMLF,A]
  W15  PGPPA_BMC_AUX  LPVDD  @SCM_LIB.SCM(SCH_1):PGPPA_BMC_AUX
  H14  P3V3_STBY_PLLAHVDD  PLLAHVDD  @SCM_LIB.SCM(SCH_1):P3V3_STBY_PLLAHVDD
  W21  P3V3_STBY_DACAV33  DACAV33_W21  @SCM_LIB.SCM(SCH_1):P3V3_STBY_DACAV33
  V21  P3V3_STBY_DACAV33  DACAV33_V21  @SCM_LIB.SCM(SCH_1):P3V3_STBY_DACAV33
  V23  P3V3_RTC_AUX   BATVDD  @SCM_LIB.SCM(SCH_1):P3V3_RTC_AUX
  K12  P3V3_RGM       PV33D_RGM_K12  @SCM_LIB.SCM(SCH_1):P3V3_RGM
  K11  P3V3_RGM       PV33D_RGM_K11  @SCM_LIB.SCM(SCH_1):P3V3_RGM
  M22  P3V3_P2V5_P1V8_RVDD  RVDD_M22  @SCM_LIB.SCM(SCH_1):P3V3_P2V5_P1V8_RVDD
  L22  P3V3_P2V5_P1V8_RVDD  RVDD_L22  @SCM_LIB.SCM(SCH_1):P3V3_P2V5_P1V8_RVDD
  K21  P3V3_P2V5_P1V8_RVDD  RVDD_K21  @SCM_LIB.SCM(SCH_1):P3V3_P2V5_P1V8_RVDD
  J21  P3V3_P2V5_P1V8_RVDD  RVDD_J21  @SCM_LIB.SCM(SCH_1):P3V3_P2V5_P1V8_RVDD
  H19  P3V3_P1V8_SD2VDD  SD2VDD_H19  @SCM_LIB.SCM(SCH_1):P3V3_P1V8_SD2VDD
  H18  P3V3_P1V8_SD2VDD  SD2VDD_H18  @SCM_LIB.SCM(SCH_1):P3V3_P1V8_SD2VDD
  H21  P3V3_P1V8_SD1VDD  SD1VDD_H21  @SCM_LIB.SCM(SCH_1):P3V3_P1V8_SD1VDD
  G21  P3V3_P1V8_SD1VDD  SD1VDD_G21  @SCM_LIB.SCM(SCH_1):P3V3_P1V8_SD1VDD
  F20  P3V3_P1V8_I2C_I3C  I3CVDDH_F20  @SCM_LIB.SCM(SCH_1):P3V3_P1V8_I2C_I3C
  F19  P3V3_P1V8_I2C_I3C  I3CVDDH_F19  @SCM_LIB.SCM(SCH_1):P3V3_P1V8_I2C_I3C
  W19  P3V3_AUX       PV33D_W19  @SCM_LIB.SCM(SCH_1):P3V3_AUX
  W18  P3V3_AUX       PV33D_W18  @SCM_LIB.SCM(SCH_1):P3V3_AUX
  W17  P3V3_AUX       PV33D_W17  @SCM_LIB.SCM(SCH_1):P3V3_AUX
  W16  P3V3_AUX       PV33D_W16  @SCM_LIB.SCM(SCH_1):P3V3_AUX
  T22  P3V3_AUX       PV33D_T22  @SCM_LIB.SCM(SCH_1):P3V3_AUX
  R22  P3V3_AUX       PV33D_R22  @SCM_LIB.SCM(SCH_1):P3V3_AUX
  P22  P3V3_AUX       PV33D_P22  @SCM_LIB.SCM(SCH_1):P3V3_AUX
  N22  P3V3_AUX       PV33D_N22  @SCM_LIB.SCM(SCH_1):P3V3_AUX
  H17  P3V3_AUX       PV33D_H17  @SCM_LIB.SCM(SCH_1):P3V3_AUX
  H16  P3V3_AUX       PV33D_H16  @SCM_LIB.SCM(SCH_1):P3V3_AUX
  H15  P3V3_AUX       PV33D_H15  @SCM_LIB.SCM(SCH_1):P3V3_AUX
  V10  P1V8_STBY_RC_VCC18A  PE_VCC18A  @SCM_LIB.SCM(SCH_1):P1V8_STBY_RC_VCC18A
   V9  P1V8_STBY_PE_VCC18A  RC_VCC18A  @SCM_LIB.SCM(SCH_1):P1V8_STBY_PE_VCC18A
   V8  P1V8_STBY_DP_VCC18A  DP_VCC18A  @SCM_LIB.SCM(SCH_1):P1V8_STBY_DP_VCC18A
   N5  P1V8_STBY_AVDDPLL  AVDDPLL  @SCM_LIB.SCM(SCH_1):P1V8_STBY_AVDDPLL
   V6  P1V8_AUX       PV18D_V6  @SCM_LIB.SCM(SCH_1):P1V8_AUX
   U6  P1V8_AUX       PV18D_U6  @SCM_LIB.SCM(SCH_1):P1V8_AUX
  W14  P1V8_AUX       PV18D_SLI_W14  @SCM_LIB.SCM(SCH_1):P1V8_AUX
  W13  P1V8_AUX       PV18D_SLI_W13  @SCM_LIB.SCM(SCH_1):P1V8_AUX
  V13  P1V8_AUX       PV18D_SLI_V13  @SCM_LIB.SCM(SCH_1):P1V8_AUX
  U13  P1V8_AUX       PV18D_SLI_U13  @SCM_LIB.SCM(SCH_1):P1V8_AUX
  T13  P1V8_AUX       PV18D_SLI_T13  @SCM_LIB.SCM(SCH_1):P1V8_AUX
  R13  P1V8_AUX       PV18D_SLI_R13  @SCM_LIB.SCM(SCH_1):P1V8_AUX
  P13  P1V8_AUX       PV18D_SLI_P13  @SCM_LIB.SCM(SCH_1):P1V8_AUX
  N13  P1V8_AUX       PV18D_SLI_N13  @SCM_LIB.SCM(SCH_1):P1V8_AUX
  M13  P1V8_AUX       PV18D_SLI_M13  @SCM_LIB.SCM(SCH_1):P1V8_AUX
  L13  P1V8_AUX       PV18D_SLI_L13  @SCM_LIB.SCM(SCH_1):P1V8_AUX
  J12  P1V8_AUX       PV18D_RGM_J12  @SCM_LIB.SCM(SCH_1):P1V8_AUX
  H12  P1V8_AUX       PV18D_RGM_H12  @SCM_LIB.SCM(SCH_1):P1V8_AUX
  R12  P1V8_AUX       PV18D_R12  @SCM_LIB.SCM(SCH_1):P1V8_AUX
  P12  P1V8_AUX       PV18D_P12  @SCM_LIB.SCM(SCH_1):P1V8_AUX
  N12  P1V8_AUX       PV18D_N12  @SCM_LIB.SCM(SCH_1):P1V8_AUX
   J8  P1V8_AUX       PV18D_J8  @SCM_LIB.SCM(SCH_1):P1V8_AUX
   H8  P1V8_AUX       PV18D_H8  @SCM_LIB.SCM(SCH_1):P1V8_AUX
   M6  P1V2_STBY_MVDD_CK  MVDD_CK  @SCM_LIB.SCM(SCH_1):P1V2_STBY_MVDD_CK
  U21  P1V2_P1V0_I3C_VDDL2  I3CVDDL2  @SCM_LIB.SCM(SCH_1):P1V2_P1V0_I3C_VDDL2
  V22  P1V2_P1V0_I3C_VDDL1  I3CVDDL1  @SCM_LIB.SCM(SCH_1):P1V2_P1V0_I3C_VDDL1
   T6  P1V2_AUX       MVDD_T6  @SCM_LIB.SCM(SCH_1):P1V2_AUX
   R6  P1V2_AUX       MVDD_R6  @SCM_LIB.SCM(SCH_1):P1V2_AUX
   P6  P1V2_AUX       MVDD_P6  @SCM_LIB.SCM(SCH_1):P1V2_AUX
   L6  P1V2_AUX       MVDD_L6  @SCM_LIB.SCM(SCH_1):P1V2_AUX
   K6  P1V2_AUX       MVDD_K6  @SCM_LIB.SCM(SCH_1):P1V2_AUX
   J6  P1V2_AUX       MVDD_J6  @SCM_LIB.SCM(SCH_1):P1V2_AUX
   H6  P1V2_AUX       MVDD_H6  @SCM_LIB.SCM(SCH_1):P1V2_AUX
   G6  P1V2_AUX       MVDD_G6  @SCM_LIB.SCM(SCH_1):P1V2_AUX
  U18  P1V2_AUX       IV12D_U18  @SCM_LIB.SCM(SCH_1):P1V2_AUX
  U17  P1V2_AUX       IV12D_U17  @SCM_LIB.SCM(SCH_1):P1V2_AUX
  U16  P1V2_AUX       IV12D_U16  @SCM_LIB.SCM(SCH_1):P1V2_AUX
  U15  P1V2_AUX       IV12D_U15  @SCM_LIB.SCM(SCH_1):P1V2_AUX
  T21  P1V2_AUX       IV12D_T21  @SCM_LIB.SCM(SCH_1):P1V2_AUX
  T14  P1V2_AUX       IV12D_T14  @SCM_LIB.SCM(SCH_1):P1V2_AUX
  R21  P1V2_AUX       IV12D_R21  @SCM_LIB.SCM(SCH_1):P1V2_AUX
  R14  P1V2_AUX       IV12D_R14  @SCM_LIB.SCM(SCH_1):P1V2_AUX
  P21  P1V2_AUX       IV12D_P21  @SCM_LIB.SCM(SCH_1):P1V2_AUX
  P14  P1V2_AUX       IV12D_P14  @SCM_LIB.SCM(SCH_1):P1V2_AUX
  N21  P1V2_AUX       IV12D_N21  @SCM_LIB.SCM(SCH_1):P1V2_AUX
  N14  P1V2_AUX       IV12D_N14  @SCM_LIB.SCM(SCH_1):P1V2_AUX
  M21  P1V2_AUX       IV12D_M21  @SCM_LIB.SCM(SCH_1):P1V2_AUX
  M14  P1V2_AUX       IV12D_M14  @SCM_LIB.SCM(SCH_1):P1V2_AUX
  L21  P1V2_AUX       IV12D_L21  @SCM_LIB.SCM(SCH_1):P1V2_AUX
  L14  P1V2_AUX       IV12D_L14  @SCM_LIB.SCM(SCH_1):P1V2_AUX
  K19  P1V2_AUX       IV12D_K19  @SCM_LIB.SCM(SCH_1):P1V2_AUX
  K18  P1V2_AUX       IV12D_K18  @SCM_LIB.SCM(SCH_1):P1V2_AUX
  K17  P1V2_AUX       IV12D_K17  @SCM_LIB.SCM(SCH_1):P1V2_AUX
  K16  P1V2_AUX       IV12D_K16  @SCM_LIB.SCM(SCH_1):P1V2_AUX
  T10  P1V0_STBY_RC_VCC10A  PE_VCC10A  @SCM_LIB.SCM(SCH_1):P1V0_STBY_RC_VCC10A
   F9  P1V0_STBY_PLAVDD  PLLDVDD_F9  @SCM_LIB.SCM(SCH_1):P1V0_STBY_PLAVDD
   E9  P1V0_STBY_PLAVDD  PLLDVDD_E9  @SCM_LIB.SCM(SCH_1):P1V0_STBY_PLAVDD
   F7  P1V0_STBY_PLAVDD  PLLAVDD_F7  @SCM_LIB.SCM(SCH_1):P1V0_STBY_PLAVDD
   E7  P1V0_STBY_PLAVDD  PLLAVDD_E7  @SCM_LIB.SCM(SCH_1):P1V0_STBY_PLAVDD
   J9  P1V0_STBY_PLAVDD  DPLLAVDD  @SCM_LIB.SCM(SCH_1):P1V0_STBY_PLAVDD
   T9  P1V0_STBY_PE_VCC10A  RC_VCC10A  @SCM_LIB.SCM(SCH_1):P1V0_STBY_PE_VCC10A
   T8  P1V0_STBY_DP_VCC10A  DP_VCC10A  @SCM_LIB.SCM(SCH_1):P1V0_STBY_DP_VCC10A
  R10  P1V0_AUX       IV10D_R10  @SCM_LIB.SCM(SCH_1):P1V0_AUX
   R9  P1V0_AUX       IV10D_R9  @SCM_LIB.SCM(SCH_1):P1V0_AUX
  P11  P1V0_AUX       IV10D_P11  @SCM_LIB.SCM(SCH_1):P1V0_AUX
   P8  P1V0_AUX       IV10D_P8  @SCM_LIB.SCM(SCH_1):P1V0_AUX
  N11  P1V0_AUX       IV10D_N11  @SCM_LIB.SCM(SCH_1):P1V0_AUX
   N8  P1V0_AUX       IV10D_N8  @SCM_LIB.SCM(SCH_1):P1V0_AUX
  M11  P1V0_AUX       IV10D_M11  @SCM_LIB.SCM(SCH_1):P1V0_AUX
   M8  P1V0_AUX       IV10D_M8  @SCM_LIB.SCM(SCH_1):P1V0_AUX
  L10  P1V0_AUX       IV10D_L10  @SCM_LIB.SCM(SCH_1):P1V0_AUX
   L9  P1V0_AUX       IV10D_L9  @SCM_LIB.SCM(SCH_1):P1V0_AUX
  AC21  A_BMC_DACREST  DACRSET  @SCM_LIB.SCM(SCH_1):A_BMC_DACREST
  AD17  A_BMC_ADCVREFP1  ADCVREFP1  @SCM_LIB.SCM(SCH_1):A_BMC_ADCVREFP1
  AC20  A_BMC_ADCVREFP0  ADCVREFP0  @SCM_LIB.SCM(SCH_1):A_BMC_ADCVREFP0
  AD18  A_BMC_ADCVREFN1  ADCVREFN1  @SCM_LIB.SCM(SCH_1):A_BMC_ADCVREFN1
  AB20  A_BMC_ADCVREFN0  ADCVREFN0  @SCM_LIB.SCM(SCH_1):A_BMC_ADCVREFN0
  AF18  A_BMC_ADCREXT1  ADCREXT1  @SCM_LIB.SCM(SCH_1):A_BMC_ADCREXT1
  AF20  A_BMC_ADCREXT0  ADCREXT0  @SCM_LIB.SCM(SCH_1):A_BMC_ADCREXT0
  Y21  A_BMC_ADCAV33  ADCAV33_Y21  @SCM_LIB.SCM(SCH_1):A_BMC_ADCAV33
  AA21  A_BMC_ADCAV33  ADCAV33_AA21  @SCM_LIB.SCM(SCH_1):A_BMC_ADCAV33
  AF17  ADCVREFEXT1    ADCVREFEXT1  @SCM_LIB.SCM(SCH_1):ADCVREFEXT1
  AF19  ADCVREFEXT0    ADCVREFEXT0  @SCM_LIB.SCM(SCH_1):ADCVREFEXT0

AST2600A1GP  I41  U5     [AST2600A1GP-AST2600A1-GP,SMLF,A]
  C14  V_VGAVS_R      GPIOL7||VGAVS  @SCM_LIB.SCM(SCH_1):V_VGAVS_R
  B14  V_VGAHS_R      GPIOL6||VGAHS  @SCM_LIB.SCM(SCH_1):V_VGAHS_R
  AF21  V_DACR_R        DACR  @SCM_LIB.SCM(SCH_1):V_DACR_R
  AE21  V_DACG_R        DACG  @SCM_LIB.SCM(SCH_1):V_DACG_R
  AD21  V_DACB_R        DACB  @SCM_LIB.SCM(SCH_1):V_DACB_R
   A8  V_BMC_DDC_SDA  DDCDAT  @SCM_LIB.SCM(SCH_1):V_BMC_DDC_SDA
   B8  V_BMC_DDC_SCL  DDCCLK  @SCM_LIB.SCM(SCH_1):V_BMC_DDC_SCL
   A6  USB_HOST_BMC_B_R_DP  USB2B_DP  @SCM_LIB.SCM(SCH_1):USB_HOST_BMC_B_R_DP
   B6  USB_HOST_BMC_B_R_DN  USB2B_DN  @SCM_LIB.SCM(SCH_1):USB_HOST_BMC_B_R_DN
   A4  USB_HOST_BMC_A_R_DP  USB2A_DP  @SCM_LIB.SCM(SCH_1):USB_HOST_BMC_A_R_DP
   B4  USB_HOST_BMC_A_R_DN  USB2A_DN  @SCM_LIB.SCM(SCH_1):USB_HOST_BMC_A_R_DN
  W24  SYS_BMC_PWRBTN_R_N  GPIOP1||PWM9||THRUOUT0  @SCM_LIB.SCM(SCH_1):SYS_BMC_PWRBTN_R_N
  AB16  SMB_BMC_ALERT9_R_N  ADC8||GPIU0||SALT9  @SCM_LIB.SCM(SCH_1):SMB_BMC_ALERT9_R_N
  AC17  SMB_BMC_ALERT16_N  ADC15||GPIU7||SALT16  @SCM_LIB.SCM(SCH_1):SMB_BMC_ALERT16_N
  AE16  SMB_BMC_ALERT12_N  ADC11||GPIU3||SALT12  @SCM_LIB.SCM(SCH_1):SMB_BMC_ALERT12_N
  AA17  SMB_BMC_ALERT10_R_N  ADC9||GPIU1||SALT10  @SCM_LIB.SCM(SCH_1):SMB_BMC_ALERT10_R_N
   B7  RST_SPI_FLASH_N  RSTIND#  @SCM_LIB.SCM(SCH_1):RST_SPI_FLASH_N
  B10  RST_EXTRST_N   EXTRST#  @SCM_LIB.SCM(SCH_1):RST_EXTRST_N
  E10  RST_BMC_SRST_N  SRST#  @SCM_LIB.SCM(SCH_1):RST_BMC_SRST_N
  AA24  RST_BMC_RSTBTN_OUT_R_N  GPIOP3||PWM11||THRUOUT1  @SCM_LIB.SCM(SCH_1):RST_BMC_RSTBTN_OUT_R_N
  T23  PWRGD_PCH_PWROK  GPIOR5||TACH13  @SCM_LIB.SCM(SCH_1):PWRGD_PCH_PWROK
  W26  PWRGD_CPUPWRGD_LVC1  GPIOR6||TACH14  @SCM_LIB.SCM(SCH_1):PWRGD_CPUPWRGD_LVC1
  AA18  PVCCIO_PECI_BMC  PECIVDD  @SCM_LIB.SCM(SCH_1):PVCCIO_PECI_BMC
  AB19  PGPPA_BMC_AUX_SENSOR  ADC5||GPIT5  @SCM_LIB.SCM(SCH_1):PGPPA_BMC_AUX_SENSOR
  AF16  PECI_BMC_R      PECI  @SCM_LIB.SCM(SCH_1):PECI_BMC_R
  C10  PD_SP_ENTEST   ENTEST  @SCM_LIB.SCM(SCH_1):PD_SP_ENTEST
  AB21  PD_INTRUDER_BMC_N  CHASI#  @SCM_LIB.SCM(SCH_1):PD_INTRUDER_BMC_N
  AC18  P5V_SENSOR     ADC1||GPIT1  @SCM_LIB.SCM(SCH_1):P5V_SENSOR
  AE18  P3V_BAT_SENSOR  ADC7||GPIT7  @SCM_LIB.SCM(SCH_1):P3V_BAT_SENSOR
  AE19  P3V3_SENSOR    ADC2||GPIT2  @SCM_LIB.SCM(SCH_1):P3V3_SENSOR
  J10  P3V3_BMC_USB2AV33  USB2AV33  @SCM_LIB.SCM(SCH_1):P3V3_BMC_USB2AV33
  AD19  P2V5_SENSOR    ADC3||GPIT3  @SCM_LIB.SCM(SCH_1):P2V5_SENSOR
  AC19  P1V8_SENSOR    ADC4||GPIT4  @SCM_LIB.SCM(SCH_1):P1V8_SENSOR
  K10  P1V8_BMC_USB2AV18  USB2AV18  @SCM_LIB.SCM(SCH_1):P1V8_BMC_USB2AV18
  AB18  P1V2_SENSOR    ADC6||GPIT6  @SCM_LIB.SCM(SCH_1):P1V2_SENSOR
  AB17  P1V0_SENSOR    ADC10||GPIU2||SALT11  @SCM_LIB.SCM(SCH_1):P1V0_SENSOR
  AD20  P12V_SENSOR    ADC0||GPIT0  @SCM_LIB.SCM(SCH_1):P12V_SENSOR
   A9  JTAG_SCM_TMS   TMS||MTMS1  @SCM_LIB.SCM(SCH_1):JTAG_SCM_TMS
   C9  JTAG_SCM_TDO   TDO||MTDO1  @SCM_LIB.SCM(SCH_1):JTAG_SCM_TDO
   D9  JTAG_SCM_TDI   TDI||MTDI1  @SCM_LIB.SCM(SCH_1):JTAG_SCM_TDI
   B9  JTAG_SCM_TCK   TCK||MNTCK1  @SCM_LIB.SCM(SCH_1):JTAG_SCM_TCK
  F11  JTAG_SCM_NTRST  NTRST||MNTRST1  @SCM_LIB.SCM(SCH_1):JTAG_SCM_NTRST
  D17  JTAG_1_BMC_TRST_R  GPIOI0||MNTRST2||TXD12  @SCM_LIB.SCM(SCH_1):JTAG_1_BMC_TRST_R
  D16  JTAG_1_BMC_TMS_R  GPIOI3||MTMS2||RXD13  @SCM_LIB.SCM(SCH_1):JTAG_1_BMC_TMS_R
  C16  JTAG_1_BMC_TDO_R  GPIOI4||MTDO2  @SCM_LIB.SCM(SCH_1):JTAG_1_BMC_TDO_R
  A16  JTAG_1_BMC_TDI_R  GPIOI1||MTDI2||RXD12  @SCM_LIB.SCM(SCH_1):JTAG_1_BMC_TDI_R
  E17  JTAG_1_BMC_TCK_R  GPIOI2||MTCK2||TXD13  @SCM_LIB.SCM(SCH_1):JTAG_1_BMC_TCK_R
  U24  IRQ_UV_DETECT_N  GPIOR1||TACH9  @SCM_LIB.SCM(SCH_1):IRQ_UV_DETECT_N
  V25  IRQ_OC_DETECT_N  GPIOR0||TACH8  @SCM_LIB.SCM(SCH_1):IRQ_OC_DETECT_N
  V24  IRQ_OC_DETECT_EN_N  GPIOR2||TACH10  @SCM_LIB.SCM(SCH_1):IRQ_OC_DETECT_EN_N
  U25  IRQ_CPU1_VRHOT_N  GPIOR4||TACH12  @SCM_LIB.SCM(SCH_1):IRQ_CPU1_VRHOT_N
  V26  IRQ_CPU0_VRHOT_N  GPIOR3||TACH11  @SCM_LIB.SCM(SCH_1):IRQ_CPU0_VRHOT_N
  AA23  ID_RST_BTN_BMC_R_N  GPIOP2||PWM10||THRUIN1  @SCM_LIB.SCM(SCH_1):ID_RST_BTN_BMC_R_N
  AB24  H_CPU1_MEMTRIP_LVC1_N  GPIOP6||PWM14||THRUIN3  @SCM_LIB.SCM(SCH_1):H_CPU1_MEMTRIP_LVC1_N
  AB23  H_CPU0_MEMTRIP_LVC1_N  GPIOP5||PWM13||THRUOUT2  @SCM_LIB.SCM(SCH_1):H_CPU0_MEMTRIP_LVC1_N
  AC23  FM_SPD_REMOTE_EN_R  GPIOO7||PWM7  @SCM_LIB.SCM(SCH_1):FM_SPD_REMOTE_EN_R
  AB22  FM_PWR_BTN     GPIOP0||PWM8||THRUIN0  @SCM_LIB.SCM(SCH_1):FM_PWR_BTN
  AD26  FM_PMBUS_ALERT_EN  GPIOO0||PWM0  @SCM_LIB.SCM(SCH_1):FM_PMBUS_ALERT_EN
  AD24  NC             GPIOO3||PWM3  NC
  AD23  FM_PCIE_M2_SSD0_PRSNT_N  GPIOO2||PWM2  @SCM_LIB.SCM(SCH_1):FM_PCIE_M2_SSD0_PRSNT_N
  AD16  FM_PCHHOT_R_N  ADC14||GPIU6||SALT15  @SCM_LIB.SCM(SCH_1):FM_PCHHOT_R_N
  AC16  FM_MASTER_MB_N  ADC12||GPIU4||SALT13  @SCM_LIB.SCM(SCH_1):FM_MASTER_MB_N
   D7  FM_BMC_SSPRST_N  SSPRST#  @SCM_LIB.SCM(SCH_1):FM_BMC_SSPRST_N
  AA16  FM_BMC_EN_DET_R  ADC13||GPIU5||SALT14  @SCM_LIB.SCM(SCH_1):FM_BMC_EN_DET_R
  U26  FM_BIOS_POST_CMPLT_BMC_N  GPIOR7||TACH15  @SCM_LIB.SCM(SCH_1):FM_BIOS_POST_CMPLT_BMC_N
  AD25  FM_ADR_TRIGGER_N  GPIOO4||PWM4  @SCM_LIB.SCM(SCH_1):FM_ADR_TRIGGER_N
  AC24  FM_ADR_COMPLETE  GPIOO6||PWM6  @SCM_LIB.SCM(SCH_1):FM_ADR_COMPLETE
  W23  BMC_PWR_LED    GPIOP4||PWM12||THRUIN2  @SCM_LIB.SCM(SCH_1):BMC_PWR_LED
  Y23  BMC_HEARTBEAT_N  GPIOP7||HBLED#||PWM15||THRUOUT3  @SCM_LIB.SCM(SCH_1):BMC_HEARTBEAT_N
  AC22  BMC_CPLD_GPIO_24_R1  GPIOO5||PWM5  @SCM_LIB.SCM(SCH_1):BMC_CPLD_GPIO_24_R1
  AD22  BMC_CPLD_GPIO_23_R1  GPIOO1||PWM1  @SCM_LIB.SCM(SCH_1):BMC_CPLD_GPIO_23_R1
  AA26  BMC_CPLD_GPIO_22_R1  GPIOQ7||TACH7  @SCM_LIB.SCM(SCH_1):BMC_CPLD_GPIO_22_R1
  Y25  BMC_CPLD_GPIO_21_R1  GPIOQ6||TACH6  @SCM_LIB.SCM(SCH_1):BMC_CPLD_GPIO_21_R1
  AC26  BMC_CPLD_GPIO_20_R1  GPIOQ5||TACH5  @SCM_LIB.SCM(SCH_1):BMC_CPLD_GPIO_20_R1
  Y26  BMC_CPLD_GPIO_19_R1  GPIOQ4||TACH4  @SCM_LIB.SCM(SCH_1):BMC_CPLD_GPIO_19_R1
  AB26  BMC_CPLD_GPIO_18_R1  GPIOQ3||TACH3  @SCM_LIB.SCM(SCH_1):BMC_CPLD_GPIO_18_R1
  Y24  BMC_CPLD_GPIO_17_R1  GPIOQ2||TACH2  @SCM_LIB.SCM(SCH_1):BMC_CPLD_GPIO_17_R1
  AB25  BMC_CPLD_GPIO_16_R1  GPIOQ1||TACH1  @SCM_LIB.SCM(SCH_1):BMC_CPLD_GPIO_16_R1
  AA25  BMC_CPLD_GPIO_15_R1  GPIOQ0||TACH0  @SCM_LIB.SCM(SCH_1):BMC_CPLD_GPIO_15_R1
  D10  BMC_CLK_25M    CLKIN  @SCM_LIB.SCM(SCH_1):BMC_CLK_25M

AST2600A1GP  I35  U5     [AST2600A1GP-AST2600A1-GP,SMLF,A]
  AF24  I3C4_SDA_R     I3C4SDA||FSI2DATA  @SCM_LIB.SCM(SCH_1):I3C4_SDA_R
  AE25  I3C4_SCL_R     I3C4SCL||FSI2CLK  @SCM_LIB.SCM(SCH_1):I3C4_SCL_R
  AE26  I3C3_SDA_R     I3C3SDA||FSI1DATA  @SCM_LIB.SCM(SCH_1):I3C3_SDA_R
  AF25  I3C3_SCL_R     I3C3SCL||FSI1CLK  @SCM_LIB.SCM(SCH_1):I3C3_SCL_R
  AE22  I3C2_SDA_R     I3C2SDA  @SCM_LIB.SCM(SCH_1):I3C2_SDA_R
  AF22  I3C2_SCL_R     I3C2SCL  @SCM_LIB.SCM(SCH_1):I3C2_SCL_R
  AE24  I3C1_SDA_R     I3C1SDA  @SCM_LIB.SCM(SCH_1):I3C1_SDA_R
  AF23  I3C1_SCL_R     I3C1SCL  @SCM_LIB.SCM(SCH_1):I3C1_SCL_R
   F5  GND            RGMII2TXD3||GPIO18C1  @SCM_LIB.SCM(SCH_1):GND
   E4  GND            RGMII2TXD2||GPIO18C0  @SCM_LIB.SCM(SCH_1):GND
   D3  GND            RGMII2TXD1||RMII2TXD1||GPIO18B7  @SCM_LIB.SCM(SCH_1):GND
   C1  GND            RGMII2TXD0||RMII2TXD0||GPIO18B6  @SCM_LIB.SCM(SCH_1):GND
   C2  GND            RGMII2TXCTL||RMII2TXEN||GPIO18B5  @SCM_LIB.SCM(SCH_1):GND
   D4  GND            RGMII2TXCK||RMII2RCLKO||GPIO18B4  @SCM_LIB.SCM(SCH_1):GND
   E1  GND            RGMII2RXD3||RMII2RXER||GPIO18C7  @SCM_LIB.SCM(SCH_1):GND
   E2  GND            RGMII2RXD2||RMII2CRSDV||GPIO18C6  @SCM_LIB.SCM(SCH_1):GND
   F4  GND            RGMII2RXD1||RMII2RXD1||GPIO18C5  @SCM_LIB.SCM(SCH_1):GND
   D1  GND            RGMII2RXD0||RMII2RXD0||GPIO18C4  @SCM_LIB.SCM(SCH_1):GND
   E3  GND            RGMII2RXCTL||GPIO18C3  @SCM_LIB.SCM(SCH_1):GND
   D2  GND            RGMII2RXCK||RMII2RCLKI||GPIO18C2  @SCM_LIB.SCM(SCH_1):GND
   E6  GND            RGMII1TXD3||GPIO18A5  @SCM_LIB.SCM(SCH_1):GND
   C5  GND            RGMII1TXD2||GPIO18A4  @SCM_LIB.SCM(SCH_1):GND
   A3  GND            RGMII1TXD1||RMII1TXD1||GPIO18A3  @SCM_LIB.SCM(SCH_1):GND
   D5  GND            RGMII1TXD0||RMII1TXD0||GPIO18A2  @SCM_LIB.SCM(SCH_1):GND
   D6  GND            RGMII1TXCTL||RMII1TXEN||GPIO18A1  @SCM_LIB.SCM(SCH_1):GND
   C6  GND            RGMII1TXCK||RMII1RCLKO||GPIO18A0  @SCM_LIB.SCM(SCH_1):GND
   E5  GND            RGMII1RXD3||RMII1RXER||GPIO18B3  @SCM_LIB.SCM(SCH_1):GND
   C4  GND            RGMII1RXD2||RMII1CRSDV||GPIO18B2  @SCM_LIB.SCM(SCH_1):GND
   B1  GND            RGMII1RXD1||RMII1RXD1||GPIO18B1  @SCM_LIB.SCM(SCH_1):GND
   B2  GND            RGMII1RXD0||RMII1RXD0||GPIO18B0  @SCM_LIB.SCM(SCH_1):GND
   A2  GND            RGMII1RXCTL||GPIO18A7  @SCM_LIB.SCM(SCH_1):GND
   B3  GND            RGMII1RXCK||RMII1RCLKI||GPIO18A6  @SCM_LIB.SCM(SCH_1):GND
  AB6  BMC_EMMC_WP_N  GPIO18D7||EMMCWP#  @SCM_LIB.SCM(SCH_1):BMC_EMMC_WP_N
   Y4  BMC_EMMC_DT7   GPIO18E3||EMMCDAT7||FWSPI18MISO||VBMISO  @SCM_LIB.SCM(SCH_1):BMC_EMMC_DT7
   Y3  BMC_EMMC_DT6   GPIO18E2||EMMCDAT6||FWSPI18MOSI||VBMOSI  @SCM_LIB.SCM(SCH_1):BMC_EMMC_DT6
   Y2  BMC_EMMC_DT5   GPIO18E1||EMMCDAT5||FWSPI18CK||VBCK  @SCM_LIB.SCM(SCH_1):BMC_EMMC_DT5
   Y1  BMC_EMMC_DT4   GPIO18E0||EMMCDAT4||FWSPI18CS#||VBCS#  @SCM_LIB.SCM(SCH_1):BMC_EMMC_DT4
  AB5  BMC_EMMC_DT3   GPIO18D5||EMMCDAT3  @SCM_LIB.SCM(SCH_1):BMC_EMMC_DT3
   Y5  BMC_EMMC_DT2   GPIO18D4||EMMCDAT2  @SCM_LIB.SCM(SCH_1):BMC_EMMC_DT2
  AA5  BMC_EMMC_DT1   GPIO18D3||EMMCDAT1  @SCM_LIB.SCM(SCH_1):BMC_EMMC_DT1
  AC4  BMC_EMMC_DT0   GPIO18D2||EMMCDAT0  @SCM_LIB.SCM(SCH_1):BMC_EMMC_DT0
  AA4  BMC_EMMC_CMD   GPIO18D1||EMMCCMD  @SCM_LIB.SCM(SCH_1):BMC_EMMC_CMD
  AB4  BMC_EMMC_CLK   GPIO18D0||EMMCCLK  @SCM_LIB.SCM(SCH_1):BMC_EMMC_CLK
  AC5  BMC_EMMC_CD_N  GPIO18D6||EMMCCD#  @SCM_LIB.SCM(SCH_1):BMC_EMMC_CD_N

AST2600A1GP  I45  U5     [AST2600A1GP-AST2600A1-GP,SMLF,A]
  K23  VOL_SEN_ALERT_R  GPIOB1||SALT2||LHAD1  @SCM_LIB.SCM(SCH_1):VOL_SEN_ALERT_R
   C8  UART_BMC_5_TXD   TXD5  @SCM_LIB.SCM(SCH_1):UART_BMC_5_TXD
   D8  UART_BMC_5_RXD   RXD5  @SCM_LIB.SCM(SCH_1):UART_BMC_5_RXD
  C13  UART_BMC_1_TXD  GPIOM6||TXD1  @SCM_LIB.SCM(SCH_1):UART_BMC_1_TXD
  D13  UART_BMC_1_RXD  GPIOM7||RXD1  @SCM_LIB.SCM(SCH_1):UART_BMC_1_RXD
  AA9  NC             GPIOX1||SPI2CS1#  NC
  A10  NC             RGMIICK  NC
  AC13  SPI_BMC_TPM_CS2_R1_N  FWSPICS2#  @SCM_LIB.SCM(SCH_1):SPI_BMC_TPM_CS2_R1_N
  AC14  SPI_BMC_MOSI_IO0_R  FWSPIMOSI  @SCM_LIB.SCM(SCH_1):SPI_BMC_MOSI_IO0_R
  AB13  SPI_BMC_MISO_IO1_R  FWSPIMISO  @SCM_LIB.SCM(SCH_1):SPI_BMC_MISO_IO1_R
  AF12  SPI_BMC_IO3_R  GPIOY5||FWSPIDQ3  @SCM_LIB.SCM(SCH_1):SPI_BMC_IO3_R
  AE12  SPI_BMC_IO2_R  GPIOY4||FWSPIDQ2  @SCM_LIB.SCM(SCH_1):SPI_BMC_IO2_R
  AC11  SPI_BMC_CPLD_R_MOSI  GPIOZ4||SPI1MOSI  @SCM_LIB.SCM(SCH_1):SPI_BMC_CPLD_R_MOSI
  AF13  SPI_BMC_CLK_R  FWSPICK  @SCM_LIB.SCM(SCH_1):SPI_BMC_CLK_R
  AA13  SPI_BMC_BOOT_CS1_R1_N  FWSPICS1#  @SCM_LIB.SCM(SCH_1):SPI_BMC_BOOT_CS1_R1_N
  AB14  SPI_BMC_BOOT_CS0_R1_N  FWSPICS0#  @SCM_LIB.SCM(SCH_1):SPI_BMC_BOOT_CS0_R1_N
  AB9  SPI_BMC_BIOS_ROM_MOSI  GPIOX4||SPI2MOSI  @SCM_LIB.SCM(SCH_1):SPI_BMC_BIOS_ROM_MOSI
  AD9  SPI_BMC_BIOS_ROM_MISO  GPIOX5||SPI2MISO  @SCM_LIB.SCM(SCH_1):SPI_BMC_BIOS_ROM_MISO
  AB10  SPI_BMC_BIOS_ROM_IO3  GPIOX7||SPI2DQ3||RXD12  @SCM_LIB.SCM(SCH_1):SPI_BMC_BIOS_ROM_IO3
  AF9  SPI_BMC_BIOS_ROM_IO2  GPIOX6||SPI2DQ2||TXD12  @SCM_LIB.SCM(SCH_1):SPI_BMC_BIOS_ROM_IO2
  AF8  SPI_BMC_BIOS_ROM_CLK  GPIOX3||SPI2CK  @SCM_LIB.SCM(SCH_1):SPI_BMC_BIOS_ROM_CLK
  AE8  SPI_BMC_BIOS_CS0_R1_N  GPIOX0||SPI2CS0#  @SCM_LIB.SCM(SCH_1):SPI_BMC_BIOS_CS0_R1_N
  J25  SMB_BMC_ALERT4_R_N  GPIOB3||SALT4||LHAD3  @SCM_LIB.SCM(SCH_1):SMB_BMC_ALERT4_R_N
  H26  SMB_BMC_ALERT3_R_N  GPIOB2||SALT3||LHAD2  @SCM_LIB.SCM(SCH_1):SMB_BMC_ALERT3_R_N
  AD12  RST_WDTRST_PLD_R1_N  GPIOY1||SALT6||WDTRST2#  @SCM_LIB.SCM(SCH_1):RST_WDTRST_PLD_R1_N
  AF14  RST_RSMRST_R_N  GPIOV1||SIOS5#  @SCM_LIB.SCM(SCH_1):RST_RSMRST_R_N
  AF11  RST_BMC_SELF_HW_R1  GPIOY0||SALT5||WDTRST1#  @SCM_LIB.SCM(SCH_1):RST_BMC_SELF_HW_R1
  E23  RMII_TXEN_R    RGMII4TXCTL||RMII4TXEN||NDCD3||GPIOD5  @SCM_LIB.SCM(SCH_1):RMII_TXEN_R
  E25  RMII_TXD1_R    RGMII4TXD1||RMII4TXD1||NRI3||GPIOD7  @SCM_LIB.SCM(SCH_1):RMII_TXD1_R
  E24  RMII_TXD0_R    RGMII4TXD0||RMII4TXD0||NDSR3||GPIOD6  @SCM_LIB.SCM(SCH_1):RMII_TXD0_R
  B24  RMII_RXER      RGMII4RXD3||RMII4RXER||NRTS4||GPIOE7  @SCM_LIB.SCM(SCH_1):RMII_RXER
  B26  RMII_RXD1      RGMII4RXD1||RMII4RXD1||NRI4||GPIOE5  @SCM_LIB.SCM(SCH_1):RMII_RXD1
  C24  RMII_RXD0      RGMII4RXD0||RMII4RXD0||NDSR4||GPIOE4  @SCM_LIB.SCM(SCH_1):RMII_RXD0
  C25  RMII_OCP_RCLKI  RGMII4RXCK||RMII4RCLKI||NCTS4||GPIOE2  @SCM_LIB.SCM(SCH_1):RMII_OCP_RCLKI
  B25  RMII_CSRDV     RGMII4RXD2||RMII4CRSDV||NDTR4||GPIOE6  @SCM_LIB.SCM(SCH_1):RMII_CSRDV
  J22  RGMII_BMC_TX_R_CTRL  RGMII3TXCTL||RMII3TXEN||GPIOC1  @SCM_LIB.SCM(SCH_1):RGMII_BMC_TX_R_CTRL
  H24  RGMII_BMC_TX_R_CLK  RGMII3TXCK||RMII3RCLKO||GPIOC0  @SCM_LIB.SCM(SCH_1):RGMII_BMC_TX_R_CLK
  F22  RGMII_BMC_TXD_R_<3>  RGMII3TXD3||GPIOC5  @SCM_LIB.SCM(SCH_1):RGMII_BMC_TXD_R_<3>
  G22  RGMII_BMC_TXD_R_<2>  RGMII3TXD2||GPIOC4  @SCM_LIB.SCM(SCH_1):RGMII_BMC_TXD_R_<2>
  H23  RGMII_BMC_TXD_R_<1>  RGMII3TXD1||RMII3TXD1||GPIOC3  @SCM_LIB.SCM(SCH_1):RGMII_BMC_TXD_R_<1>
  H22  RGMII_BMC_TXD_R_<0>  RGMII3TXD0||RMII3TXD0||GPIOC2  @SCM_LIB.SCM(SCH_1):RGMII_BMC_TXD_R_<0>
  G24  RGMII_BMC_RX_CTRL  RGMII3RXCTL||GPIOC7  @SCM_LIB.SCM(SCH_1):RGMII_BMC_RX_CTRL
  G23  RGMII_BMC_RX_CLK_R  RGMII3RXCK||RMII3RCLKI||GPIOC6  @SCM_LIB.SCM(SCH_1):RGMII_BMC_RX_CLK_R
  E26  RGMII_BMC_RXD_<3>  RGMII3RXD3||RMII3RXER||GPIOD3  @SCM_LIB.SCM(SCH_1):RGMII_BMC_RXD_<3>
  F25  RGMII_BMC_RXD_<2>  RGMII3RXD2||RMII3CRSDV||GPIOD2  @SCM_LIB.SCM(SCH_1):RGMII_BMC_RXD_<2>
  F26  RGMII_BMC_RXD_<1>  RGMII3RXD1||RMII3RXD1||GPIOD1  @SCM_LIB.SCM(SCH_1):RGMII_BMC_RXD_<1>
  F23  RGMII_BMC_RXD_<0>  RGMII3RXD0||RMII3RXD0||GPIOD0  @SCM_LIB.SCM(SCH_1):RGMII_BMC_RXD_<0>
  B12  PWRGD_SYS_PWROK_BMC  GPIOM4||NDTR1  @SCM_LIB.SCM(SCH_1):PWRGD_SYS_PWROK_BMC
  A12  PWRGD_PSU_AC_PWROK_BMC  GPIOM2||NDSR1  @SCM_LIB.SCM(SCH_1):PWRGD_PSU_AC_PWROK_BMC
  AE10  PU_SPI1WP_N    GPIOZ2||SPI1WP#  @SCM_LIB.SCM(SCH_1):PU_SPI1WP_N
  AD10  PU_SPI1ABR     GPIOZ1||SPI1ABR  @SCM_LIB.SCM(SCH_1):PU_SPI1ABR
  AB12  PU_FWSPIWP_N   GPIOY7||FWSPIWP#  @SCM_LIB.SCM(SCH_1):PU_FWSPIWP_N
  AC12  PU_BMC_FWSPIABR_N  GPIOY6||FWSPIABR  @SCM_LIB.SCM(SCH_1):PU_BMC_FWSPIABR_N
  E16  PD_BIOS_MUX_EN_R_N  GPIOI5||SIOPBO#  @SCM_LIB.SCM(SCH_1):PD_BIOS_MUX_EN_R_N
  M26  LED_POSTCODE_7_N  GPION7||RXD2  @SCM_LIB.SCM(SCH_1):LED_POSTCODE_7_N
  N26  LED_POSTCODE_6_N  GPION6||TXD2  @SCM_LIB.SCM(SCH_1):LED_POSTCODE_6_N
  M23  LED_POSTCODE_5_N  GPION5||NRTS2  @SCM_LIB.SCM(SCH_1):LED_POSTCODE_5_N
  P26  LED_POSTCODE_4_N  GPION4||NDTR2  @SCM_LIB.SCM(SCH_1):LED_POSTCODE_4_N
  N24  LED_POSTCODE_3_N  GPION3||NRI2  @SCM_LIB.SCM(SCH_1):LED_POSTCODE_3_N
  N25  LED_POSTCODE_2_N  GPION2||NDSR2  @SCM_LIB.SCM(SCH_1):LED_POSTCODE_2_N
  N23  LED_POSTCODE_1_N  GPION1||NDCD2  @SCM_LIB.SCM(SCH_1):LED_POSTCODE_1_N
  P25  LED_POSTCODE_0_N  GPION0||NCTS2  @SCM_LIB.SCM(SCH_1):LED_POSTCODE_0_N
  AF15  IRQ_TPM_SPI_N  GPIOV7||LPCSMI#  @SCM_LIB.SCM(SCH_1):IRQ_TPM_SPI_N
  AC9  IRQ_SMI_ACTIVE_BMC_N  GPIOX2||SPI2CS2#  @SCM_LIB.SCM(SCH_1):IRQ_SMI_ACTIVE_BMC_N
  A15  IRQ_PCH_SCI_WHEA_R_N  GPIOI7||SIOSCI#  @SCM_LIB.SCM(SCH_1):IRQ_PCH_SCI_WHEA_R_N
  R23  IRQ_BMC_PCH_NMI_N  GPIOS0||MDC1  @SCM_LIB.SCM(SCH_1):IRQ_BMC_PCH_NMI_N
  J24  IRQ_BMC_CPU_NMI  GPIOB7||RXD4||LHRST#  @SCM_LIB.SCM(SCH_1):IRQ_BMC_CPU_NMI
  P24  H_CPU1_PROCHOT_LVC1_N  GPIOS5||RXD10  @SCM_LIB.SCM(SCH_1):H_CPU1_PROCHOT_LVC1_N
  D14  H_CPU0_PROCHOT_LVC1_N  GPIOM0||NCTS1  @SCM_LIB.SCM(SCH_1):H_CPU0_PROCHOT_LVC1_N
  C26  GND            RGMII4RXCTL||NDCD4||GPIOE3  @SCM_LIB.SCM(SCH_1):GND
  B13  FM_VIRTUAL_RESEAT_BMC  GPIOM1||NDCD1  @SCM_LIB.SCM(SCH_1):FM_VIRTUAL_RESEAT_BMC
  B16  FM_THROTTLE_N  GPIOI6||SIOPBI#  @SCM_LIB.SCM(SCH_1):FM_THROTTLE_N
  AB15  FM_SLPS3_GF_N  GPIOV0||SIOS3#  @SCM_LIB.SCM(SCH_1):FM_SLPS3_GF_N
  T24  FM_RISER2_JTAG_SEL_R_N  GPIOS7||RXD11  @SCM_LIB.SCM(SCH_1):FM_RISER2_JTAG_SEL_R_N
  P23  FM_RISER1_JTAG_SEL_R_N  GPIOS6||TXD11  @SCM_LIB.SCM(SCH_1):FM_RISER1_JTAG_SEL_R_N
  E14  FM_PECI_SEL_R_N  GPIOM3||NRI1  @SCM_LIB.SCM(SCH_1):FM_PECI_SEL_R_N
  J26  FM_ME_BT_DONE  GPIOB0||SALT1||LHAD0  @SCM_LIB.SCM(SCH_1):FM_ME_BT_DONE
  F15  FM_JTAG_TCK_MUX_BMC_SEL_R1  GPIOL5||RXD3  @SCM_LIB.SCM(SCH_1):FM_JTAG_TCK_MUX_BMC_SEL_R1
  G26  FM_ID_LED_N    GPIOB5||MDIO2||LHFRAME#  @SCM_LIB.SCM(SCH_1):FM_ID_LED_N
  H25  FM_ESPI_PLD_R1_EN  GPIOB6||TXD4||LHSIRQ#  @SCM_LIB.SCM(SCH_1):FM_ESPI_PLD_R1_EN
  C15  FM_DBP_CPU_PREQ_GF_N  GPIOL4||TXD3  @SCM_LIB.SCM(SCH_1):FM_DBP_CPU_PREQ_GF_N
  C12  FM_DBP_BMC_PRDY_R_N  GPIOM5||NRTS1  @SCM_LIB.SCM(SCH_1):FM_DBP_BMC_PRDY_R_N
  AD15  FM_BMC_SUSACK_N  GPIOV6||LPCPME#  @SCM_LIB.SCM(SCH_1):FM_BMC_SUSACK_N
  AE14  FM_BMC_READY_R_PLD_N  GPIOV5||LPCPD#||LHPD#  @SCM_LIB.SCM(SCH_1):FM_BMC_READY_R_PLD_N
  AC15  FM_BMC_ONCTL_R_N  GPIOV3||SIOONCTRL#  @SCM_LIB.SCM(SCH_1):FM_BMC_ONCTL_R_N
  J23  FM_BMC_MUX_CS_SPI_SEL_0  GPIOB4||MDC2||LHCLK  @SCM_LIB.SCM(SCH_1):FM_BMC_MUX_CS_SPI_SEL_0
  R26  FM_BMC_DEBUG_SW_N  GPIOS4||TXD10  @SCM_LIB.SCM(SCH_1):FM_BMC_DEBUG_SW_N
  AE11  FM_BIOS_DEBUG_EN_R_N  GPIOY2||SALT7||WDTRST3#  @SCM_LIB.SCM(SCH_1):FM_BIOS_DEBUG_EN_R_N
  AD11  BMC_CPLD_GPIO_9_R1  GPIOZ6||SPI1DQ2||TXD13  @SCM_LIB.SCM(SCH_1):BMC_CPLD_GPIO_9_R1
  AA11  BMC_CPLD_GPIO_8_R1  GPIOZ5||SPI1MISO  @SCM_LIB.SCM(SCH_1):BMC_CPLD_GPIO_8_R1
  AB11  BMC_CPLD_GPIO_7_R1  GPIOZ3||SPI1CK  @SCM_LIB.SCM(SCH_1):BMC_CPLD_GPIO_7_R1
  AD14  BMC_CPLD_GPIO_6_R1  GPIOV2||SIOPWREQ#  @SCM_LIB.SCM(SCH_1):BMC_CPLD_GPIO_6_R1
  AC10  BMC_CPLD_GPIO_5_R1  GPIOZ0||SPI1CS1#  @SCM_LIB.SCM(SCH_1):BMC_CPLD_GPIO_5_R1
  AD13  BMC_CPLD_GPIO_4_R1  SPI1CS0#  @SCM_LIB.SCM(SCH_1):BMC_CPLD_GPIO_4_R1
  AA12  BMC_CPLD_GPIO_25_R1  GPIOY3||SALT8||WDTRST4#  @SCM_LIB.SCM(SCH_1):BMC_CPLD_GPIO_25_R1
  T25  BMC_CPLD_GPIO_14_R1  GPIOS1||MDIO1  @SCM_LIB.SCM(SCH_1):BMC_CPLD_GPIO_14_R1
  D24  BMC_CPLD_GPIO_13_R1  RGMII4TXD3||NRTS3||GPIOE1  @SCM_LIB.SCM(SCH_1):BMC_CPLD_GPIO_13_R1
  D26  BMC_CPLD_GPIO_12_R1  RGMII4TXD2||NDTR3||GPIOE0  @SCM_LIB.SCM(SCH_1):BMC_CPLD_GPIO_12_R1
  F24  BMC_CPLD_GPIO_11_R1  RGMII4TXCK||RMII4RCLKO||NCTS3||GPIOD4  @SCM_LIB.SCM(SCH_1):BMC_CPLD_GPIO_11_R1
  AF10  BMC_CPLD_GPIO_10_R1  GPIOZ7||SPI1DQ3||RXD13  @SCM_LIB.SCM(SCH_1):BMC_CPLD_GPIO_10_R1
  AE15  BATTERY_DETECT  GPIOV4||SIOPWRGD  @SCM_LIB.SCM(SCH_1):BATTERY_DETECT

AST2600A1GP  I45  U5     [AST2600A1GP-AST2600A1-GP,SMLF,A]
  C21  UART_2_BMC_R_TXD  GPIOG2||TXD7||SD2DAT0||SALT11  @SCM_LIB.SCM(SCH_1):UART_2_BMC_R_TXD
  A22  UART_2_BMC_R_RXD  GPIOG3||RXD7||SD2DAT1||SALT12  @SCM_LIB.SCM(SCH_1):UART_2_BMC_R_RXD
  E21  UART_1_SCM_R_TXD  GPIOG0||TXD6||SD2CLK||SALT9  @SCM_LIB.SCM(SCH_1):UART_1_SCM_R_TXD
  B22  UART_1_SCM_R_RXD  GPIOG1||RXD6||SD2CMD||SALT10  @SCM_LIB.SCM(SCH_1):UART_1_SCM_R_RXD
  AF2  NC             RCTXP  NC
  AF3  NC             RCTXN  NC
  AD2  NC             RCRXP  NC
  AD3  NC             RCRXN  NC
  AE1  NC             RCREFCLKP  NC
  AE2  NC             RCREFCLKN  NC
  A14  SMB_BMC_MM9_R_SDA  GPIOL1||SDA9  @SCM_LIB.SCM(SCH_1):SMB_BMC_MM9_R_SDA
  D15  SMB_BMC_MM9_R_SCL  GPIOL0||SCL9  @SCM_LIB.SCM(SCH_1):SMB_BMC_MM9_R_SCL
  E12  SMB_BMC_MM8_R_SDA  GPIOK7||SDA8  @SCM_LIB.SCM(SCH_1):SMB_BMC_MM8_R_SDA
  F13  SMB_BMC_MM8_R_SCL  GPIOK6||SCL8  @SCM_LIB.SCM(SCH_1):SMB_BMC_MM8_R_SCL
  E11  SMB_BMC_MM7_R_SDA  GPIOK5||SDA7  @SCM_LIB.SCM(SCH_1):SMB_BMC_MM7_R_SDA
  D11  SMB_BMC_MM7_R_SCL  GPIOK4||SCL7  @SCM_LIB.SCM(SCH_1):SMB_BMC_MM7_R_SCL
  E13  SMB_BMC_MM6_R_SDA  GPIOK3||SDA6  @SCM_LIB.SCM(SCH_1):SMB_BMC_MM6_R_SDA
  D12  SMB_BMC_MM6_R_SCL  GPIOK2||SCL6  @SCM_LIB.SCM(SCH_1):SMB_BMC_MM6_R_SCL
  C11  SMB_BMC_MM5_R_SDA  GPIOK1||SDA5  @SCM_LIB.SCM(SCH_1):SMB_BMC_MM5_R_SDA
  A11  SMB_BMC_MM5_R_SCL  GPIOK0||SCL5  @SCM_LIB.SCM(SCH_1):SMB_BMC_MM5_R_SCL
  D19  SMB_BMC_MM4_R_SDA  GPIOJ7||SDA4||HVI3C6SDA  @SCM_LIB.SCM(SCH_1):SMB_BMC_MM4_R_SDA
  C20  SMB_BMC_MM4_R_SCL  GPIOJ6||SCL4||HVI3C6SCL  @SCM_LIB.SCM(SCH_1):SMB_BMC_MM4_R_SCL
  A19  SMB_BMC_MM3_R_SDA  GPIOJ5||SDA3||HVI3C5SDA  @SCM_LIB.SCM(SCH_1):SMB_BMC_MM3_R_SDA
  C19  SMB_BMC_MM3_R_SCL  GPIOJ4||SCL3||HVI3C5SCL  @SCM_LIB.SCM(SCH_1):SMB_BMC_MM3_R_SCL
  D20  SMB_BMC_MM2_R_SDA  GPIOJ3||SDA2||HVI3C4SDA  @SCM_LIB.SCM(SCH_1):SMB_BMC_MM2_R_SDA
  E19  SMB_BMC_MM2_R_SCL  GPIOJ2||SCL2||HVI3C4SCL  @SCM_LIB.SCM(SCH_1):SMB_BMC_MM2_R_SCL
  A20  SMB_BMC_MM1_R_SDA  GPIOJ1||SDA1||HVI3C3SDA  @SCM_LIB.SCM(SCH_1):SMB_BMC_MM1_R_SDA
  B20  SMB_BMC_MM1_R_SCL  GPIOJ0||SCL1||HVI3C3SCL  @SCM_LIB.SCM(SCH_1):SMB_BMC_MM1_R_SCL
  E18  SMB_BMC_MM16_R_SDA  GPIOH7||SGPS1I1||SDA16  @SCM_LIB.SCM(SCH_1):SMB_BMC_MM16_R_SDA
  C17  SMB_BMC_MM16_R_SCL  GPIOH6||SGPS1I0||SCL16  @SCM_LIB.SCM(SCH_1):SMB_BMC_MM16_R_SCL
  B17  SMB_BMC_MM15_R_SDA  GPIOH5||SGPS1LD||SDA15  @SCM_LIB.SCM(SCH_1):SMB_BMC_MM15_R_SDA
  D18  SMB_BMC_MM15_R_SCL  GPIOH4||SGPS1CK||SCL15  @SCM_LIB.SCM(SCH_1):SMB_BMC_MM15_R_SCL
  K25  SMB_BMC_MM14_R_SDA  GPIOA7||MAC4LINK||SDA14||SGPS2I1||SGPM2I  @SCM_LIB.SCM(SCH_1):SMB_BMC_MM14_R_SDA
  L23  SMB_BMC_MM14_R_SCL  GPIOA6||MAC3LINK||SCL14||SGPS2I0||SGPM2O  @SCM_LIB.SCM(SCH_1):SMB_BMC_MM14_R_SCL
  L24  SMB_BMC_MM13_R_SDA  GPIOA5||MAC2LINK||SDA13||SGPS2LD||SPGM2LD  @SCM_LIB.SCM(SCH_1):SMB_BMC_MM13_R_SDA
  K26  SMB_BMC_MM13_R_SCL  GPIOA4||MAC1LINK||SCL13||SGPS2CK||SGPM2CK  @SCM_LIB.SCM(SCH_1):SMB_BMC_MM13_R_SCL
  K24  SMB_BMC_MM12_R_SDA  GPIOA3||MDIO4||SDA12  @SCM_LIB.SCM(SCH_1):SMB_BMC_MM12_R_SDA
  L26  SMB_BMC_MM12_R_SCL  GPIOA2||MDC4||SCL12  @SCM_LIB.SCM(SCH_1):SMB_BMC_MM12_R_SCL
  A13  SMB_BMC_MM10_R_SDA  GPIOL3||SDA10  @SCM_LIB.SCM(SCH_1):SMB_BMC_MM10_R_SDA
  E15  SMB_BMC_MM10_R_SCL  GPIOL2||SCL10  @SCM_LIB.SCM(SCH_1):SMB_BMC_MM10_R_SCL
  D21  SMB_BMC_ALERT15_N  GPIOG6||TXD9||SD2CD#||SALT15  @SCM_LIB.SCM(SCH_1):SMB_BMC_ALERT15_N
  B18  SGPIO_BMC_M1_LD  GPIOH1||SGPM1LD  @SCM_LIB.SCM(SCH_1):SGPIO_BMC_M1_LD
  C18  SGPIO_BMC_M1_DO  GPIOH2||SGPM1O  @SCM_LIB.SCM(SCH_1):SGPIO_BMC_M1_DO
  A17  SGPIO_BMC_M1_DI  GPIOH3||SGPM1I  @SCM_LIB.SCM(SCH_1):SGPIO_BMC_M1_DI
  A18  SGPIO_BMC_M1_CLK  GPIOH0||SGPM1CK  @SCM_LIB.SCM(SCH_1):SGPIO_BMC_M1_CLK
  C23  RST_SGPIO_RESET_BMC_N  GPIOF3||SD1DAT1||PWM11  @SCM_LIB.SCM(SCH_1):RST_SGPIO_RESET_BMC_N
  D22  RST_PLTRST_R_N  GPIOF0||SD1CLK||PWM8  @SCM_LIB.SCM(SCH_1):RST_PLTRST_R_N
   A7  RST_PLTRST_N   PERST#  @SCM_LIB.SCM(SCH_1):RST_PLTRST_N
  A25  RST_PCA9548_SENSOR_R_N  GPIOF5||SD1DAT3||PWM13  @SCM_LIB.SCM(SCH_1):RST_PCA9548_SENSOR_R_N
  AD8  RST_ESPI_LPC_BMC_N  GPIOW7||LPCRST#||ESPIRST#  @SCM_LIB.SCM(SCH_1):RST_ESPI_LPC_BMC_N
  M25  RGMII_BMC_MDIO  GPIOA1||MDIO3||SDA11  @SCM_LIB.SCM(SCH_1):RGMII_BMC_MDIO
  M24  RGMII_BMC_MDC  GPIOA0||MDC3||SCL11  @SCM_LIB.SCM(SCH_1):RGMII_BMC_MDC
  AF5  PCIE_BMC_TX_DP  PERXP  @SCM_LIB.SCM(SCH_1):PCIE_BMC_TX_DP
  AF6  PCIE_BMC_TX_DN  PERXN  @SCM_LIB.SCM(SCH_1):PCIE_BMC_TX_DN
  AE4  P2E_BMC_RX_DP  PETXP  @SCM_LIB.SCM(SCH_1):P2E_BMC_RX_DP
  AE5  P2E_BMC_RX_DN  PETXN  @SCM_LIB.SCM(SCH_1):P2E_BMC_RX_DN
   U5  P0V6_DDR_VREF_AUX  MVREF_U5  @SCM_LIB.SCM(SCH_1):P0V6_DDR_VREF_AUX
   T5  P0V6_DDR_VREF_AUX  MVREF_T5  @SCM_LIB.SCM(SCH_1):P0V6_DDR_VREF_AUX
   L3  M_BMC_DDR4_RST_N  MRESET#  @SCM_LIB.SCM(SCH_1):M_BMC_DDR4_RST_N
   G5  M_BMC_DDR4_MWE_N   MWE#  @SCM_LIB.SCM(SCH_1):M_BMC_DDR4_MWE_N
   J5  M_BMC_DDR4_MRAS_N  MRAS#  @SCM_LIB.SCM(SCH_1):M_BMC_DDR4_MRAS_N
   J1  M_BMC_DDR4_MODT   MODT  @SCM_LIB.SCM(SCH_1):M_BMC_DDR4_MODT
   R5  M_BMC_DDR4_MDM1   MDM1  @SCM_LIB.SCM(SCH_1):M_BMC_DDR4_MDM1
   N3  M_BMC_DDR4_MDM0   MDM0  @SCM_LIB.SCM(SCH_1):M_BMC_DDR4_MDM0
   H2  M_BMC_DDR4_MCS_N   MCS#  @SCM_LIB.SCM(SCH_1):M_BMC_DDR4_MCS_N
   K2  M_BMC_DDR4_MCLK_DP    MCK  @SCM_LIB.SCM(SCH_1):M_BMC_DDR4_MCLK_DP
   K1  M_BMC_DDR4_MCLK_DN   MCK#  @SCM_LIB.SCM(SCH_1):M_BMC_DDR4_MCLK_DN
   L5  M_BMC_DDR4_MCKE   MCKE  @SCM_LIB.SCM(SCH_1):M_BMC_DDR4_MCKE
   J4  M_BMC_DDR4_MCAS_N  MCAS#  @SCM_LIB.SCM(SCH_1):M_BMC_DDR4_MCAS_N
   M3  M_BMC_DDR4_MBG1  MA15||MBG1  @SCM_LIB.SCM(SCH_1):M_BMC_DDR4_MBG1
   G3  M_BMC_DDR4_MBG0  MBA2||MBG0  @SCM_LIB.SCM(SCH_1):M_BMC_DDR4_MBG0
   H5  M_BMC_DDR4_MBA1   MBA1  @SCM_LIB.SCM(SCH_1):M_BMC_DDR4_MBA1
   G4  M_BMC_DDR4_MBA0   MBA0  @SCM_LIB.SCM(SCH_1):M_BMC_DDR4_MBA0
   H1  M_BMC_DDR4_MACT_N  MA14||MACT#  @SCM_LIB.SCM(SCH_1):M_BMC_DDR4_MACT_N
   N1  M_BMC_DDR4_MA<9>    MA9  @SCM_LIB.SCM(SCH_1):M_BMC_DDR4_MA<9>
   M1  M_BMC_DDR4_MA<8>    MA8  @SCM_LIB.SCM(SCH_1):M_BMC_DDR4_MA<8>
   M2  M_BMC_DDR4_MA<7>    MA7  @SCM_LIB.SCM(SCH_1):M_BMC_DDR4_MA<7>
   M5  M_BMC_DDR4_MA<6>    MA6  @SCM_LIB.SCM(SCH_1):M_BMC_DDR4_MA<6>
   L1  M_BMC_DDR4_MA<5>    MA5  @SCM_LIB.SCM(SCH_1):M_BMC_DDR4_MA<5>
   J3  M_BMC_DDR4_MA<4>    MA4  @SCM_LIB.SCM(SCH_1):M_BMC_DDR4_MA<4>
   H3  M_BMC_DDR4_MA<3>    MA3  @SCM_LIB.SCM(SCH_1):M_BMC_DDR4_MA<3>
   F1  M_BMC_DDR4_MA<2>    MA2  @SCM_LIB.SCM(SCH_1):M_BMC_DDR4_MA<2>
   K5  M_BMC_DDR4_MA<1>    MA1  @SCM_LIB.SCM(SCH_1):M_BMC_DDR4_MA<1>
   K3  M_BMC_DDR4_MA<13>   MA13  @SCM_LIB.SCM(SCH_1):M_BMC_DDR4_MA<13>
   L4  M_BMC_DDR4_MA<12>   MA12  @SCM_LIB.SCM(SCH_1):M_BMC_DDR4_MA<12>
   G1  M_BMC_DDR4_MA<11>   MA11  @SCM_LIB.SCM(SCH_1):M_BMC_DDR4_MA<11>
   F2  M_BMC_DDR4_MA<10>   MA10  @SCM_LIB.SCM(SCH_1):M_BMC_DDR4_MA<10>
   F3  M_BMC_DDR4_MA<0>    MA0  @SCM_LIB.SCM(SCH_1):M_BMC_DDR4_MA<0>
   V2  M_BMC_DDR4_DQS1_P  MDQS1  @SCM_LIB.SCM(SCH_1):M_BMC_DDR4_DQS1_P
   V1  M_BMC_DDR4_DQS1_N  MDQS1#  @SCM_LIB.SCM(SCH_1):M_BMC_DDR4_DQS1_N
   T2  M_BMC_DDR4_DQS0_P  MDQS0  @SCM_LIB.SCM(SCH_1):M_BMC_DDR4_DQS0_P
   T1  M_BMC_DDR4_DQS0_N  MDQS0#  @SCM_LIB.SCM(SCH_1):M_BMC_DDR4_DQS0_N
   V3  M_BMC_DDR4_DQ<9>   MDQ9  @SCM_LIB.SCM(SCH_1):M_BMC_DDR4_DQ<9>
   W2  M_BMC_DDR4_DQ<8>   MDQ8  @SCM_LIB.SCM(SCH_1):M_BMC_DDR4_DQ<8>
   P3  M_BMC_DDR4_DQ<7>   MDQ7  @SCM_LIB.SCM(SCH_1):M_BMC_DDR4_DQ<7>
   P2  M_BMC_DDR4_DQ<6>   MDQ6  @SCM_LIB.SCM(SCH_1):M_BMC_DDR4_DQ<6>
   P1  M_BMC_DDR4_DQ<5>   MDQ5  @SCM_LIB.SCM(SCH_1):M_BMC_DDR4_DQ<5>
   R1  M_BMC_DDR4_DQ<4>   MDQ4  @SCM_LIB.SCM(SCH_1):M_BMC_DDR4_DQ<4>
   R3  M_BMC_DDR4_DQ<3>   MDQ3  @SCM_LIB.SCM(SCH_1):M_BMC_DDR4_DQ<3>
   U1  M_BMC_DDR4_DQ<2>   MDQ2  @SCM_LIB.SCM(SCH_1):M_BMC_DDR4_DQ<2>
   R4  M_BMC_DDR4_DQ<1>   MDQ1  @SCM_LIB.SCM(SCH_1):M_BMC_DDR4_DQ<1>
   U3  M_BMC_DDR4_DQ<15>  MDQ15  @SCM_LIB.SCM(SCH_1):M_BMC_DDR4_DQ<15>
   V4  M_BMC_DDR4_DQ<14>  MDQ14  @SCM_LIB.SCM(SCH_1):M_BMC_DDR4_DQ<14>
   U4  M_BMC_DDR4_DQ<13>  MDQ13  @SCM_LIB.SCM(SCH_1):M_BMC_DDR4_DQ<13>
   W4  M_BMC_DDR4_DQ<12>  MDQ12  @SCM_LIB.SCM(SCH_1):M_BMC_DDR4_DQ<12>
   W3  M_BMC_DDR4_DQ<11>  MDQ11  @SCM_LIB.SCM(SCH_1):M_BMC_DDR4_DQ<11>
   W1  M_BMC_DDR4_DQ<10>  MDQ10  @SCM_LIB.SCM(SCH_1):M_BMC_DDR4_DQ<10>
   T3  M_BMC_DDR4_DQ<0>   MDQ0  @SCM_LIB.SCM(SCH_1):M_BMC_DDR4_DQ<0>
   N4  M_BMC_DDR4_ALERT_N  MALERT#  @SCM_LIB.SCM(SCH_1):M_BMC_DDR4_ALERT_N
  A24  IRQ_SGPIO_BMC_N  GPIOF6||SD1CD#||PWM14  @SCM_LIB.SCM(SCH_1):IRQ_SGPIO_BMC_N
  AD7  IRQ_ESPI_LPC_SERIRQ_ALERT0_N  GPIOW6||LSIRQ#||ESPIALT#  @SCM_LIB.SCM(SCH_1):IRQ_ESPI_LPC_SERIRQ_ALERT0_N
   P5  IBMC_MIOZ       MIOZ  @SCM_LIB.SCM(SCH_1):IBMC_MIOZ
  T26  FM_THERMTRIP_DLY_LVC1_R_N  GPIOS2||PEWAKE#  @SCM_LIB.SCM(SCH_1):FM_THERMTRIP_DLY_LVC1_R_N
  A21  FM_PLT_BMC_THERMTRIP_N_R  GPIOG4||TXD8||SD2DAT2||SALT13  @SCM_LIB.SCM(SCH_1):FM_PLT_BMC_THERMTRIP_N_R
  R24  FM_INTRUDER_HDR_PCH_R_N  GPIOS3||OSCCLK  @SCM_LIB.SCM(SCH_1):FM_INTRUDER_HDR_PCH_R_N
  E22  FM_CPU_RMCA_CATERR_LVT3_R_N  GPIOF1||SD1CMD||PWM9  @SCM_LIB.SCM(SCH_1):FM_CPU_RMCA_CATERR_LVT3_R_N
  B21  FM_BMC_DBP_PRESENT_R_N  GPIOG7||RXD9||SD2WP#||SALT16  @SCM_LIB.SCM(SCH_1):FM_BMC_DBP_PRESENT_R_N
  D23  FM_BMC_CPU_FBRK_OUT_N  GPIOF2||SD1DAT0||PWM10  @SCM_LIB.SCM(SCH_1):FM_BMC_CPU_FBRK_OUT_N
  AC7  ESPI_LPC_D3_IO3  GPIOW3||LAD3||ESPID3  @SCM_LIB.SCM(SCH_1):ESPI_LPC_D3_IO3
  AC8  ESPI_LPC_D2_IO2  GPIOW2||LAD2||ESPID2  @SCM_LIB.SCM(SCH_1):ESPI_LPC_D2_IO2
  AB8  ESPI_LPC_D1_IO1  GPIOW1||LAD1||ESPID1  @SCM_LIB.SCM(SCH_1):ESPI_LPC_D1_IO1
  AB7  ESPI_LPC_D0_IO0  GPIOW0||LAD0||ESPID0  @SCM_LIB.SCM(SCH_1):ESPI_LPC_D0_IO0
  AF7  ESPI_HOST_LPC_BMC_LFRAME_N  GPIOW5||LFRAME#||ESPICS#  @SCM_LIB.SCM(SCH_1):ESPI_HOST_LPC_BMC_LFRAME_N
  AE7  ESPI_HOST_LPC_BMC_CLK  GPIOW4||LCLK||ESPICK  @SCM_LIB.SCM(SCH_1):ESPI_HOST_LPC_BMC_CLK
   C7  DP_BMC_HPD_3V3  DPHPD  @SCM_LIB.SCM(SCH_1):DP_BMC_HPD_3V3
  AB2  DP_BMC_C_TX1_P  DPTXP1  @SCM_LIB.SCM(SCH_1):DP_BMC_C_TX1_P
  AA2  DP_BMC_C_TX1_N  DPTXN1  @SCM_LIB.SCM(SCH_1):DP_BMC_C_TX1_N
  AC1  DP_BMC_C_TX0_P  DPTXP0  @SCM_LIB.SCM(SCH_1):DP_BMC_C_TX0_P
  AB1  DP_BMC_C_TX0_N  DPTXN0  @SCM_LIB.SCM(SCH_1):DP_BMC_C_TX0_N
  AC3  DP_BMC_AUX_P   DPAUXP  @SCM_LIB.SCM(SCH_1):DP_BMC_AUX_P
  AB3  DP_BMC_AUX_N   DPAUXN  @SCM_LIB.SCM(SCH_1):DP_BMC_AUX_N
  AD5  CLK_BMC_GF_DP  PEREFCLKP  @SCM_LIB.SCM(SCH_1):CLK_BMC_GF_DP
  AD6  CLK_BMC_GF_DN  PEREFCLKN  @SCM_LIB.SCM(SCH_1):CLK_BMC_GF_DN
  E20  BMC_CPLD_GPIO_3_R1  GPIOG5||RXD8||SD2DAT3||SALT14  @SCM_LIB.SCM(SCH_1):BMC_CPLD_GPIO_3_R1
  A23  BMC_CPLD_GPIO_2_R1  GPIOF7||SD1WP#||PWM15  @SCM_LIB.SCM(SCH_1):BMC_CPLD_GPIO_2_R1
  C22  BMC_CPLD_GPIO_1_R1  GPIOF4||SD1DAT2||PWM12  @SCM_LIB.SCM(SCH_1):BMC_CPLD_GPIO_1_R1

SN74LVC2G07DCKR  I64  U6     [SN74LVC2G07DCKR_SMLF-SN74LVC2GA]
    3  RST_SRST_PLD_BMC_R_N     2A  @SCM_LIB.SCM(SCH_1):RST_SRST_PLD_BMC_R_N
    4  RST_SRST_PLD_BMC_BUF_N     2Y  @SCM_LIB.SCM(SCH_1):RST_SRST_PLD_BMC_BUF_N
    6  PWRGD_P1V0_AUX_DELAY_BUF     1Y  @SCM_LIB.SCM(SCH_1):PWRGD_P1V0_AUX_DELAY_BUF
    1  PWRGD_P1V0_AUX_DELAY     1A  @SCM_LIB.SCM(SCH_1):PWRGD_P1V0_AUX_DELAY
    5  P3V3_AUX         VCC  @SCM_LIB.SCM(SCH_1):P3V3_AUX
    2  GND              GND  @SCM_LIB.SCM(SCH_1):GND

BCM54612EB1KMLG  I126  U7     [BCM54612EB1KMLG-BCM54612EB1KMLA]
    7  XTAL_PHY_XO    XTALO  @SCM_LIB.SCM(SCH_1):XTAL_PHY_XO
    8  XTAL_PHY_XI    XTALI  @SCM_LIB.SCM(SCH_1):XTAL_PHY_XI
   42  NC              LED4  NC
   46  RST_RSTB_N     RESET#  @SCM_LIB.SCM(SCH_1):RST_RSTB_N
   35  RGMII_BMC_TX_CTRL  TX_EN  @SCM_LIB.SCM(SCH_1):RGMII_BMC_TX_CTRL
   40  RGMII_BMC_TX_CLK  GTXCLK  @SCM_LIB.SCM(SCH_1):RGMII_BMC_TX_CLK
   36  RGMII_BMC_TXD_<3>   TXD3  @SCM_LIB.SCM(SCH_1):RGMII_BMC_TXD_<3>
   37  RGMII_BMC_TXD_<2>   TXD2  @SCM_LIB.SCM(SCH_1):RGMII_BMC_TXD_<2>
   38  RGMII_BMC_TXD_<1>   TXD1  @SCM_LIB.SCM(SCH_1):RGMII_BMC_TXD_<1>
   39  RGMII_BMC_TXD_<0>   TXD0  @SCM_LIB.SCM(SCH_1):RGMII_BMC_TXD_<0>
   27  RGMII_BMC_R_RXD_<3>   RXD3  @SCM_LIB.SCM(SCH_1):RGMII_BMC_R_RXD_<3>
   28  RGMII_BMC_R_RXD_<2>   RXD2  @SCM_LIB.SCM(SCH_1):RGMII_BMC_R_RXD_<2>
   31  RGMII_BMC_R_RXD_<1>   RXD1  @SCM_LIB.SCM(SCH_1):RGMII_BMC_R_RXD_<1>
   32  RGMII_BMC_R_RXD_<0>   RXD0  @SCM_LIB.SCM(SCH_1):RGMII_BMC_R_RXD_<0>
   26  RGMII_BMC_RX_R_CTRL  RX_DV  @SCM_LIB.SCM(SCH_1):RGMII_BMC_RX_R_CTRL
   33  RGMII_BMC_RX_CLK    RXC  @SCM_LIB.SCM(SCH_1):RGMII_BMC_RX_CLK
   47  RGMII_BMC_MDIO_R   MDIO  @SCM_LIB.SCM(SCH_1):RGMII_BMC_MDIO_R
   48  RGMII_BMC_MDC_R    MDC  @SCM_LIB.SCM(SCH_1):RGMII_BMC_MDC_R
   24  PHY_TRD_3_P    TRD3+  @SCM_LIB.SCM(SCH_1):PHY_TRD_3_P
   23  PHY_TRD_3_N    TRD3-  @SCM_LIB.SCM(SCH_1):PHY_TRD_3_N
   20  PHY_TRD_2_P    TRD2+  @SCM_LIB.SCM(SCH_1):PHY_TRD_2_P
   21  PHY_TRD_2_N    TRD2-  @SCM_LIB.SCM(SCH_1):PHY_TRD_2_N
   18  PHY_TRD_1_P    TRD1+  @SCM_LIB.SCM(SCH_1):PHY_TRD_1_P
   17  PHY_TRD_1_N    TRD1-  @SCM_LIB.SCM(SCH_1):PHY_TRD_1_N
   14  PHY_TRD_0_P    TRD0+  @SCM_LIB.SCM(SCH_1):PHY_TRD_0_P
   15  PHY_TRD_0_N    TRD0-  @SCM_LIB.SCM(SCH_1):PHY_TRD_0_N
   10  PHY_RDAC        RDAC  @SCM_LIB.SCM(SCH_1):PHY_RDAC
   43  PHY_LED3        LED3  @SCM_LIB.SCM(SCH_1):PHY_LED3
   44  PHY_LED2        LED2  @SCM_LIB.SCM(SCH_1):PHY_LED2
   45  PHY_LED1        LED1  @SCM_LIB.SCM(SCH_1):PHY_LED1
   41  PHYA0          PHYA0  @SCM_LIB.SCM(SCH_1):PHYA0
    9  P3V3_XTALVDD   XTALVDD  @SCM_LIB.SCM(SCH_1):P3V3_XTALVDD
   12  P3V3_BIASVDD   BIASVDD  @SCM_LIB.SCM(SCH_1):P3V3_BIASVDD
   22  P3V3_AVDD      AVDD_2  @SCM_LIB.SCM(SCH_1):P3V3_AVDD
   16  P3V3_AVDD      AVDD_1  @SCM_LIB.SCM(SCH_1):P3V3_AVDD
    4  P3V3_AUX       REGSUPPLY  @SCM_LIB.SCM(SCH_1):P3V3_AUX
   34  P3V3_AUX       OVDD_RGMII_2  @SCM_LIB.SCM(SCH_1):P3V3_AUX
   29  P3V3_AUX       OVDD_RGMII_1  @SCM_LIB.SCM(SCH_1):P3V3_AUX
    1  P3V3_AUX        OVDD  @SCM_LIB.SCM(SCH_1):P3V3_AUX
   11  P1V2_PHY0_PLLVDD  PLLVDD  @SCM_LIB.SCM(SCH_1):P1V2_PHY0_PLLVDD
   25  P1V2_PHY0_AVDDL  AVDDL_3  @SCM_LIB.SCM(SCH_1):P1V2_PHY0_AVDDL
   19  P1V2_PHY0_AVDDL  AVDDL_2  @SCM_LIB.SCM(SCH_1):P1V2_PHY0_AVDDL
   13  P1V2_PHY0_AVDDL  AVDDL_1  @SCM_LIB.SCM(SCH_1):P1V2_PHY0_AVDDL
    3  P1V2_PHY0      REGOUT  @SCM_LIB.SCM(SCH_1):P1V2_PHY0
   30  P1V2_PHY0      DVDD_2  @SCM_LIB.SCM(SCH_1):P1V2_PHY0
    2  P1V2_PHY0      DVDD_1  @SCM_LIB.SCM(SCH_1):P1V2_PHY0
   TH  GND               TH  @SCM_LIB.SCM(SCH_1):GND
    5  GND            TEST3  @SCM_LIB.SCM(SCH_1):GND
    6  GND            TEST2  @SCM_LIB.SCM(SCH_1):GND

TPD4E001DBVR  I93  U8     [TPD4E001DBVR-TPD4E001DBVR,SMLFB]
    5  PU_RJ45_ESD      VCC  @SCM_LIB.SCM(SCH_1):PU_RJ45_ESD
    4  PHY_TRD_1_P      IO3  @SCM_LIB.SCM(SCH_1):PHY_TRD_1_P
    3  PHY_TRD_1_N      IO2  @SCM_LIB.SCM(SCH_1):PHY_TRD_1_N
    6  PHY_TRD_0_P      IO4  @SCM_LIB.SCM(SCH_1):PHY_TRD_0_P
    1  PHY_TRD_0_N      IO1  @SCM_LIB.SCM(SCH_1):PHY_TRD_0_N
    2  GND              GND  @SCM_LIB.SCM(SCH_1):GND

TPD4E001DBVR  I94  U9     [TPD4E001DBVR-TPD4E001DBVR,SMLFB]
    5  PU_RJ45_ESD      VCC  @SCM_LIB.SCM(SCH_1):PU_RJ45_ESD
    4  PHY_TRD_3_P      IO3  @SCM_LIB.SCM(SCH_1):PHY_TRD_3_P
    3  PHY_TRD_3_N      IO2  @SCM_LIB.SCM(SCH_1):PHY_TRD_3_N
    6  PHY_TRD_2_P      IO4  @SCM_LIB.SCM(SCH_1):PHY_TRD_2_P
    1  PHY_TRD_2_N      IO1  @SCM_LIB.SCM(SCH_1):PHY_TRD_2_N
    2  GND              GND  @SCM_LIB.SCM(SCH_1):GND

TPS2553DBVR1  I51  U10    [TPS2553DBVR1-TPS2553DBVR-1,SMLA]
    4  USB_OC0_REAR_N  FAULT_N  @SCM_LIB.SCM(SCH_1):USB_OC0_REAR_N
    5  USB_OC0_ILIM    ILIM  @SCM_LIB.SCM(SCH_1):USB_OC0_ILIM
    3  USB_OC0_EN        EN  @SCM_LIB.SCM(SCH_1):USB_OC0_EN
    6  P5V_USB_REAR     OUT  @SCM_LIB.SCM(SCH_1):P5V_USB_REAR
    1  P5V_AUX           IN  @SCM_LIB.SCM(SCH_1):P5V_AUX
    2  GND              GND  @SCM_LIB.SCM(SCH_1):GND

BAT54C  I185  U11    [BAT54C-BAT54C,SMLF,IC,BCBAT54CA]
    2  UART_BMC_5_TXD_R      A  @SCM_LIB.SCM(SCH_1):UART_BMC_5_TXD_R
    1  FM_BMC_ONCTL_R_N      B  @SCM_LIB.SCM(SCH_1):FM_BMC_ONCTL_R_N
    3  FM_BMC_DISABLE      C  @SCM_LIB.SCM(SCH_1):FM_BMC_DISABLE

MOSFET_N  I14  U12    [MOSFET_N_SMLF-BSS138K,BSS138K,A]
    G  RST_BMC_SELF_HW_D_C   GATE  @SCM_LIB.SCM(SCH_1):RST_BMC_SELF_HW_D_C
    D  RST_BMC_EXTRST_R1_N  DRAIN  @SCM_LIB.SCM(SCH_1):RST_BMC_EXTRST_R1_N
    S  GND            SOURCE  @SCM_LIB.SCM(SCH_1):GND

SN74LVC1G07DCKR  I15  U13    [SN74LVC1G07DCKR-SN74LVC1G07DCKA]
    2  RST_BMC_SRST_BUF_R1_N      A  @SCM_LIB.SCM(SCH_1):RST_BMC_SRST_BUF_R1_N
    4  RST_BMC_EXTRST_R1_N      Y  @SCM_LIB.SCM(SCH_1):RST_BMC_EXTRST_R1_N
    5  P3V3_AUX         VCC  @SCM_LIB.SCM(SCH_1):P3V3_AUX
    1  NC               NC1  NC
    3  GND              GND  @SCM_LIB.SCM(SCH_1):GND

AP22811AW57  I79  U14    [AP22811AW57-AP22811AW5-7,SMLF,A]
    3  NC              FLG#  NC
    4  PWRGD_P1V8_AUX_R2     EN  @SCM_LIB.SCM(SCH_1):PWRGD_P1V8_AUX_R2
    1  P3V3_RGM         OUT  @SCM_LIB.SCM(SCH_1):P3V3_RGM
    5  P3V3_AUX          IN  @SCM_LIB.SCM(SCH_1):P3V3_AUX
    2  GND              GND  @SCM_LIB.SCM(SCH_1):GND

TPS22965DSGR  I2   U15    [TPS22965DSGR-TPS22965DSGR,SMLFA]
    3  PU_LOADSW_EN      ON  @SCM_LIB.SCM(SCH_1):PU_LOADSW_EN
    8  P3V3_DP        VOUT2  @SCM_LIB.SCM(SCH_1):P3V3_DP
    7  P3V3_DP        VOUT1  @SCM_LIB.SCM(SCH_1):P3V3_DP
    2  P3V3_AUX        VIN2  @SCM_LIB.SCM(SCH_1):P3V3_AUX
    1  P3V3_AUX        VIN1  @SCM_LIB.SCM(SCH_1):P3V3_AUX
    4  LOADSW_VBIAS   VBIAS  @SCM_LIB.SCM(SCH_1):LOADSW_VBIAS
    6  LOADSW_CT         CT  @SCM_LIB.SCM(SCH_1):LOADSW_CT
   TH  GND               TH  @SCM_LIB.SCM(SCH_1):GND
    5  GND              GND  @SCM_LIB.SCM(SCH_1):GND

TPD4E001DBVR  I51  U16    [TPD4E001DBVR-TPD4E001DBVR,SMLFA]
    5  P3V3_DP_L        VCC  @SCM_LIB.SCM(SCH_1):P3V3_DP_L
    2  GND              GND  @SCM_LIB.SCM(SCH_1):GND
    1  DP_BMC_TX1_P     IO1  @SCM_LIB.SCM(SCH_1):DP_BMC_TX1_P
    3  DP_BMC_TX1_N     IO2  @SCM_LIB.SCM(SCH_1):DP_BMC_TX1_N
    6  DP_BMC_TX0_P     IO4  @SCM_LIB.SCM(SCH_1):DP_BMC_TX0_P
    4  DP_BMC_TX0_N     IO3  @SCM_LIB.SCM(SCH_1):DP_BMC_TX0_N

FT234XDR  I98  U17    [FT234XDR-FT234XD-R,SMLF,IC,AL0A]
   12  USB2_PL2303_EXT_DP  USBDP  @SCM_LIB.SCM(SCH_1):USB2_PL2303_EXT_DP
    1  USB2_PL2303_EXT_DN  USBDM  @SCM_LIB.SCM(SCH_1):USB2_PL2303_EXT_DN
    8  NC              RTS#  NC
   11  NC              CTS#  NC
    6  NC             CBUS0  NC
   10  SPA_SOUT_SW_MNUSB    RXD  @SCM_LIB.SCM(SCH_1):SPA_SOUT_SW_MNUSB
    7  SPA_SIN_SW_MNUSB_R    TXD  @SCM_LIB.SCM(SCH_1):SPA_SIN_SW_MNUSB_R
    4  P5V_BUS          VCC  @SCM_LIB.SCM(SCH_1):P5V_BUS
    9  P3V3_PL2303    VCCIO  @SCM_LIB.SCM(SCH_1):P3V3_PL2303
    2  P3V3_PL2303    RESET#  @SCM_LIB.SCM(SCH_1):P3V3_PL2303
    3  P3V3_PL2303    3V3OUT  @SCM_LIB.SCM(SCH_1):P3V3_PL2303
   13  GND             GND2  @SCM_LIB.SCM(SCH_1):GND
    5  GND             GND1  @SCM_LIB.SCM(SCH_1):GND

TPD2EUSB30DRTR  I84  U18    [TPD2EUSB30DRTR_SMLF-TPD2EUSB30A]
    1  USB2_EXT_R_DP    D_P  @SCM_LIB.SCM(SCH_1):USB2_EXT_R_DP
    2  USB2_EXT_R_DN    D_N  @SCM_LIB.SCM(SCH_1):USB2_EXT_R_DN
    3  GND              GND  @SCM_LIB.SCM(SCH_1):GND

M24128BWDW6TP  I15  U19    [M24128BWDW6TP-M24128-BWDW6TP,SA]
    5  SMB_BMC_MM15_R2_SDA    SDA  @SCM_LIB.SCM(SCH_1):SMB_BMC_MM15_R2_SDA
    6  SMB_BMC_MM15_R2_SCL    SCL  @SCM_LIB.SCM(SCH_1):SMB_BMC_MM15_R2_SCL
    7  PD_FRU_WC_N      WC#  @SCM_LIB.SCM(SCH_1):PD_FRU_WC_N
    8  P3V3_AUX         VCC  @SCM_LIB.SCM(SCH_1):P3V3_AUX
    4  GND              VSS  @SCM_LIB.SCM(SCH_1):GND
    3  FRU_E2            E2  @SCM_LIB.SCM(SCH_1):FRU_E2
    2  FRU_E1            E1  @SCM_LIB.SCM(SCH_1):FRU_E1
    1  FRU_E0            E0  @SCM_LIB.SCM(SCH_1):FRU_E0

MTFC8GAKAJCN1MWT  I1   U20    [MTFC8GAKAJCN1MWT-MTFC8GAKAJCN-A]
  P10  NC             RFU_P10  NC
   K7  NC             RFU_K7  NC
   K6  NC             RFU_K6  NC
  K10  NC             RFU_K10  NC
  G10  NC             RFU_G10  NC
  F10  NC             RFU_F10  NC
   E9  NC             RFU_E9  NC
   E8  NC             RFU_E8  NC
   E5  NC             RFU_E5  NC
  E10  NC             RFU_E10  NC
   A7  NC             RFU_A7  NC
   P9  NC             NC_P9  NC
   P8  NC             NC_P8  NC
   P7  NC             NC_P7  NC
   P2  NC             NC_P2  NC
  P14  NC             NC_P14  NC
  P13  NC             NC_P13  NC
  P12  NC             NC_P12  NC
  P11  NC             NC_P11  NC
   P1  NC             NC_P1  NC
   N9  NC             NC_N9  NC
   N8  NC             NC_N8  NC
   N7  NC             NC_N7  NC
   N6  NC             NC_N6  NC
   N3  NC             NC_N3  NC
  N14  NC             NC_N14  NC
  N13  NC             NC_N13  NC
  N12  NC             NC_N12  NC
  N11  NC             NC_N11  NC
  N10  NC             NC_N10  NC
   N1  NC             NC_N1  NC
   M9  NC             NC_M9  NC
   M8  NC             NC_M8  NC
   M7  NC             NC_M7  NC
   M3  NC             NC_M3  NC
   M2  NC             NC_M2  NC
  M14  NC             NC_M14  NC
  M13  NC             NC_M13  NC
  M12  NC             NC_M12  NC
  M11  NC             NC_M11  NC
  M10  NC             NC_M10  NC
   M1  NC             NC_M1  NC
   L3  NC             NC_L3  NC
   L2  NC             NC_L2  NC
  L14  NC             NC_L14  NC
  L13  NC             NC_L13  NC
  L12  NC             NC_L12  NC
   L1  NC             NC_L1  NC
   K3  NC             NC_K3  NC
   K2  NC             NC_K2  NC
  K14  NC             NC_K14  NC
  K13  NC             NC_K13  NC
  K12  NC             NC_K12  NC
   K1  NC             NC_K1  NC
   J3  NC             NC_J3  NC
   J2  NC             NC_J2  NC
  J14  NC             NC_J14  NC
  J13  NC             NC_J13  NC
  J12  NC             NC_J12  NC
   J1  NC             NC_J1  NC
   H3  NC             NC_H3  NC
   H2  NC             NC_H2  NC
  H14  NC             NC_H14  NC
  H13  NC             NC_H13  NC
  H12  NC             NC_H12  NC
   H1  NC             NC_H1  NC
   G3  NC             NC_G3  NC
   G2  NC             NC_G2  NC
  G14  NC             NC_G14  NC
  G13  NC             NC_G13  NC
  G12  NC             NC_G12  NC
   G1  NC             NC_G1  NC
   F3  NC             NC_F3  NC
   F2  NC             NC_F2  NC
  F14  NC             NC_F14  NC
  F13  NC             NC_F13  NC
  F12  NC             NC_F12  NC
   F1  NC             NC_F1  NC
   E3  NC             NC_E3  NC
   E2  NC             NC_E2  NC
  E14  NC             NC_E14  NC
  E13  NC             NC_E13  NC
  E12  NC             NC_E12  NC
   E1  NC             NC_E1  NC
   D4  NC             NC_D4  NC
   D3  NC             NC_D3  NC
   D2  NC             NC_D2  NC
  D14  NC             NC_D14  NC
  D13  NC             NC_D13  NC
  D12  NC             NC_D12  NC
   D1  NC             NC_D1  NC
   C9  NC             NC_C9  NC
   C8  NC             NC_C8  NC
   C7  NC             NC_C7  NC
   C5  NC             NC_C5  NC
   C3  NC             NC_C3  NC
  C14  NC             NC_C14  NC
  C13  NC             NC_C13  NC
  C12  NC             NC_C12  NC
  C11  NC             NC_C11  NC
  C10  NC             NC_C10  NC
   C1  NC             NC_C1  NC
   B9  NC             NC_B9  NC
   B8  NC             NC_B8  NC
   B7  NC             NC_B7  NC
  B14  NC             NC_B14  NC
  B13  NC             NC_B13  NC
  B12  NC             NC_B12  NC
  B11  NC             NC_B11  NC
  B10  NC             NC_B10  NC
   B1  NC             NC_B1  NC
   A9  NC             NC_A9  NC
   A8  NC             NC_A8  NC
   A2  NC             NC_A2  NC
  A14  NC             NC_A14  NC
  A13  NC             NC_A13  NC
  A12  NC             NC_A12  NC
  A11  NC             NC_A11  NC
  A10  NC             NC_A10  NC
   A1  NC             NC_A1  NC

MTFC8GAKAJCN1MWT  I38  U20    [MTFC8GAKAJCN1MWT-MTFC8GAKAJCN-A]
   C2  VDDI_U2_EMMC   VDDIM  @SCM_LIB.SCM(SCH_1):VDDI_U2_EMMC
   H5  NC                DS  NC
   K9  P3V3_AUX       VCC_K9  @SCM_LIB.SCM(SCH_1):P3V3_AUX
  J10  P3V3_AUX       VCC_J10  @SCM_LIB.SCM(SCH_1):P3V3_AUX
   F5  P3V3_AUX       VCC_F5  @SCM_LIB.SCM(SCH_1):P3V3_AUX
   E6  P3V3_AUX       VCC_E6  @SCM_LIB.SCM(SCH_1):P3V3_AUX
   P5  P1V8_AUX       VCCQ_P5  @SCM_LIB.SCM(SCH_1):P1V8_AUX
   P3  P1V8_AUX       VCCQ_P3  @SCM_LIB.SCM(SCH_1):P1V8_AUX
   N4  P1V8_AUX       VCCQ_N4  @SCM_LIB.SCM(SCH_1):P1V8_AUX
   M4  P1V8_AUX       VCCQ_M4  @SCM_LIB.SCM(SCH_1):P1V8_AUX
   C6  P1V8_AUX       VCCQ_C6  @SCM_LIB.SCM(SCH_1):P1V8_AUX
   P6  GND            VSSQ_P6  @SCM_LIB.SCM(SCH_1):GND
   P4  GND            VSSQ_P4  @SCM_LIB.SCM(SCH_1):GND
   N5  GND            VSSQ_N5  @SCM_LIB.SCM(SCH_1):GND
   N2  GND            VSSQ_N2  @SCM_LIB.SCM(SCH_1):GND
   C4  GND            VSSQ_C4  @SCM_LIB.SCM(SCH_1):GND
   K8  GND            VSS_K8  @SCM_LIB.SCM(SCH_1):GND
   J5  GND            VSS_J5  @SCM_LIB.SCM(SCH_1):GND
  H10  GND            VSS_H10  @SCM_LIB.SCM(SCH_1):GND
   G5  GND            VSS_G5  @SCM_LIB.SCM(SCH_1):GND
   E7  GND            VSS_E7  @SCM_LIB.SCM(SCH_1):GND
   A6  GND            VSS_A6  @SCM_LIB.SCM(SCH_1):GND
   B6  EMMC_DT7_R      DAT7  @SCM_LIB.SCM(SCH_1):EMMC_DT7_R
   B5  EMMC_DT6_R      DAT6  @SCM_LIB.SCM(SCH_1):EMMC_DT6_R
   B4  EMMC_DT5_R      DAT5  @SCM_LIB.SCM(SCH_1):EMMC_DT5_R
   B3  EMMC_DT4_R      DAT4  @SCM_LIB.SCM(SCH_1):EMMC_DT4_R
   B2  EMMC_DT3_R      DAT3  @SCM_LIB.SCM(SCH_1):EMMC_DT3_R
   A5  EMMC_DT2_R      DAT2  @SCM_LIB.SCM(SCH_1):EMMC_DT2_R
   A4  EMMC_DT1_R      DAT1  @SCM_LIB.SCM(SCH_1):EMMC_DT1_R
   A3  EMMC_DT0_R      DAT0  @SCM_LIB.SCM(SCH_1):EMMC_DT0_R
   M5  EMMC_CMD_R       CMD  @SCM_LIB.SCM(SCH_1):EMMC_CMD_R
   M6  EMMC_CLK_R       CLK  @SCM_LIB.SCM(SCH_1):EMMC_CLK_R
   K5  BMC_EMMC_RST_N  RST_N  @SCM_LIB.SCM(SCH_1):BMC_EMMC_RST_N

IDTQS3VH257PAG  I296  U21    [IDTQS3VH257PAG_SMLF-IDTQS3VH25A]
   14  NC              I_0D  NC
   13  NC              I_1D  NC
   12  NC                YD  NC
    2  SPI_SYS_MUX_WP_IO2   I_0A  @SCM_LIB.SCM(SCH_1):SPI_SYS_MUX_WP_IO2
    5  SPI_SYS_MUX_MISO   I_0B  @SCM_LIB.SCM(SCH_1):SPI_SYS_MUX_MISO
   11  SPI_PCH_SECURE_CS0_N   I_0C  @SCM_LIB.SCM(SCH_1):SPI_PCH_SECURE_CS0_N
    4  SPI_PCH_MUXED_IO2     YA  @SCM_LIB.SCM(SCH_1):SPI_PCH_MUXED_IO2
    7  SPI_PCH_MUXED_IO1     YB  @SCM_LIB.SCM(SCH_1):SPI_PCH_MUXED_IO1
    9  SPI_PCH_MUXED_CS0_N     YC  @SCM_LIB.SCM(SCH_1):SPI_PCH_MUXED_CS0_N
   10  SPI_BMC_BIOS_SOURCE_CS0_N   I_1C  @SCM_LIB.SCM(SCH_1):SPI_BMC_BIOS_SOURCE_CS0_N
    6  SPI_BMC_BIOS_ROM_R_MISO   I_1B  @SCM_LIB.SCM(SCH_1):SPI_BMC_BIOS_ROM_R_MISO
    3  SPI_BMC_BIOS_ROM_R_IO2   I_1A  @SCM_LIB.SCM(SCH_1):SPI_BMC_BIOS_ROM_R_IO2
   15  PD_BIOS_MUX_EN_N     E*  @SCM_LIB.SCM(SCH_1):PD_BIOS_MUX_EN_N
   16  P3V3_AUX         VCC  @SCM_LIB.SCM(SCH_1):P3V3_AUX
    8  GND              GND  @SCM_LIB.SCM(SCH_1):GND
    1  FM_BMC_BIOS_MUX_CS_SPI_R_SEL_0      S  @SCM_LIB.SCM(SCH_1):FM_BMC_BIOS_MUX_CS_SPI_R_SEL_0

SN74LVC1G07DBVR  I2   U23    [SN74LVC1G07DBVR_SMLF-SN74LVC1GA]
    5  P3V3_AUX         VCC  @SCM_LIB.SCM(SCH_1):P3V3_AUX
    1  NC                NC  NC
    3  GND              GND  @SCM_LIB.SCM(SCH_1):GND
    4  DEBUG_PORT_PRSNT_BUF_EN      Y  @SCM_LIB.SCM(SCH_1):DEBUG_PORT_PRSNT_BUF_EN
    2  DEBUG_PORT_PRSNT      A  @SCM_LIB.SCM(SCH_1):DEBUG_PORT_PRSNT

SN74LVC2G07DCKR  I115  U24    [SN74LVC2G07DCKR_SMLF-SN74LVC2GA]
    1  UART_BMC_5_TXD_R     1A  @SCM_LIB.SCM(SCH_1):UART_BMC_5_TXD_R
    6  UART_BMC_5_TXD_BUF     1Y  @SCM_LIB.SCM(SCH_1):UART_BMC_5_TXD_BUF
    4  UART_BMC_5_RXD_BUF_R     2Y  @SCM_LIB.SCM(SCH_1):UART_BMC_5_RXD_BUF_R
    3  UART_BMC_5_RXD_BUF     2A  @SCM_LIB.SCM(SCH_1):UART_BMC_5_RXD_BUF
    5  P3V3_AUX         VCC  @SCM_LIB.SCM(SCH_1):P3V3_AUX
    2  GND              GND  @SCM_LIB.SCM(SCH_1):GND

10M02SCU169C8G  I96  U25    [10M02SCU169C8G-10M02SCU169C8G,A]
   K9  PVCCD_PLL_AUX  VCCA4  @SCM_LIB.SCM(SCH_1):PVCCD_PLL_AUX
   D4  PVCCD_PLL_AUX  VCCA3  @SCM_LIB.SCM(SCH_1):PVCCD_PLL_AUX
  D10  PVCCD_PLL_AUX  VCCA2  @SCM_LIB.SCM(SCH_1):PVCCD_PLL_AUX
   K4  PVCCD_PLL_AUX  VCCA1  @SCM_LIB.SCM(SCH_1):PVCCD_PLL_AUX
   F7  PVCCA_AUX_PLD  VCC_ONE_3  @SCM_LIB.SCM(SCH_1):PVCCA_AUX_PLD
   G6  PVCCA_AUX_PLD  VCC_ONE_2  @SCM_LIB.SCM(SCH_1):PVCCA_AUX_PLD
   G8  PVCCA_AUX_PLD  VCC_ONE_1  @SCM_LIB.SCM(SCH_1):PVCCA_AUX_PLD
   H7  PVCCA_AUX_PLD  VCC_ONE_0  @SCM_LIB.SCM(SCH_1):PVCCA_AUX_PLD
   C6  P3V3_AUX       VCCIO8_2  @SCM_LIB.SCM(SCH_1):P3V3_AUX
   C7  P3V3_AUX       VCCIO8_1  @SCM_LIB.SCM(SCH_1):P3V3_AUX
   C8  P3V3_AUX       VCCIO8_0  @SCM_LIB.SCM(SCH_1):P3V3_AUX
  F11  P3V3_AUX       VCCIO6_1  @SCM_LIB.SCM(SCH_1):P3V3_AUX
  G11  P3V3_AUX       VCCIO6_0  @SCM_LIB.SCM(SCH_1):P3V3_AUX
  H11  P3V3_AUX       VCCIO5_1  @SCM_LIB.SCM(SCH_1):P3V3_AUX
  J11  P3V3_AUX       VCCIO5_0  @SCM_LIB.SCM(SCH_1):P3V3_AUX
   L6  P3V3_AUX       VCCIO3_2  @SCM_LIB.SCM(SCH_1):P3V3_AUX
   L7  P3V3_AUX       VCCIO3_1  @SCM_LIB.SCM(SCH_1):P3V3_AUX
   L8  P3V3_AUX       VCCIO3_0  @SCM_LIB.SCM(SCH_1):P3V3_AUX
   J3  P3V3_AUX       VCCIO2_1  @SCM_LIB.SCM(SCH_1):P3V3_AUX
   K3  P3V3_AUX       VCCIO2_0  @SCM_LIB.SCM(SCH_1):P3V3_AUX
   G3  P3V3_AUX       VCCIO1_1  @SCM_LIB.SCM(SCH_1):P3V3_AUX
   F2  P3V3_AUX       VCCIO1_0  @SCM_LIB.SCM(SCH_1):P3V3_AUX
   D2  NC              NC_2  NC
   D3  NC              NC_1  NC
   E2  NC              NC_0  NC
   A1  GND            GND_13  @SCM_LIB.SCM(SCH_1):GND
  A13  GND            GND_12  @SCM_LIB.SCM(SCH_1):GND
   B8  GND            GND_11  @SCM_LIB.SCM(SCH_1):GND
   C3  GND            GND_10  @SCM_LIB.SCM(SCH_1):GND
   D5  GND            GND_9  @SCM_LIB.SCM(SCH_1):GND
  E11  GND            GND_8  @SCM_LIB.SCM(SCH_1):GND
   F3  GND            GND_7  @SCM_LIB.SCM(SCH_1):GND
   G7  GND            GND_6  @SCM_LIB.SCM(SCH_1):GND
  H12  GND            GND_5  @SCM_LIB.SCM(SCH_1):GND
   J4  GND            GND_4  @SCM_LIB.SCM(SCH_1):GND
   L9  GND            GND_3  @SCM_LIB.SCM(SCH_1):GND
   M6  GND            GND_2  @SCM_LIB.SCM(SCH_1):GND
   N1  GND            GND_1  @SCM_LIB.SCM(SCH_1):GND
  N13  GND            GND_0  @SCM_LIB.SCM(SCH_1):GND

10M02SCU169C8G  I330  U25    [10M02SCU169C8G-10M02SCU169C8G,A]
   E8  USB_OC0_REAR_R_N  IO_111_8  @SCM_LIB.SCM(SCH_1):USB_OC0_REAR_R_N
   E9  NC             IO_92_6  NC
   D8  NC             IO_110_DEV_OE_8  NC
   D6  NC             IO_123_CRC_ERROR_8  NC
  D11  NC             IO_101_6  NC
   C9  NC             IO_104_8  NC
  C12  NC             IO_94_6  NC
  C11  NC             IO_96_6  NC
  C10  NC             IO_102_8  NC
   B9  NC             IO_108_DEV_CLRN_8  NC
  B13  NC             IO_95_6  NC
  B12  NC             IO_91_6  NC
  B11  NC             IO_93_6  NC
  B10  NC             IO_106_8  NC
   A9  NC             IO_105_8  NC
   A8  NC             IO_103_8  NC
  A12  NC             IO_97_6  NC
   D9  SMB_BMC_MM15_R3_SDA  IO_99_6  @SCM_LIB.SCM(SCH_1):SMB_BMC_MM15_R3_SDA
  E10  SMB_BMC_MM15_R3_SCL  IO_98_6  @SCM_LIB.SCM(SCH_1):SMB_BMC_MM15_R3_SCL
   B7  SMB_BMC_ALERT12_N  IO_112_VREFB8N0_8  @SCM_LIB.SCM(SCH_1):SMB_BMC_ALERT12_N
   F8  RST_WDTRST_PLD_R2_N  IO_90_6  @SCM_LIB.SCM(SCH_1):RST_WDTRST_PLD_R2_N
  L13  RST_ROT_CPU_R_N  IO_69_5  @SCM_LIB.SCM(SCH_1):RST_ROT_CPU_R_N
  H10  RST_MB_STBY_R_N  IO_74_5  @SCM_LIB.SCM(SCH_1):RST_MB_STBY_R_N
  L12  RST_BMC_SELF_HW_R2  IO_67_5  @SCM_LIB.SCM(SCH_1):RST_BMC_SELF_HW_R2
  D12  RST_BMC_HW_R   IO_100_6  @SCM_LIB.SCM(SCH_1):RST_BMC_HW_R
   B5  PWR_LED_CPLD   IO_119_8  @SCM_LIB.SCM(SCH_1):PWR_LED_CPLD
  A11  PWRGD_SYS_PWROK_PLD  IO_109_8  @SCM_LIB.SCM(SCH_1):PWRGD_SYS_PWROK_PLD
   A3  PWRGD_P5V_AUX_R1  IO_120_8  @SCM_LIB.SCM(SCH_1):PWRGD_P5V_AUX_R1
   A5  PWRGD_P3V3_RGM_R1  IO_126_8  @SCM_LIB.SCM(SCH_1):PWRGD_P3V3_RGM_R1
   E6  PWRGD_P3V3_AUX_R1  IO_121_8  @SCM_LIB.SCM(SCH_1):PWRGD_P3V3_AUX_R1
   B3  PWRGD_P2V5_AUX_R1  IO_122_8  @SCM_LIB.SCM(SCH_1):PWRGD_P2V5_AUX_R1
   B4  PWRGD_P1V8_AUX_R1  IO_124_8  @SCM_LIB.SCM(SCH_1):PWRGD_P1V8_AUX_R1
   A2  PWRGD_P1V2_AUX_R1  IO_128_8  @SCM_LIB.SCM(SCH_1):PWRGD_P1V2_AUX_R1
   B2  PWRGD_P1V0_AUX_R1  IO_129_8  @SCM_LIB.SCM(SCH_1):PWRGD_P1V0_AUX_R1
   C4  PU_FPGA_NSTATUS  IO_125_NSTATUS_8  @SCM_LIB.SCM(SCH_1):PU_FPGA_NSTATUS
   E7  PU_FPGA_NCONFIG  IN_115_NCONFIG_8  @SCM_LIB.SCM(SCH_1):PU_FPGA_NCONFIG
   C5  PU_FPGA_CONFIG_DONE  IO_127_CONF_DONE_8  @SCM_LIB.SCM(SCH_1):PU_FPGA_CONFIG_DONE
   D7  PD_FPGA_CONFIG_SEL  IO_113_CONFIG_SEL_8  @SCM_LIB.SCM(SCH_1):PD_FPGA_CONFIG_SEL
  J13  H_CPU0_PROCHOT_LVC1_R_N  IO_73_5  @SCM_LIB.SCM(SCH_1):H_CPU0_PROCHOT_LVC1_R_N
  K13  FM_THROTTLE_R_N  IO_71_VREFB5N0_5  @SCM_LIB.SCM(SCH_1):FM_THROTTLE_R_N
  K12  FM_SLPS3_GF_R_N  IO_68_5  @SCM_LIB.SCM(SCH_1):FM_SLPS3_GF_R_N
   A4  FM_RISER2_JTAG_SEL_N  IO_118_8  @SCM_LIB.SCM(SCH_1):FM_RISER2_JTAG_SEL_N
   B6  FM_RISER1_JTAG_SEL_N  IO_117_8  @SCM_LIB.SCM(SCH_1):FM_RISER1_JTAG_SEL_N
  A10  FM_PWR_R_BTN   IO_107_8  @SCM_LIB.SCM(SCH_1):FM_PWR_R_BTN
   J9  FM_PMBUS_ALERT_EN  IO_72_5  @SCM_LIB.SCM(SCH_1):FM_PMBUS_ALERT_EN
   H8  FM_PCHHOT_R_N  IO_78_5  @SCM_LIB.SCM(SCH_1):FM_PCHHOT_R_N
   H9  FM_MASTER_MB_N  IO_76_5  @SCM_LIB.SCM(SCH_1):FM_MASTER_MB_N
  J12  FM_ESPI_PLD_R_EN  IO_70_5  @SCM_LIB.SCM(SCH_1):FM_ESPI_PLD_R_EN
   A7  FM_BMC_READY_PLD_N  IO_114_8  @SCM_LIB.SCM(SCH_1):FM_BMC_READY_PLD_N
  G12  FM_BMC_ONCTL_R_N  IO_79_5  @SCM_LIB.SCM(SCH_1):FM_BMC_ONCTL_R_N
  G13  FM_BMC_EN_DET_R  IO_77_5  @SCM_LIB.SCM(SCH_1):FM_BMC_EN_DET_R
   A6  FM_BIOS_DEBUG_EN_N  IO_116_8  @SCM_LIB.SCM(SCH_1):FM_BIOS_DEBUG_EN_N
  H13  FM_ADR_TRIGGER_N  IO_75_5  @SCM_LIB.SCM(SCH_1):FM_ADR_TRIGGER_N
  C13  BMC_CPLD_GPIO_25_R2  IO_89_6  @SCM_LIB.SCM(SCH_1):BMC_CPLD_GPIO_25_R2
  F10  BMC_CPLD_GPIO_24_R2  IO_88_DPCLK2_6  @SCM_LIB.SCM(SCH_1):BMC_CPLD_GPIO_24_R2
  D13  BMC_CPLD_GPIO_23_R2  IO_87_VREFB6N0_6  @SCM_LIB.SCM(SCH_1):BMC_CPLD_GPIO_23_R2
   F9  BMC_CPLD_GPIO_22_R2  IO_86_DPCLK_3_6  @SCM_LIB.SCM(SCH_1):BMC_CPLD_GPIO_22_R2
  E12  BMC_CPLD_GPIO_21_R2  IO_85_6  @SCM_LIB.SCM(SCH_1):BMC_CPLD_GPIO_21_R2
  F12  BMC_CPLD_GPIO_20_R2  IO_84_6  @SCM_LIB.SCM(SCH_1):BMC_CPLD_GPIO_20_R2
  E13  BMC_CPLD_GPIO_19_R2  IO_83_CLK3N_6  @SCM_LIB.SCM(SCH_1):BMC_CPLD_GPIO_19_R2
  F13  BMC_CPLD_GPIO_18_R2  IO_82_CLK3P_6  @SCM_LIB.SCM(SCH_1):BMC_CPLD_GPIO_18_R2
  G10  BMC_CPLD_GPIO_17_R2  IO_81_CLK2N_6  @SCM_LIB.SCM(SCH_1):BMC_CPLD_GPIO_17_R2
   G9  BMC_CPLD_GPIO_16_R2  IO_80_CLK2P_6  @SCM_LIB.SCM(SCH_1):BMC_CPLD_GPIO_16_R2

10M02SCU169C8G  I394  U25    [10M02SCU169C8G-10M02SCU169C8G,A]
   N2  VOL_SEN_ALERT_R  IO_26_DPCLK0_2  @SCM_LIB.SCM(SCH_1):VOL_SEN_ALERT_R
   M3  SMB_BMC_ALERT9_R1_N  IO_30_PLL_L_CLKOUTN_2  @SCM_LIB.SCM(SCH_1):SMB_BMC_ALERT9_R1_N
   L2  SMB_BMC_ALERT4_R1_N  IO_29_2  @SCM_LIB.SCM(SCH_1):SMB_BMC_ALERT4_R1_N
   N3  SMB_BMC_ALERT3_R1_N  IO_28_DPCLK1_2  @SCM_LIB.SCM(SCH_1):SMB_BMC_ALERT3_R1_N
   K1  SMB_BMC_ALERT10_R1_N  IO_31_2  @SCM_LIB.SCM(SCH_1):SMB_BMC_ALERT10_R1_N
   J7  SGPIO_PLD_LD_0  IO_50_3  @SCM_LIB.SCM(SCH_1):SGPIO_PLD_LD_0
   M9  SGPIO_PLD_DO_0  IO_49_3  @SCM_LIB.SCM(SCH_1):SGPIO_PLD_DO_0
  N11  SGPIO_PLD_DI_0  IO_51_VREFB3N0_3  @SCM_LIB.SCM(SCH_1):SGPIO_PLD_DI_0
   K6  SGPIO_CLK_PLD_0  IO_48_3  @SCM_LIB.SCM(SCH_1):SGPIO_CLK_PLD_0
   K2  RST_SRST_PLD_BMC_R_N  IO_33_2  @SCM_LIB.SCM(SCH_1):RST_SRST_PLD_BMC_R_N
   N9  RST_SGPIO_RESET_R_N  IO_57_3  @SCM_LIB.SCM(SCH_1):RST_SGPIO_RESET_R_N
   F1  RST_RSMRST_N   IO_5_1A  @SCM_LIB.SCM(SCH_1):RST_RSMRST_N
   B1  RST_PLTRST_R1_N  IO_3_1A  @SCM_LIB.SCM(SCH_1):RST_PLTRST_R1_N
   H1  RST_PCA9548_SENSOR_N  IO_10_VREFB1N0_1B  @SCM_LIB.SCM(SCH_1):RST_PCA9548_SENSOR_N
   N5  RST_EXTRST_R_N  IO_41_3  @SCM_LIB.SCM(SCH_1):RST_EXTRST_R_N
   H3  RST_BMC_RSTBTN_OUT_N  IO_17_1B  @SCM_LIB.SCM(SCH_1):RST_BMC_RSTBTN_OUT_N
   N4  PWR_BTN_BMC_N  IO_39_3  @SCM_LIB.SCM(SCH_1):PWR_BTN_BMC_N
   E3  PWRGD_PSU_AC_PWROK_PLD  IO_4_1A  @SCM_LIB.SCM(SCH_1):PWRGD_PSU_AC_PWROK_PLD
   G4  PWRGD_PCH_PWROK  IO_15_1B  @SCM_LIB.SCM(SCH_1):PWRGD_PCH_PWROK
   N6  PWRGD_CPUPWRGD_LVC1  IO_42_3  @SCM_LIB.SCM(SCH_1):PWRGD_CPUPWRGD_LVC1
   G1  JTAG_SCM_PLD_TMS  IO_9_TMS_1B  @SCM_LIB.SCM(SCH_1):JTAG_SCM_PLD_TMS
   F6  JTAG_SCM_PLD_TDO  IO_13_TDO_1B  @SCM_LIB.SCM(SCH_1):JTAG_SCM_PLD_TDO
   F5  JTAG_SCM_PLD_TDI  IO_12_TDI_1B  @SCM_LIB.SCM(SCH_1):JTAG_SCM_PLD_TDI
   G2  JTAG_SCM_PLD_TCK  IO_11_TCK_1B  @SCM_LIB.SCM(SCH_1):JTAG_SCM_PLD_TCK
   E5  JTAG_SCM_PLD_JTAGEN  IO_8_JTAGEN_1B  @SCM_LIB.SCM(SCH_1):JTAG_SCM_PLD_JTAGEN
   H2  IRQ_UV_DETECT_N  IO_16_1B  @SCM_LIB.SCM(SCH_1):IRQ_UV_DETECT_N
  M12  IRQ_SGPIO_R_N  IO_56_3  @SCM_LIB.SCM(SCH_1):IRQ_SGPIO_R_N
   M4  IRQ_PCH_SCI_WHEA_R_N  IO_35_3  @SCM_LIB.SCM(SCH_1):IRQ_PCH_SCI_WHEA_R_N
   N8  IRQ_OC_DETECT_N  IO_45_3  @SCM_LIB.SCM(SCH_1):IRQ_OC_DETECT_N
   M8  IRQ_OC_DETECT_EN_N  IO_47_3  @SCM_LIB.SCM(SCH_1):IRQ_OC_DETECT_EN_N
   M7  IRQ_CPU1_VRHOT_N  IO_44_3  @SCM_LIB.SCM(SCH_1):IRQ_CPU1_VRHOT_N
   N7  IRQ_CPU0_VRHOT_N  IO_43_3  @SCM_LIB.SCM(SCH_1):IRQ_CPU0_VRHOT_N
   M1  IRQ_BMC_PCH_NMI_R_N  IO_23_2  @SCM_LIB.SCM(SCH_1):IRQ_BMC_PCH_NMI_R_N
   C2  IRQ_BMC_CPU_NMI_R  IO_2_1A  @SCM_LIB.SCM(SCH_1):IRQ_BMC_CPU_NMI_R
   M2  H_CPU1_PROCHOT_LVC1_R_N  IO_25_2  @SCM_LIB.SCM(SCH_1):H_CPU1_PROCHOT_LVC1_R_N
  N10  H_CPU1_MEMTRIP_LVC1_N  IO_55_3  @SCM_LIB.SCM(SCH_1):H_CPU1_MEMTRIP_LVC1_N
  N12  H_CPU0_MEMTRIP_LVC1_N  IO_53_3  @SCM_LIB.SCM(SCH_1):H_CPU0_MEMTRIP_LVC1_N
   C1  FM_TPM_PRSNT_1_R_N  IO_1_1A  @SCM_LIB.SCM(SCH_1):FM_TPM_PRSNT_1_R_N
   D1  FM_TPM_PRSNT_0_R_N  IO_0_1A  @SCM_LIB.SCM(SCH_1):FM_TPM_PRSNT_0_R_N
   K7  FM_THERMTRIP_DLY_LVC1_R_N  IO_52_3  @SCM_LIB.SCM(SCH_1):FM_THERMTRIP_DLY_LVC1_R_N
  M13  FM_SPD_REMOTE_EN_R  IO_54_3  @SCM_LIB.SCM(SCH_1):FM_SPD_REMOTE_EN_R
   L1  FM_PECI_SEL_N  IO_27_VREFB2N0_2  @SCM_LIB.SCM(SCH_1):FM_PECI_SEL_N
   J2  FM_PCIE_M2_SSD0_PRSNT_N  IO_21_2  @SCM_LIB.SCM(SCH_1):FM_PCIE_M2_SSD0_PRSNT_N
   H4  FM_PCH_BMC_THERMTRIP_N  IO_24_CLK1P_2  @SCM_LIB.SCM(SCH_1):FM_PCH_BMC_THERMTRIP_N
   J1  FM_ME_BT_DONE  IO_19_2  @SCM_LIB.SCM(SCH_1):FM_ME_BT_DONE
   L5  FM_MB_STBY_R_EN  IO_34_3  @SCM_LIB.SCM(SCH_1):FM_MB_STBY_R_EN
   E4  FM_JTAG_TCK_MUX_BMC_SEL  IO_6_1A  @SCM_LIB.SCM(SCH_1):FM_JTAG_TCK_MUX_BMC_SEL
   J5  FM_CPU_MSMI_CATERR_LVT3_PLD_N  IO_40_3  @SCM_LIB.SCM(SCH_1):FM_CPU_MSMI_CATERR_LVT3_PLD_N
   F4  FM_BMC_DBP_PRESENT_N  IO_14_1B  @SCM_LIB.SCM(SCH_1):FM_BMC_DBP_PRESENT_N
   H5  FM_BIOS_POST_CMPLT_BMC_N  IO_22_CLK1N_2  @SCM_LIB.SCM(SCH_1):FM_BIOS_POST_CMPLT_BMC_N
   J6  FM_ADR_COMPLETE  IO_46_3  @SCM_LIB.SCM(SCH_1):FM_ADR_COMPLETE
   H6  CLK_25M_OSC_FPGA  IO_20_CLK0P_2  @SCM_LIB.SCM(SCH_1):CLK_25M_OSC_FPGA
   J8  BMC_CPLD_GPIO_9_R2  IO_60_3  @SCM_LIB.SCM(SCH_1):BMC_CPLD_GPIO_9_R2
  L11  BMC_CPLD_GPIO_8_R2  IO_59_3  @SCM_LIB.SCM(SCH_1):BMC_CPLD_GPIO_8_R2
  M11  BMC_CPLD_GPIO_7_R2  IO_58_3  @SCM_LIB.SCM(SCH_1):BMC_CPLD_GPIO_7_R2
   K5  BMC_CPLD_GPIO_6_R2  IO_38_3  @SCM_LIB.SCM(SCH_1):BMC_CPLD_GPIO_6_R2
   M5  BMC_CPLD_GPIO_5_R2  IO_37_3  @SCM_LIB.SCM(SCH_1):BMC_CPLD_GPIO_5_R2
   L4  BMC_CPLD_GPIO_4_R2  IO_36_3  @SCM_LIB.SCM(SCH_1):BMC_CPLD_GPIO_4_R2
   L3  BMC_CPLD_GPIO_3_R2  IO_32_PLL_L_CLKOUTP_2  @SCM_LIB.SCM(SCH_1):BMC_CPLD_GPIO_3_R2
   G5  BMC_CPLD_GPIO_2_R2  IO_18_CLK0N_2  @SCM_LIB.SCM(SCH_1):BMC_CPLD_GPIO_2_R2
   E1  BMC_CPLD_GPIO_1_R2  IO_7_1A  @SCM_LIB.SCM(SCH_1):BMC_CPLD_GPIO_1_R2
  J10  BMC_CPLD_GPIO_15_R2  IO_66_5  @SCM_LIB.SCM(SCH_1):BMC_CPLD_GPIO_15_R2
  K11  BMC_CPLD_GPIO_14_R2  IO_65_5  @SCM_LIB.SCM(SCH_1):BMC_CPLD_GPIO_14_R2
  K10  BMC_CPLD_GPIO_13_R2  IO_64_5  @SCM_LIB.SCM(SCH_1):BMC_CPLD_GPIO_13_R2
  L10  BMC_CPLD_GPIO_12_R2  IO_63_3  @SCM_LIB.SCM(SCH_1):BMC_CPLD_GPIO_12_R2
  M10  BMC_CPLD_GPIO_11_R2  IO_62_3  @SCM_LIB.SCM(SCH_1):BMC_CPLD_GPIO_11_R2
   K8  BMC_CPLD_GPIO_10_R2  IO_61_3  @SCM_LIB.SCM(SCH_1):BMC_CPLD_GPIO_10_R2

74HC1G126GW  I33  U26    [74HC1G126GW-74HC1G126GW,SMLF,IA]
    4  V_VGAVS_BUF_R      4  @SCM_LIB.SCM(SCH_1):V_VGAVS_BUF_R
    2  V_VGAVS            2  @SCM_LIB.SCM(SCH_1):V_VGAVS
    3  GND              GND  @SCM_LIB.SCM(SCH_1):GND
    5  BMC_DDC_BUF_PWR      5  @SCM_LIB.SCM(SCH_1):BMC_DDC_BUF_PWR
    1  BMC_DDC_BUF_EN      1  @SCM_LIB.SCM(SCH_1):BMC_DDC_BUF_EN

MX66L1G45GMI08G  I64  U28    [MX66L1G45GMI08G-MX66L1G45GMI-0A]
    6  NC              DNU2  NC
    5  NC              DNU1  NC
    4  NC               NC1  NC
   14  NC               NC3  NC
   13  NC               NC2  NC
   12  NC              DNU4  NC
   11  NC              DNU3  NC
    1  SPI_BMC_IO3_FLASH_R2  NC0||SIO3  @SCM_LIB.SCM(SCH_1):SPI_BMC_IO3_FLASH_R2
    9  SPI_BMC_IO2_FLASH_R2  WP#||SIO2  @SCM_LIB.SCM(SCH_1):SPI_BMC_IO2_FLASH_R2
    8  SPI_BMC_IO1_FLASH_R2  SO||SIO1  @SCM_LIB.SCM(SCH_1):SPI_BMC_IO1_FLASH_R2
   15  SPI_BMC_IO0_FLASH_R2  SI_SIO0  @SCM_LIB.SCM(SCH_1):SPI_BMC_IO0_FLASH_R2
    7  SPI_BMC_CS1_FLASH_R2_N    CS#  @SCM_LIB.SCM(SCH_1):SPI_BMC_CS1_FLASH_R2_N
   16  SPI_BMC_CLK_FLASH_R2   SCLK  @SCM_LIB.SCM(SCH_1):SPI_BMC_CLK_FLASH_R2
    3  RST_SPI_BMC_FLASH_R2_N  RESET#  @SCM_LIB.SCM(SCH_1):RST_SPI_BMC_FLASH_R2_N
    2  P3V3_AUX         VCC  @SCM_LIB.SCM(SCH_1):P3V3_AUX
   10  GND              GND  @SCM_LIB.SCM(SCH_1):GND

74HC1G126GW  I67  U29    [74HC1G126GW-74HC1G126GW,SMLF,IA]
    2  SPA_SOUT_SW_DBG      2  @SCM_LIB.SCM(SCH_1):SPA_SOUT_SW_DBG
    5  P3V3_AUX           5  @SCM_LIB.SCM(SCH_1):P3V3_AUX
    3  GND              GND  @SCM_LIB.SCM(SCH_1):GND
    4  DEBUG_PORT_UART_TX      4  @SCM_LIB.SCM(SCH_1):DEBUG_PORT_UART_TX
    1  DEBUG_PORT_PRSNT      1  @SCM_LIB.SCM(SCH_1):DEBUG_PORT_PRSNT

IDTQS3VH257PAG  I271  U30    [IDTQS3VH257PAG_SMLF-IDTQS3VH25A]
   14  NC              I_0D  NC
   13  NC              I_1D  NC
   12  NC                YD  NC
    2  SPI_SYS_MUX_MOSI   I_0A  @SCM_LIB.SCM(SCH_1):SPI_SYS_MUX_MOSI
    5  SPI_SYS_MUX_HOLD_IO3   I_0B  @SCM_LIB.SCM(SCH_1):SPI_SYS_MUX_HOLD_IO3
   11  SPI_SYS_MUX_CLK   I_0C  @SCM_LIB.SCM(SCH_1):SPI_SYS_MUX_CLK
    7  SPI_PCH_MUXED_IO3     YB  @SCM_LIB.SCM(SCH_1):SPI_PCH_MUXED_IO3
    4  SPI_PCH_MUXED_IO0     YA  @SCM_LIB.SCM(SCH_1):SPI_PCH_MUXED_IO0
    9  SPI_PCH_MUXED_CLK     YC  @SCM_LIB.SCM(SCH_1):SPI_PCH_MUXED_CLK
    3  SPI_BMC_BIOS_ROM_R_MOSI   I_1A  @SCM_LIB.SCM(SCH_1):SPI_BMC_BIOS_ROM_R_MOSI
    6  SPI_BMC_BIOS_ROM_R_IO3   I_1B  @SCM_LIB.SCM(SCH_1):SPI_BMC_BIOS_ROM_R_IO3
   10  SPI_BMC_BIOS_ROM_R_CLK   I_1C  @SCM_LIB.SCM(SCH_1):SPI_BMC_BIOS_ROM_R_CLK
   15  PD_BIOS_MUX_EN_N     E*  @SCM_LIB.SCM(SCH_1):PD_BIOS_MUX_EN_N
   16  P3V3_AUX         VCC  @SCM_LIB.SCM(SCH_1):P3V3_AUX
    8  GND              GND  @SCM_LIB.SCM(SCH_1):GND
    1  FM_BMC_BIOS_MUX_CS_SPI_R_SEL_0      S  @SCM_LIB.SCM(SCH_1):FM_BMC_BIOS_MUX_CS_SPI_R_SEL_0

74LVC1G07GW  I151  U31    [74LVC1G07GW-74LVC1G07GW,SMLF,IA]
    1  NC                NC  NC
    2  REAR_PWR_BTN_N      A  @SCM_LIB.SCM(SCH_1):REAR_PWR_BTN_N
    4  PWR_BTN_BMC_N      Y  @SCM_LIB.SCM(SCH_1):PWR_BTN_BMC_N
    5  P3V3_AUX         VCC  @SCM_LIB.SCM(SCH_1):P3V3_AUX
    3  GND              GND  @SCM_LIB.SCM(SCH_1):GND

74LVC1G17GW  I49  U32    [74LVC1G17GW-74LVC1G17GW,SMLF,IA]
    1  NC                NC  NC
    2  REAR_ID_RST_BTN_N      A  @SCM_LIB.SCM(SCH_1):REAR_ID_RST_BTN_N
    5  P3V3_AUX         VCC  @SCM_LIB.SCM(SCH_1):P3V3_AUX
    4  ID_RST_BTN_BMC_N      Y  @SCM_LIB.SCM(SCH_1):ID_RST_BTN_BMC_N
    3  GND              GND  @SCM_LIB.SCM(SCH_1):GND

74HC1G126GW  I32  U33    [74HC1G126GW-74HC1G126GW,SMLF,IA]
    4  V_VGAHS_BUF_R      4  @SCM_LIB.SCM(SCH_1):V_VGAHS_BUF_R
    2  V_VGAHS            2  @SCM_LIB.SCM(SCH_1):V_VGAHS
    3  GND              GND  @SCM_LIB.SCM(SCH_1):GND
    5  BMC_DDC_BUF_PWR      5  @SCM_LIB.SCM(SCH_1):BMC_DDC_BUF_PWR
    1  BMC_DDC_BUF_EN      1  @SCM_LIB.SCM(SCH_1):BMC_DDC_BUF_EN

TPD4E001DBVR  I48  U34    [TPD4E001DBVR-TPD4E001DBVR,SMLFA]
    4  V_VGAVS_BUF      IO3  @SCM_LIB.SCM(SCH_1):V_VGAVS_BUF
    6  V_VGAHS_BUF      IO4  @SCM_LIB.SCM(SCH_1):V_VGAHS_BUF
    1  V_BMC_LS_DDC_SDA_R    IO1  @SCM_LIB.SCM(SCH_1):V_BMC_LS_DDC_SDA_R
    3  V_BMC_LS_DDC_SCL_R    IO2  @SCM_LIB.SCM(SCH_1):V_BMC_LS_DDC_SCL_R
    2  GND              GND  @SCM_LIB.SCM(SCH_1):GND
    5  CRT_VCC5         VCC  @SCM_LIB.SCM(SCH_1):CRT_VCC5

TPD4E001DBVR  I70  U35    [TPD4E001DBVR-TPD4E001DBVR,SMLFA]
    4  V_DACR_IO        IO3  @SCM_LIB.SCM(SCH_1):V_DACR_IO
    3  V_DACG_IO        IO2  @SCM_LIB.SCM(SCH_1):V_DACG_IO
    1  V_DACB_IO        IO1  @SCM_LIB.SCM(SCH_1):V_DACB_IO
    6  NC               IO4  NC
    2  GND              GND  @SCM_LIB.SCM(SCH_1):GND
    5  CRT_VCC5         VCC  @SCM_LIB.SCM(SCH_1):CRT_VCC5

74HC1G126GW  I43  U36    [74HC1G126GW-74HC1G126GW,SMLF,IA]
    4  SPA_SIN_SW_DBG      4  @SCM_LIB.SCM(SCH_1):SPA_SIN_SW_DBG
    5  P3V3_AUX           5  @SCM_LIB.SCM(SCH_1):P3V3_AUX
    3  GND              GND  @SCM_LIB.SCM(SCH_1):GND
    2  DEBUG_PORT_UART_RX      2  @SCM_LIB.SCM(SCH_1):DEBUG_PORT_UART_RX
    1  DEBUG_PORT_PRSNT      1  @SCM_LIB.SCM(SCH_1):DEBUG_PORT_PRSNT

PRTR5V0U2X  I6   U38    [PRTR5V0U2X-PRTR5V0U2X,SMLF,IC,A]
    2  USB2_01_F_DP     IO1  @SCM_LIB.SCM(SCH_1):USB2_01_F_DP
    3  USB2_01_F_DN     IO2  @SCM_LIB.SCM(SCH_1):USB2_01_F_DN
    4  P5V_USB_REAR     VCC  @SCM_LIB.SCM(SCH_1):P5V_USB_REAR
    1  GND              GND  @SCM_LIB.SCM(SCH_1):GND

TPS3808G33DBVR  I60  U43    [TPS3808G33DBVR-TPS3808G33DBVR,A]
    4  U43_CT            CT  @SCM_LIB.SCM(SCH_1):U43_CT
    3  PWRGD_P1V0_AUX_R2    #MR  @SCM_LIB.SCM(SCH_1):PWRGD_P1V0_AUX_R2
    1  PWRGD_P1V0_AUX_DELAY_R1  #RESET  @SCM_LIB.SCM(SCH_1):PWRGD_P1V0_AUX_DELAY_R1
    6  P3V3_AUX         VDD  @SCM_LIB.SCM(SCH_1):P3V3_AUX
    5  P1V0_AUX       SENSE  @SCM_LIB.SCM(SCH_1):P1V0_AUX
    2  GND              GND  @SCM_LIB.SCM(SCH_1):GND

Q_XTAL_4P_13BI_24GND  I204  Y1     [Q_XTAL_4P_13BI_24GND-25MHZ,SMLA]
    3  XTAL_PHY_XO_R     X2  @SCM_LIB.SCM(SCH_1):XTAL_PHY_XO_R
    1  XTAL_PHY_XI_R     X1  @SCM_LIB.SCM(SCH_1):XTAL_PHY_XI_R
    4  GND               G2  @SCM_LIB.SCM(SCH_1):GND
    2  GND               G1  @SCM_LIB.SCM(SCH_1):GND
END OF PART CROSS REFERENCE

SIGNAL CROSS REFERENCE (forward interface)

85_10INCH_BOT_DN   @SCM_LIB.SCM(SCH_1):85_10INCH_BOT_DN
  J24      2      2  DELTA_L     I33
  J27      1      1  DELTA_L     I37

85_10INCH_BOT_DP   @SCM_LIB.SCM(SCH_1):85_10INCH_BOT_DP
  J24      1      1  DELTA_L     I33
  J27      2      2  DELTA_L     I37

85_10INCH_IN1_DN   @SCM_LIB.SCM(SCH_1):85_10INCH_IN1_DN
  J28      1      1  DELTA_L     I45
  J30      2      2  DELTA_L     I43

85_10INCH_IN1_DP   @SCM_LIB.SCM(SCH_1):85_10INCH_IN1_DP
  J28      2      2  DELTA_L     I45
  J30      1      1  DELTA_L     I43

85_10INCH_IN4_DN   @SCM_LIB.SCM(SCH_1):85_10INCH_IN4_DN
  J23      2      2  DELTA_L     I32
  J26      1      1  DELTA_L     I36

85_10INCH_IN4_DP   @SCM_LIB.SCM(SCH_1):85_10INCH_IN4_DP
  J23      1      1  DELTA_L     I32
  J26      2      2  DELTA_L     I36

85_10INCH_TOP_DN   @SCM_LIB.SCM(SCH_1):85_10INCH_TOP_DN
  J22      2      2  DELTA_L     I42
  J25      1      1  DELTA_L     I44

85_10INCH_TOP_DP   @SCM_LIB.SCM(SCH_1):85_10INCH_TOP_DP
  J22      1      1  DELTA_L     I42
  J25      2      2  DELTA_L     I44

85_5INCH_BOT_DN   @SCM_LIB.SCM(SCH_1):85_5INCH_BOT_DN
  J17      1      1  DELTA_L     I23
  J20      2      2  DELTA_L     I28

85_5INCH_BOT_DP   @SCM_LIB.SCM(SCH_1):85_5INCH_BOT_DP
  J17      2      2  DELTA_L     I23
  J20      1      1  DELTA_L     I28

85_5INCH_IN1_DN   @SCM_LIB.SCM(SCH_1):85_5INCH_IN1_DN
  J11      1      1  DELTA_L     I11
  J29      2      2  DELTA_L     I29

85_5INCH_IN1_DP   @SCM_LIB.SCM(SCH_1):85_5INCH_IN1_DP
  J11      2      2  DELTA_L     I11
  J29      1      1  DELTA_L     I29

85_5INCH_IN4_DN   @SCM_LIB.SCM(SCH_1):85_5INCH_IN4_DN
  J16      1      1  DELTA_L     I21
  J19      2      2  DELTA_L     I27

85_5INCH_IN4_DP   @SCM_LIB.SCM(SCH_1):85_5INCH_IN4_DP
  J16      2      2  DELTA_L     I21
  J19      1      1  DELTA_L     I27

85_5INCH_TOP_DN   @SCM_LIB.SCM(SCH_1):85_5INCH_TOP_DN
  J9       1      1  DELTA_L      I1
  J12      2      2  DELTA_L     I31

85_5INCH_TOP_DP   @SCM_LIB.SCM(SCH_1):85_5INCH_TOP_DP
  J9       2      2  DELTA_L      I1
  J12      1      1  DELTA_L     I31

ADCVREFEXT0     @SCM_LIB.SCM(SCH_1):ADCVREFEXT0
  C282     1      A  Q_CAP       I252
  C284     1      A  Q_CAP       I250
  R780     2      B  Q_RES       I256
  R783     2      B  Q_RES       I260
  R784     2      B  Q_RES       I267
  U5     AF19  ADCVREFEXT0  AST2600A1GP  I181

ADCVREFEXT1     @SCM_LIB.SCM(SCH_1):ADCVREFEXT1
  C277     1      A  Q_CAP       I253
  C279     1      A  Q_CAP       I255
  R779     2      B  Q_RES       I259
  R781     2      B  Q_RES       I263
  R782     2      B  Q_RES       I264
  U5     AF17  ADCVREFEXT1  AST2600A1GP  I181

A_BMC_ADCAV33   @SCM_LIB.SCM(SCH_1):A_BMC_ADCAV33
  C75      1      A  Q_CAP       I93
  C77      1      A  Q_CAP       I100
  L12      2      2  Q_INDUCTOR  I99
  U5     AA21  ADCAV33_AA21  AST2600A1GP  I181
  U5     Y21  ADCAV33_Y21  AST2600A1GP  I181

A_BMC_ADCREXT0   @SCM_LIB.SCM(SCH_1):A_BMC_ADCREXT0
  R233     2      B  Q_RES       I87
  U5     AF20  ADCREXT0  AST2600A1GP  I181

A_BMC_ADCREXT1   @SCM_LIB.SCM(SCH_1):A_BMC_ADCREXT1
  R234     2      B  Q_RES       I86
  U5     AF18  ADCREXT1  AST2600A1GP  I181

A_BMC_ADCVREFN0   @SCM_LIB.SCM(SCH_1):A_BMC_ADCVREFN0
  C134     2      B  Q_CAP       I106
  C138     1      A  Q_CAP       I109
  U5     AB20  ADCVREFN0  AST2600A1GP  I181

A_BMC_ADCVREFN1   @SCM_LIB.SCM(SCH_1):A_BMC_ADCVREFN1
  C133     2      B  Q_CAP       I104
  C137     1      A  Q_CAP       I108
  U5     AD18  ADCVREFN1  AST2600A1GP  I181

A_BMC_ADCVREFP0   @SCM_LIB.SCM(SCH_1):A_BMC_ADCVREFP0
  C136     2      B  Q_CAP       I110
  C138     2      B  Q_CAP       I109
  U5     AC20  ADCVREFP0  AST2600A1GP  I181

A_BMC_ADCVREFP1   @SCM_LIB.SCM(SCH_1):A_BMC_ADCVREFP1
  C135     2      B  Q_CAP       I107
  C137     2      B  Q_CAP       I108
  U5     AD17  ADCVREFP1  AST2600A1GP  I181

A_BMC_DACREST   @SCM_LIB.SCM(SCH_1):A_BMC_DACREST
  R235     2      B  Q_RES       I187
  U5     AC21  DACRSET  AST2600A1GP  I181

BATTERY_DETECT   @SCM_LIB.SCM(SCH_1):BATTERY_DETECT
  R775     1      A  Q_RES       I183
  U5     AE15  GPIOV4||SIOPWRGD  AST2600A1GP  I45

BATTERY_DETECT_R   @SCM_LIB.SCM(SCH_1):BATTERY_DETECT_R
  Q11      G   GATE  MOSFET_N_GSD  I179
  R775     2      B  Q_RES       I183
  R776     1      A  Q_RES       I184

BJT_Q3_B        @SCM_LIB.SCM(SCH_1):BJT_Q3_B
  Q3       B      1  MMBT39047F   I4
  R290     1      A  Q_RES        I8

BJT_Q3_C        @SCM_LIB.SCM(SCH_1):BJT_Q3_C
  Q1       B      1  MMBT39047F   I2
  Q3       C      3  MMBT39047F   I4
  R289     2      B  Q_RES        I7

BMC_CLK_25M     @SCM_LIB.SCM(SCH_1):BMC_CLK_25M
  R215     2      B  Q_RES       I42
  U5     D10  CLKIN  AST2600A1GP  I41

BMC_CLK_25M_R   @SCM_LIB.SCM(SCH_1):BMC_CLK_25M_R
  OSC1     3    OUT  OSC4_7X25000018  I39
  R215     1      A  Q_RES       I42

BMC_CPLD_GPIO_1   @SCM_LIB.SCM(SCH_1):BMC_CPLD_GPIO_1
  R60      1      A  Q_RES       I417
  R495     1      A  Q_RES       I449
  R581     2      B  Q_RES        I2

BMC_CPLD_GPIO_10   @SCM_LIB.SCM(SCH_1):BMC_CPLD_GPIO_10
  R473     2      B  Q_RES       I323
  R534     2      B  Q_RES       I476
  R605     2      B  Q_RES       I33

BMC_CPLD_GPIO_10_R1   @SCM_LIB.SCM(SCH_1):BMC_CPLD_GPIO_10_R1
  R473     1      A  Q_RES       I323
  U5     AF10  GPIOZ7||SPI1DQ3||RXD13  AST2600A1GP  I45

BMC_CPLD_GPIO_10_R2   @SCM_LIB.SCM(SCH_1):BMC_CPLD_GPIO_10_R2
  R534     1      A  Q_RES       I476
  U25     K8  IO_61_3  10M02SCU169C8G  I394

BMC_CPLD_GPIO_11   @SCM_LIB.SCM(SCH_1):BMC_CPLD_GPIO_11
  R463     2      B  Q_RES       I331
  R535     2      B  Q_RES       I474
  R606     2      B  Q_RES       I31

BMC_CPLD_GPIO_11_R1   @SCM_LIB.SCM(SCH_1):BMC_CPLD_GPIO_11_R1
  R463     1      A  Q_RES       I331
  U5     F24  RGMII4TXCK||RMII4RCLKO||NCTS3||GPIOD4  AST2600A1GP  I45

BMC_CPLD_GPIO_11_R2   @SCM_LIB.SCM(SCH_1):BMC_CPLD_GPIO_11_R2
  R535     1      A  Q_RES       I474
  U25    M10  IO_62_3  10M02SCU169C8G  I394

BMC_CPLD_GPIO_12   @SCM_LIB.SCM(SCH_1):BMC_CPLD_GPIO_12
  R465     2      B  Q_RES       I329
  R536     2      B  Q_RES       I472
  R607     2      B  Q_RES       I29

BMC_CPLD_GPIO_12_R1   @SCM_LIB.SCM(SCH_1):BMC_CPLD_GPIO_12_R1
  R465     1      A  Q_RES       I329
  U5     D26  RGMII4TXD2||NDTR3||GPIOE0  AST2600A1GP  I45

BMC_CPLD_GPIO_12_R2   @SCM_LIB.SCM(SCH_1):BMC_CPLD_GPIO_12_R2
  R536     1      A  Q_RES       I472
  U25    L10  IO_63_3  10M02SCU169C8G  I394

BMC_CPLD_GPIO_13   @SCM_LIB.SCM(SCH_1):BMC_CPLD_GPIO_13
  R466     2      B  Q_RES       I327
  R537     2      B  Q_RES       I470
  R608     2      B  Q_RES       I27

BMC_CPLD_GPIO_13_R1   @SCM_LIB.SCM(SCH_1):BMC_CPLD_GPIO_13_R1
  R466     1      A  Q_RES       I327
  U5     D24  RGMII4TXD3||NRTS3||GPIOE1  AST2600A1GP  I45

BMC_CPLD_GPIO_13_R2   @SCM_LIB.SCM(SCH_1):BMC_CPLD_GPIO_13_R2
  R537     1      A  Q_RES       I470
  U25    K10  IO_64_5  10M02SCU169C8G  I394

BMC_CPLD_GPIO_14   @SCM_LIB.SCM(SCH_1):BMC_CPLD_GPIO_14
  R462     2      B  Q_RES       I325
  R540     2      B  Q_RES       I468
  R609     2      B  Q_RES       I25

BMC_CPLD_GPIO_14_R1   @SCM_LIB.SCM(SCH_1):BMC_CPLD_GPIO_14_R1
  R462     1      A  Q_RES       I325
  U5     T25  GPIOS1||MDIO1  AST2600A1GP  I45

BMC_CPLD_GPIO_14_R2   @SCM_LIB.SCM(SCH_1):BMC_CPLD_GPIO_14_R2
  R540     1      A  Q_RES       I468
  U25    K11  IO_65_5  10M02SCU169C8G  I394

BMC_CPLD_GPIO_15   @SCM_LIB.SCM(SCH_1):BMC_CPLD_GPIO_15
  R474     1      A  Q_RES       I324
  R541     2      B  Q_RES       I466
  R611     2      B  Q_RES       I23

BMC_CPLD_GPIO_15_R1   @SCM_LIB.SCM(SCH_1):BMC_CPLD_GPIO_15_R1
  R474     2      B  Q_RES       I324
  U5     AA25  GPIOQ0||TACH0  AST2600A1GP  I41

BMC_CPLD_GPIO_15_R2   @SCM_LIB.SCM(SCH_1):BMC_CPLD_GPIO_15_R2
  R541     1      A  Q_RES       I466
  U25    J10  IO_66_5  10M02SCU169C8G  I394

BMC_CPLD_GPIO_16   @SCM_LIB.SCM(SCH_1):BMC_CPLD_GPIO_16
  R475     1      A  Q_RES       I338
  R542     1      A  Q_RES       I340
  R612     2      B  Q_RES       I21

BMC_CPLD_GPIO_16_R1   @SCM_LIB.SCM(SCH_1):BMC_CPLD_GPIO_16_R1
  R475     2      B  Q_RES       I338
  U5     AB25  GPIOQ1||TACH1  AST2600A1GP  I41

BMC_CPLD_GPIO_16_R2   @SCM_LIB.SCM(SCH_1):BMC_CPLD_GPIO_16_R2
  R542     2      B  Q_RES       I340
  U25     G9  IO_80_CLK2P_6  10M02SCU169C8G  I330

BMC_CPLD_GPIO_17   @SCM_LIB.SCM(SCH_1):BMC_CPLD_GPIO_17
  R476     1      A  Q_RES       I336
  R572     1      A  Q_RES       I356
  R613     2      B  Q_RES       I19

BMC_CPLD_GPIO_17_R1   @SCM_LIB.SCM(SCH_1):BMC_CPLD_GPIO_17_R1
  R476     2      B  Q_RES       I336
  U5     Y24  GPIOQ2||TACH2  AST2600A1GP  I41

BMC_CPLD_GPIO_17_R2   @SCM_LIB.SCM(SCH_1):BMC_CPLD_GPIO_17_R2
  R572     2      B  Q_RES       I356
  U25    G10  IO_81_CLK2N_6  10M02SCU169C8G  I330

BMC_CPLD_GPIO_18   @SCM_LIB.SCM(SCH_1):BMC_CPLD_GPIO_18
  R477     1      A  Q_RES       I334
  R573     1      A  Q_RES       I354
  R617     2      B  Q_RES       I17

BMC_CPLD_GPIO_18_R1   @SCM_LIB.SCM(SCH_1):BMC_CPLD_GPIO_18_R1
  R477     2      B  Q_RES       I334
  U5     AB26  GPIOQ3||TACH3  AST2600A1GP  I41

BMC_CPLD_GPIO_18_R2   @SCM_LIB.SCM(SCH_1):BMC_CPLD_GPIO_18_R2
  R573     2      B  Q_RES       I354
  U25    F13  IO_82_CLK3P_6  10M02SCU169C8G  I330

BMC_CPLD_GPIO_19_R1   @SCM_LIB.SCM(SCH_1):BMC_CPLD_GPIO_19_R1
  R478     2      B  Q_RES       I332
  U5     Y26  GPIOQ4||TACH4  AST2600A1GP  I41

BMC_CPLD_GPIO_19_R2   @SCM_LIB.SCM(SCH_1):BMC_CPLD_GPIO_19_R2
  R574     2      B  Q_RES       I352
  U25    E13  IO_83_CLK3N_6  10M02SCU169C8G  I330

BMC_CPLD_GPIO_1_R1   @SCM_LIB.SCM(SCH_1):BMC_CPLD_GPIO_1_R1
  R60      2      B  Q_RES       I417
  U5     C22  GPIOF4||SD1DAT2||PWM12  AST2600A1GP  I45

BMC_CPLD_GPIO_1_R2   @SCM_LIB.SCM(SCH_1):BMC_CPLD_GPIO_1_R2
  R495     2      B  Q_RES       I449
  U25     E1  IO_7_1A  10M02SCU169C8G  I394

BMC_CPLD_GPIO_2   @SCM_LIB.SCM(SCH_1):BMC_CPLD_GPIO_2
  R65      1      A  Q_RES       I418
  R519     1      A  Q_RES       I451
  R586     2      B  Q_RES       I49

BMC_CPLD_GPIO_19   @SCM_LIB.SCM(SCH_1):BMC_CPLD_GPIO_19
  R478     1      A  Q_RES       I332
  R574     1      A  Q_RES       I352
  R619     2      B  Q_RES       I15

BMC_CPLD_GPIO_20   @SCM_LIB.SCM(SCH_1):BMC_CPLD_GPIO_20
  R479     1      A  Q_RES       I330
  R575     1      A  Q_RES       I350
  R621     2      B  Q_RES       I13

BMC_CPLD_GPIO_20_R1   @SCM_LIB.SCM(SCH_1):BMC_CPLD_GPIO_20_R1
  R479     2      B  Q_RES       I330
  U5     AC26  GPIOQ5||TACH5  AST2600A1GP  I41

BMC_CPLD_GPIO_20_R2   @SCM_LIB.SCM(SCH_1):BMC_CPLD_GPIO_20_R2
  R575     2      B  Q_RES       I350
  U25    F12  IO_84_6  10M02SCU169C8G  I330

BMC_CPLD_GPIO_21   @SCM_LIB.SCM(SCH_1):BMC_CPLD_GPIO_21
  R480     1      A  Q_RES       I328
  R576     1      A  Q_RES       I348
  R622     2      B  Q_RES       I11

BMC_CPLD_GPIO_21_R1   @SCM_LIB.SCM(SCH_1):BMC_CPLD_GPIO_21_R1
  R480     2      B  Q_RES       I328
  U5     Y25  GPIOQ6||TACH6  AST2600A1GP  I41

BMC_CPLD_GPIO_21_R2   @SCM_LIB.SCM(SCH_1):BMC_CPLD_GPIO_21_R2
  R576     2      B  Q_RES       I348
  U25    E12  IO_85_6  10M02SCU169C8G  I330

BMC_CPLD_GPIO_3   @SCM_LIB.SCM(SCH_1):BMC_CPLD_GPIO_3
  R458     1      A  Q_RES       I421
  R520     1      A  Q_RES       I453
  R587     2      B  Q_RES       I47

BMC_CPLD_GPIO_22   @SCM_LIB.SCM(SCH_1):BMC_CPLD_GPIO_22
  R489     1      A  Q_RES       I326
  R577     1      A  Q_RES       I346
  R626     2      B  Q_RES        I9

BMC_CPLD_GPIO_22_R1   @SCM_LIB.SCM(SCH_1):BMC_CPLD_GPIO_22_R1
  R489     2      B  Q_RES       I326
  U5     AA26  GPIOQ7||TACH7  AST2600A1GP  I41

BMC_CPLD_GPIO_22_R2   @SCM_LIB.SCM(SCH_1):BMC_CPLD_GPIO_22_R2
  R577     2      B  Q_RES       I346
  U25     F9  IO_86_DPCLK_3_6  10M02SCU169C8G  I330

BMC_CPLD_GPIO_23   @SCM_LIB.SCM(SCH_1):BMC_CPLD_GPIO_23
  R491     1      A  Q_RES       I340
  R578     1      A  Q_RES       I344
  R627     2      B  Q_RES        I7

BMC_CPLD_GPIO_23_R1   @SCM_LIB.SCM(SCH_1):BMC_CPLD_GPIO_23_R1
  R491     2      B  Q_RES       I340
  U5     AD22  GPIOO1||PWM1  AST2600A1GP  I41

BMC_CPLD_GPIO_23_R2   @SCM_LIB.SCM(SCH_1):BMC_CPLD_GPIO_23_R2
  R578     2      B  Q_RES       I344
  U25    D13  IO_87_VREFB6N0_6  10M02SCU169C8G  I330

BMC_CPLD_GPIO_24   @SCM_LIB.SCM(SCH_1):BMC_CPLD_GPIO_24
  R493     1      A  Q_RES       I343
  R579     1      A  Q_RES       I342
  R632     2      B  Q_RES        I5

BMC_CPLD_GPIO_24_R1   @SCM_LIB.SCM(SCH_1):BMC_CPLD_GPIO_24_R1
  R493     2      B  Q_RES       I343
  U5     AC22  GPIOO5||PWM5  AST2600A1GP  I41

BMC_CPLD_GPIO_24_R2   @SCM_LIB.SCM(SCH_1):BMC_CPLD_GPIO_24_R2
  R579     2      B  Q_RES       I342
  U25    F10  IO_88_DPCLK2_6  10M02SCU169C8G  I330

BMC_CPLD_GPIO_25   @SCM_LIB.SCM(SCH_1):BMC_CPLD_GPIO_25
  R96      2      B  Q_RES       I286
  R634     1      A  Q_RES       I362
  R640     2      B  Q_RES       I51

BMC_CPLD_GPIO_25_R1   @SCM_LIB.SCM(SCH_1):BMC_CPLD_GPIO_25_R1
  R96      1      A  Q_RES       I286
  U5     AA12  GPIOY3||SALT8||WDTRST4#  AST2600A1GP  I45

BMC_CPLD_GPIO_25_R2   @SCM_LIB.SCM(SCH_1):BMC_CPLD_GPIO_25_R2
  R634     2      B  Q_RES       I362
  U25    C13  IO_89_6  10M02SCU169C8G  I330

BMC_CPLD_GPIO_2_R1   @SCM_LIB.SCM(SCH_1):BMC_CPLD_GPIO_2_R1
  R65      2      B  Q_RES       I418
  U5     A23  GPIOF7||SD1WP#||PWM15  AST2600A1GP  I45

BMC_CPLD_GPIO_2_R2   @SCM_LIB.SCM(SCH_1):BMC_CPLD_GPIO_2_R2
  R519     2      B  Q_RES       I451
  U25     G5  IO_18_CLK0N_2  10M02SCU169C8G  I394

BMC_CPLD_GPIO_3_R1   @SCM_LIB.SCM(SCH_1):BMC_CPLD_GPIO_3_R1
  R458     2      B  Q_RES       I421
  U5     E20  GPIOG5||RXD8||SD2DAT3||SALT14  AST2600A1GP  I45

BMC_CPLD_GPIO_3_R2   @SCM_LIB.SCM(SCH_1):BMC_CPLD_GPIO_3_R2
  R520     2      B  Q_RES       I453
  U25     L3  IO_32_PLL_L_CLKOUTP_2  10M02SCU169C8G  I394

BMC_CPLD_GPIO_4   @SCM_LIB.SCM(SCH_1):BMC_CPLD_GPIO_4
  R459     1      A  Q_RES       I310
  R522     2      B  Q_RES       I458
  R588     2      B  Q_RES       I45

BMC_CPLD_GPIO_4_R1   @SCM_LIB.SCM(SCH_1):BMC_CPLD_GPIO_4_R1
  R459     2      B  Q_RES       I310
  U5     AD13  SPI1CS0#  AST2600A1GP  I45

BMC_CPLD_GPIO_4_R2   @SCM_LIB.SCM(SCH_1):BMC_CPLD_GPIO_4_R2
  R522     1      A  Q_RES       I458
  U25     L4  IO_36_3  10M02SCU169C8G  I394

BMC_CPLD_GPIO_5   @SCM_LIB.SCM(SCH_1):BMC_CPLD_GPIO_5
  R460     1      A  Q_RES       I312
  R524     2      B  Q_RES       I460
  R591     2      B  Q_RES       I43

BMC_CPLD_GPIO_5_R1   @SCM_LIB.SCM(SCH_1):BMC_CPLD_GPIO_5_R1
  R460     2      B  Q_RES       I312
  U5     AC10  GPIOZ0||SPI1CS1#  AST2600A1GP  I45

BMC_CPLD_GPIO_5_R2   @SCM_LIB.SCM(SCH_1):BMC_CPLD_GPIO_5_R2
  R524     1      A  Q_RES       I460
  U25     M5  IO_37_3  10M02SCU169C8G  I394

BMC_CPLD_GPIO_6   @SCM_LIB.SCM(SCH_1):BMC_CPLD_GPIO_6
  R461     1      A  Q_RES       I314
  R525     2      B  Q_RES       I462
  R592     2      B  Q_RES       I41

BMC_CPLD_GPIO_6_R1   @SCM_LIB.SCM(SCH_1):BMC_CPLD_GPIO_6_R1
  R461     2      B  Q_RES       I314
  U5     AD14  GPIOV2||SIOPWREQ#  AST2600A1GP  I45

BMC_CPLD_GPIO_6_R2   @SCM_LIB.SCM(SCH_1):BMC_CPLD_GPIO_6_R2
  R525     1      A  Q_RES       I462
  U25     K5  IO_38_3  10M02SCU169C8G  I394

BMC_CPLD_GPIO_7   @SCM_LIB.SCM(SCH_1):BMC_CPLD_GPIO_7
  R468     2      B  Q_RES       I318
  R526     2      B  Q_RES       I464
  R593     2      B  Q_RES       I39

BMC_CPLD_GPIO_7_R1   @SCM_LIB.SCM(SCH_1):BMC_CPLD_GPIO_7_R1
  R468     1      A  Q_RES       I318
  U5     AB11  GPIOZ3||SPI1CK  AST2600A1GP  I45

BMC_CPLD_GPIO_7_R2   @SCM_LIB.SCM(SCH_1):BMC_CPLD_GPIO_7_R2
  R526     1      A  Q_RES       I464
  U25    M11  IO_58_3  10M02SCU169C8G  I394

BMC_CPLD_GPIO_8   @SCM_LIB.SCM(SCH_1):BMC_CPLD_GPIO_8
  R469     2      B  Q_RES       I319
  R531     2      B  Q_RES       I480
  R595     2      B  Q_RES       I37

BMC_CPLD_GPIO_8_R1   @SCM_LIB.SCM(SCH_1):BMC_CPLD_GPIO_8_R1
  R469     1      A  Q_RES       I319
  U5     AA11  GPIOZ5||SPI1MISO  AST2600A1GP  I45

BMC_CPLD_GPIO_8_R2   @SCM_LIB.SCM(SCH_1):BMC_CPLD_GPIO_8_R2
  R531     1      A  Q_RES       I480
  U25    L11  IO_59_3  10M02SCU169C8G  I394

BMC_CPLD_GPIO_9   @SCM_LIB.SCM(SCH_1):BMC_CPLD_GPIO_9
  R472     2      B  Q_RES       I321
  R533     2      B  Q_RES       I478
  R596     2      B  Q_RES       I35

BMC_CPLD_GPIO_9_R1   @SCM_LIB.SCM(SCH_1):BMC_CPLD_GPIO_9_R1
  R472     1      A  Q_RES       I321
  U5     AD11  GPIOZ6||SPI1DQ2||TXD13  AST2600A1GP  I45

BMC_CPLD_GPIO_9_R2   @SCM_LIB.SCM(SCH_1):BMC_CPLD_GPIO_9_R2
  R533     1      A  Q_RES       I478
  U25     J8  IO_60_3  10M02SCU169C8G  I394

BMC_DDC_BUF_EN   @SCM_LIB.SCM(SCH_1):BMC_DDC_BUF_EN
  R30      2      B  Q_RES       I39
  U26      1      1  74HC1G126GW  I33
  U33      1      1  74HC1G126GW  I32

BMC_DDC_BUF_PWR   @SCM_LIB.SCM(SCH_1):BMC_DDC_BUF_PWR
  R18      2      B  Q_RES       I19
  U26      5      5  74HC1G126GW  I33
  U33      5      5  74HC1G126GW  I32

BMC_EMMC_CD_N   @SCM_LIB.SCM(SCH_1):BMC_EMMC_CD_N
  R685     1      A  Q_RES       I124
  R687     2      B  Q_RES       I126
  U5     AC5  GPIO18D6||EMMCCD#  AST2600A1GP  I35

BMC_EMMC_CLK    @SCM_LIB.SCM(SCH_1):BMC_EMMC_CLK
  R654     1      A  Q_RES       I27
  U5     AB4  GPIO18D0||EMMCCLK  AST2600A1GP  I35

BMC_EMMC_CMD    @SCM_LIB.SCM(SCH_1):BMC_EMMC_CMD
  R48      1      A  Q_RES       I28
  U5     AA4  GPIO18D1||EMMCCMD  AST2600A1GP  I35

BMC_EMMC_DT0    @SCM_LIB.SCM(SCH_1):BMC_EMMC_DT0
  R532     1      A  Q_RES       I34
  U5     AC4  GPIO18D2||EMMCDAT0  AST2600A1GP  I35

BMC_EMMC_DT1    @SCM_LIB.SCM(SCH_1):BMC_EMMC_DT1
  R647     1      A  Q_RES       I35
  U5     AA5  GPIO18D3||EMMCDAT1  AST2600A1GP  I35

BMC_EMMC_DT2    @SCM_LIB.SCM(SCH_1):BMC_EMMC_DT2
  R648     1      A  Q_RES       I36
  U5      Y5  GPIO18D4||EMMCDAT2  AST2600A1GP  I35

BMC_EMMC_DT3    @SCM_LIB.SCM(SCH_1):BMC_EMMC_DT3
  R649     1      A  Q_RES       I29
  U5     AB5  GPIO18D5||EMMCDAT3  AST2600A1GP  I35

BMC_EMMC_DT4    @SCM_LIB.SCM(SCH_1):BMC_EMMC_DT4
  R650     1      A  Q_RES       I30
  U5      Y1  GPIO18E0||EMMCDAT4||FWSPI18CS#||VBCS#  AST2600A1GP  I35

BMC_EMMC_DT5    @SCM_LIB.SCM(SCH_1):BMC_EMMC_DT5
  R651     1      A  Q_RES       I31
  U5      Y2  GPIO18E1||EMMCDAT5||FWSPI18CK||VBCK  AST2600A1GP  I35

BMC_EMMC_DT6    @SCM_LIB.SCM(SCH_1):BMC_EMMC_DT6
  R652     1      A  Q_RES       I32
  U5      Y3  GPIO18E2||EMMCDAT6||FWSPI18MOSI||VBMOSI  AST2600A1GP  I35

BMC_EMMC_DT7    @SCM_LIB.SCM(SCH_1):BMC_EMMC_DT7
  R653     1      A  Q_RES       I33
  U5      Y4  GPIO18E3||EMMCDAT7||FWSPI18MISO||VBMISO  AST2600A1GP  I35

BMC_EMMC_RST_N   @SCM_LIB.SCM(SCH_1):BMC_EMMC_RST_N
  C230     1      A  Q_CAP       I16
  R164     2      B  Q_RES       I17
  U20     K5  RST_N  MTFC8GAKAJCN1MWT  I38

BMC_EMMC_WP_N   @SCM_LIB.SCM(SCH_1):BMC_EMMC_WP_N
  R684     1      A  Q_RES       I122
  R686     2      B  Q_RES       I125
  U5     AB6  GPIO18D7||EMMCWP#  AST2600A1GP  I35

BMC_HEARTBEAT_N   @SCM_LIB.SCM(SCH_1):BMC_HEARTBEAT_N
  D8       C      C  Q_LED       I46
  U5     Y23  GPIOP7||HBLED#||PWM15||THRUOUT3  AST2600A1GP  I41

BMC_HEARTBEAT_R_N   @SCM_LIB.SCM(SCH_1):BMC_HEARTBEAT_R_N
  D8       A      A  Q_LED       I46
  R167     2      B  Q_RES       I33

BMC_PWR_LED     @SCM_LIB.SCM(SCH_1):BMC_PWR_LED
  R316     1      A  Q_RES       I318
  U5     W23  GPIOP4||PWM12||THRUIN2  AST2600A1GP  I41

CLK_25M_OSC_FPGA   @SCM_LIB.SCM(SCH_1):CLK_25M_OSC_FPGA
  R807     2      B  Q_RES       I429
  U25     H6  IO_20_CLK0P_2  10M02SCU169C8G  I394

CLK_25M_OSC_FPGA_R   @SCM_LIB.SCM(SCH_1):CLK_25M_OSC_FPGA_R
  OSC2     3    OUT  OSC4_7X25000018  I431
  R807     1      A  Q_RES       I429

CLK_BMC_GF_DN   @SCM_LIB.SCM(SCH_1):CLK_BMC_GF_DN
  GF1    A13    A13  FCONN168_ME1016810106011  I171
  U5     AD6  PEREFCLKN  AST2600A1GP  I45

CLK_BMC_GF_DP   @SCM_LIB.SCM(SCH_1):CLK_BMC_GF_DP
  GF1    A12    A12  FCONN168_ME1016810106011  I171
  U5     AD5  PEREFCLKP  AST2600A1GP  I45

CRT_VCC5        @SCM_LIB.SCM(SCH_1):CRT_VCC5
  C204     1      A  Q_CAP       I45
  D9       C      C  SCHOTTKY_AC  I42
  D11      C      C  SCHOTTKY_AC  I41
  D12      1      1  BZA462A     I74
  D12      3      3  BZA462A     I74
  D12      4      4  BZA462A     I74
  D12      6      6  BZA462A     I74
  D16      A      A  SCHOTTKY_AC  I152
  R16      2      B  Q_RES       I75
  R17      2      B  Q_RES       I68
  R27      2      B  Q_RES       I40
  R30      1      A  Q_RES       I39
  R91      1      A  Q_RES       I62
  R92      1      A  Q_RES       I64
  U34      5    VCC  TPD4E001DBVR  I48
  U35      5    VCC  TPD4E001DBVR  I70

DEBUG_PORT_PRSNT   @SCM_LIB.SCM(SCH_1):DEBUG_PORT_PRSNT
  J2       7  GND_D  CONN9_GSB311131HR  I22
  R205     1      A  Q_RES       I79
  U23      2      A  SN74LVC1G07DBVR   I2
  U29      1      1  74HC1G126GW  I67
  U36      1      1  74HC1G126GW  I43

DEBUG_PORT_PRSNT_BUF_EN   @SCM_LIB.SCM(SCH_1):DEBUG_PORT_PRSNT_BUF_EN
  D13      5  ENABLE  PCA9517ADP   I1
  R295     2      B  Q_RES        I8
  R296     1      A  Q_RES       I11
  U23      4      Y  SN74LVC1G07DBVR   I2

DEBUG_PORT_UART_RX   @SCM_LIB.SCM(SCH_1):DEBUG_PORT_UART_RX
  J2       9  SSTX+  CONN9_GSB311131HR  I22
  R274     2      B  Q_RES       I16
  U36      2      2  74HC1G126GW  I43

DEBUG_PORT_UART_TX   @SCM_LIB.SCM(SCH_1):DEBUG_PORT_UART_TX
  J2       8  SSTX-  CONN9_GSB311131HR  I22
  R219     1      A  Q_RES       I75
  U29      4      4  74HC1G126GW  I67

DP_BMC_AUX_C_N   @SCM_LIB.SCM(SCH_1):DP_BMC_AUX_C_N
  C186     1      A  Q_CAP       I120
  D10      1      1  BZA462A     I59
  J3      18  AUX_CH_N  SCONN20_3VM11207D7307H  I127
  R10      2      B  Q_RES       I42

DP_BMC_AUX_C_P   @SCM_LIB.SCM(SCH_1):DP_BMC_AUX_C_P
  C185     1      A  Q_CAP       I119
  D10      4      4  BZA462A     I59
  J3      16  AUX_CH_P  SCONN20_3VM11207D7307H  I127
  R392     1      A  Q_RES       I35

DP_BMC_AUX_N    @SCM_LIB.SCM(SCH_1):DP_BMC_AUX_N
  C186     2      B  Q_CAP       I120
  U5     AB3  DPAUXN  AST2600A1GP  I45

DP_BMC_AUX_P    @SCM_LIB.SCM(SCH_1):DP_BMC_AUX_P
  C185     2      B  Q_CAP       I119
  U5     AC3  DPAUXP  AST2600A1GP  I45

DP_BMC_C_TX0_N   @SCM_LIB.SCM(SCH_1):DP_BMC_C_TX0_N
  C27      1      A  Q_CAP       I160
  U5     AB1  DPTXN0  AST2600A1GP  I45

DP_BMC_C_TX0_P   @SCM_LIB.SCM(SCH_1):DP_BMC_C_TX0_P
  C26      1      A  Q_CAP       I161
  U5     AC1  DPTXP0  AST2600A1GP  I45

DP_BMC_C_TX1_N   @SCM_LIB.SCM(SCH_1):DP_BMC_C_TX1_N
  C29      1      A  Q_CAP       I163
  U5     AA2  DPTXN1  AST2600A1GP  I45

DP_BMC_C_TX1_P   @SCM_LIB.SCM(SCH_1):DP_BMC_C_TX1_P
  C28      1      A  Q_CAP       I164
  U5     AB2  DPTXP1  AST2600A1GP  I45

DP_BMC_HPD_3V3   @SCM_LIB.SCM(SCH_1):DP_BMC_HPD_3V3
  D10      3      3  BZA462A     I59
  J3       2  HOTPLUG_DETECT  SCONN20_3VM11207D7307H  I127
  R391     1      A  Q_RES       I34
  U5      C7  DPHPD  AST2600A1GP  I45

DP_BMC_TX0_N    @SCM_LIB.SCM(SCH_1):DP_BMC_TX0_N
  C27      2      B  Q_CAP       I160
  J3       5  ML_LANE_0_N  SCONN20_3VM11207D7307H  I127
  U16      4    IO3  TPD4E001DBVR  I51

DP_BMC_TX0_P    @SCM_LIB.SCM(SCH_1):DP_BMC_TX0_P
  C26      2      B  Q_CAP       I161
  J3       3  ML_LANE_0_P  SCONN20_3VM11207D7307H  I127
  U16      6    IO4  TPD4E001DBVR  I51

DP_BMC_TX1_N    @SCM_LIB.SCM(SCH_1):DP_BMC_TX1_N
  C29      2      B  Q_CAP       I163
  J3      11  ML_LANE_1_N  SCONN20_3VM11207D7307H  I127
  U16      3    IO2  TPD4E001DBVR  I51

DP_BMC_TX1_P    @SCM_LIB.SCM(SCH_1):DP_BMC_TX1_P
  C28      2      B  Q_CAP       I164
  J3       9  ML_LANE_1_P  SCONN20_3VM11207D7307H  I127
  U16      1    IO1  TPD4E001DBVR  I51

DP_CONFIG1      @SCM_LIB.SCM(SCH_1):DP_CONFIG1
  J3       4  CONFIG1  SCONN20_3VM11207D7307H  I127
  R395     1      A  Q_RES       I114

DP_CONFIG2      @SCM_LIB.SCM(SCH_1):DP_CONFIG2
  J3       6  CONFIG2  SCONN20_3VM11207D7307H  I127
  R396     1      A  Q_RES       I113

EMMC_CLK_R      @SCM_LIB.SCM(SCH_1):EMMC_CLK_R
  R654     2      B  Q_RES       I27
  U20     M6    CLK  MTFC8GAKAJCN1MWT  I38

EMMC_CMD_R      @SCM_LIB.SCM(SCH_1):EMMC_CMD_R
  R48      2      B  Q_RES       I28
  R663     2      B  Q_RES       I52
  U20     M5    CMD  MTFC8GAKAJCN1MWT  I38

EMMC_DT0_R      @SCM_LIB.SCM(SCH_1):EMMC_DT0_R
  R532     2      B  Q_RES       I34
  R655     2      B  Q_RES       I59
  U20     A3   DAT0  MTFC8GAKAJCN1MWT  I38

EMMC_DT1_R      @SCM_LIB.SCM(SCH_1):EMMC_DT1_R
  R647     2      B  Q_RES       I35
  R656     2      B  Q_RES       I60
  U20     A4   DAT1  MTFC8GAKAJCN1MWT  I38

EMMC_DT2_R      @SCM_LIB.SCM(SCH_1):EMMC_DT2_R
  R648     2      B  Q_RES       I36
  R657     2      B  Q_RES       I61
  U20     A5   DAT2  MTFC8GAKAJCN1MWT  I38

EMMC_DT3_R      @SCM_LIB.SCM(SCH_1):EMMC_DT3_R
  R649     2      B  Q_RES       I29
  R658     2      B  Q_RES       I58
  U20     B2   DAT3  MTFC8GAKAJCN1MWT  I38

EMMC_DT4_R      @SCM_LIB.SCM(SCH_1):EMMC_DT4_R
  R650     2      B  Q_RES       I30
  R659     2      B  Q_RES       I57
  U20     B3   DAT4  MTFC8GAKAJCN1MWT  I38

EMMC_DT5_R      @SCM_LIB.SCM(SCH_1):EMMC_DT5_R
  R651     2      B  Q_RES       I31
  R660     2      B  Q_RES       I55
  U20     B4   DAT5  MTFC8GAKAJCN1MWT  I38

EMMC_DT6_R      @SCM_LIB.SCM(SCH_1):EMMC_DT6_R
  R652     2      B  Q_RES       I32
  R661     2      B  Q_RES       I53
  U20     B5   DAT6  MTFC8GAKAJCN1MWT  I38

EMMC_DT7_R      @SCM_LIB.SCM(SCH_1):EMMC_DT7_R
  R653     2      B  Q_RES       I33
  R662     2      B  Q_RES       I54
  U20     B6   DAT7  MTFC8GAKAJCN1MWT  I38

EN_P1V2_AUX     @SCM_LIB.SCM(SCH_1):EN_P1V2_AUX
  PU41     5     EN  NB695GDZ    I15
  R708     2      B  Q_RES       I38
  R764     2      B  Q_RES       I41

EN_P5V_AUX      @SCM_LIB.SCM(SCH_1):EN_P5V_AUX
  PC205    1      A  Q_CAP        I1
  PR521    2      B  Q_RES        I4
  PR522    1      A  Q_RES        I3
  PU38     8     EN  MPQ8633AGLEC807Z  I42

ESPI_HOST_LPC_BMC_CLK   @SCM_LIB.SCM(SCH_1):ESPI_HOST_LPC_BMC_CLK
  GF1     B1     B1  FCONN168_ME1016810106011  I171
  U5     AE7  GPIOW4||LCLK||ESPICK  AST2600A1GP  I45

ESPI_HOST_LPC_BMC_LFRAME_N   @SCM_LIB.SCM(SCH_1):ESPI_HOST_LPC_BMC_LFRAME_N
  GF1     B2     B2  FCONN168_ME1016810106011  I171
  R115     2      B  Q_RES        I4
  U5     AF7  GPIOW5||LFRAME#||ESPICS#  AST2600A1GP  I45

ESPI_LPC_D0_IO0   @SCM_LIB.SCM(SCH_1):ESPI_LPC_D0_IO0
  R128     1      A  Q_RES       I100
  U5     AB7  GPIOW0||LAD0||ESPID0  AST2600A1GP  I45

ESPI_LPC_D1_IO1   @SCM_LIB.SCM(SCH_1):ESPI_LPC_D1_IO1
  R129     1      A  Q_RES       I101
  U5     AB8  GPIOW1||LAD1||ESPID1  AST2600A1GP  I45

ESPI_LPC_D2_IO2   @SCM_LIB.SCM(SCH_1):ESPI_LPC_D2_IO2
  R130     1      A  Q_RES       I102
  U5     AC8  GPIOW2||LAD2||ESPID2  AST2600A1GP  I45

ESPI_LPC_D3_IO3   @SCM_LIB.SCM(SCH_1):ESPI_LPC_D3_IO3
  R131     1      A  Q_RES       I99
  U5     AC7  GPIOW3||LAD3||ESPID3  AST2600A1GP  I45

ESPI_LPC_LAD0_IO0   @SCM_LIB.SCM(SCH_1):ESPI_LPC_LAD0_IO0
  GF1     B5     B5  FCONN168_ME1016810106011  I171
  R128     2      B  Q_RES       I100

ESPI_LPC_LAD1_IO1   @SCM_LIB.SCM(SCH_1):ESPI_LPC_LAD1_IO1
  GF1     B6     B6  FCONN168_ME1016810106011  I171
  R129     2      B  Q_RES       I101

ESPI_LPC_LAD2_IO2   @SCM_LIB.SCM(SCH_1):ESPI_LPC_LAD2_IO2
  GF1     B7     B7  FCONN168_ME1016810106011  I171
  R130     2      B  Q_RES       I102

ESPI_LPC_LAD3_IO3   @SCM_LIB.SCM(SCH_1):ESPI_LPC_LAD3_IO3
  GF1     B8     B8  FCONN168_ME1016810106011  I171
  R131     2      B  Q_RES       I99

FM_ADR_COMPLETE   @SCM_LIB.SCM(SCH_1):FM_ADR_COMPLETE
  U5     AC24  GPIOO6||PWM6  AST2600A1GP  I41
  U25     J6  IO_46_3  10M02SCU169C8G  I394

FM_ADR_TRIGGER_N   @SCM_LIB.SCM(SCH_1):FM_ADR_TRIGGER_N
  U5     AD25  GPIOO4||PWM4  AST2600A1GP  I41
  U25    H13  IO_75_5  10M02SCU169C8G  I330

FM_BIOS_DEBUG_EN_N   @SCM_LIB.SCM(SCH_1):FM_BIOS_DEBUG_EN_N
  R112     2      B  Q_RES       I267
  U25     A6  IO_116_8  10M02SCU169C8G  I330

FM_BIOS_DEBUG_EN_R_N   @SCM_LIB.SCM(SCH_1):FM_BIOS_DEBUG_EN_R_N
  R56      2      B  Q_RES       I279
  R112     1      A  Q_RES       I267
  U5     AE11  GPIOY2||SALT7||WDTRST3#  AST2600A1GP  I45

FM_BIOS_POST_CMPLT_BMC_N   @SCM_LIB.SCM(SCH_1):FM_BIOS_POST_CMPLT_BMC_N
  U5     U26  GPIOR7||TACH15  AST2600A1GP  I41
  U25     H5  IO_22_CLK1N_2  10M02SCU169C8G  I394

FM_BMC_BIOS_MUX_CS_SPI_R_SEL_0   @SCM_LIB.SCM(SCH_1):FM_BMC_BIOS_MUX_CS_SPI_R_SEL_0
  R852     2      B  Q_RES       I357
  R866     1      A  Q_RES       I311
  U21      1      S  IDTQS3VH257PAG  I296
  U30      1      S  IDTQS3VH257PAG  I271

FM_BMC_CPU_FBRK_OUT_N   @SCM_LIB.SCM(SCH_1):FM_BMC_CPU_FBRK_OUT_N
  R242     2      B  Q_RES       I300
  U5     D23  GPIOF2||SD1DAT0||PWM10  AST2600A1GP  I45

FM_BMC_CPU_FBRK_OUT_R_N   @SCM_LIB.SCM(SCH_1):FM_BMC_CPU_FBRK_OUT_R_N
  GF1    A55    A55  FCONN168_ME1016810106011  I171
  R242     1      A  Q_RES       I300

FM_BMC_DBP_PRESENT_N   @SCM_LIB.SCM(SCH_1):FM_BMC_DBP_PRESENT_N
  R705     1      A  Q_RES       I353
  R706     2      B  Q_RES       I354
  U25     F4  IO_14_1B  10M02SCU169C8G  I394

FM_BMC_DBP_PRESENT_R_N   @SCM_LIB.SCM(SCH_1):FM_BMC_DBP_PRESENT_R_N
  R705     2      B  Q_RES       I353
  U5     B21  GPIOG7||RXD9||SD2WP#||SALT16  AST2600A1GP  I45

FM_BMC_DEBUG_SW_N   @SCM_LIB.SCM(SCH_1):FM_BMC_DEBUG_SW_N
  R11      2      B  Q_RES       I44
  R624     2      B  Q_RES       I44
  SW3      3      3  SW4S_DHNF02FTVTR  I37
  U2       6      S  SN74LVC1G3157DCKR  I20
  U3       6      S  SN74LVC1G3157DCKR  I43
  U5     R26  GPIOS4||TXD10  AST2600A1GP  I45

FM_BMC_DISABLE   @SCM_LIB.SCM(SCH_1):FM_BMC_DISABLE
  SW1      3      3  SW4S_DHNF02FTVTR   I1
  U11      3      C  BAT54C      I185

FM_BMC_EN_DET_R   @SCM_LIB.SCM(SCH_1):FM_BMC_EN_DET_R
  R846     2      B  Q_RES       I181
  U5     AA16  ADC13||GPIU5||SALT14  AST2600A1GP  I41
  U25    G13  IO_77_5  10M02SCU169C8G  I330

FM_BMC_MUX_CS_SPI_SEL_0   @SCM_LIB.SCM(SCH_1):FM_BMC_MUX_CS_SPI_SEL_0
  R852     1      A  Q_RES       I357
  U5     J23  GPIOB4||MDC2||LHCLK  AST2600A1GP  I45

FM_BMC_ONCTL_R_N   @SCM_LIB.SCM(SCH_1):FM_BMC_ONCTL_R_N
  R430     2      B  Q_RES       I188
  R821     2      B  Q_RES       I220
  U5     AC15  GPIOV3||SIOONCTRL#  AST2600A1GP  I45
  U11      1      B  BAT54C      I185
  U25    G12  IO_79_5  10M02SCU169C8G  I330

FM_BMC_READY_PLD_N   @SCM_LIB.SCM(SCH_1):FM_BMC_READY_PLD_N
  R111     2      B  Q_RES       I266
  U25     A7  IO_114_8  10M02SCU169C8G  I330

FM_BMC_READY_R_PLD_N   @SCM_LIB.SCM(SCH_1):FM_BMC_READY_R_PLD_N
  R55      2      B  Q_RES       I278
  R111     1      A  Q_RES       I266
  U5     AE14  GPIOV5||LPCPD#||LHPD#  AST2600A1GP  I45

FM_BMC_SSPRST_N   @SCM_LIB.SCM(SCH_1):FM_BMC_SSPRST_N
  R211     2      B  Q_RES       I51
  U5      D7  SSPRST#  AST2600A1GP  I41

FM_BMC_SUSACK_N   @SCM_LIB.SCM(SCH_1):FM_BMC_SUSACK_N
  R38      2      B  Q_RES       I200
  U5     AD15  GPIOV6||LPCPME#  AST2600A1GP  I45

FM_CPU_MSMI_CATERR_LVT3_N   @SCM_LIB.SCM(SCH_1):FM_CPU_MSMI_CATERR_LVT3_N
  R121     1      A  Q_RES       I239
  R163     2      B  Q_RES       I212
  R270     1      A  Q_RES       I387

FM_CPU_MSMI_CATERR_LVT3_PLD_N   @SCM_LIB.SCM(SCH_1):FM_CPU_MSMI_CATERR_LVT3_PLD_N
  R270     2      B  Q_RES       I387
  U25     J5  IO_40_3  10M02SCU169C8G  I394

FM_CPU_RMCA_CATERR_LVT3_R_N   @SCM_LIB.SCM(SCH_1):FM_CPU_RMCA_CATERR_LVT3_R_N
  R121     2      B  Q_RES       I239
  U5     E22  GPIOF1||SD1CMD||PWM9  AST2600A1GP  I45

FM_DBP_BMC_PRDY_N   @SCM_LIB.SCM(SCH_1):FM_DBP_BMC_PRDY_N
  GF1    A50    A50  FCONN168_ME1016810106011  I171
  R237     1      A  Q_RES       I156

FM_DBP_BMC_PRDY_R_N   @SCM_LIB.SCM(SCH_1):FM_DBP_BMC_PRDY_R_N
  R237     2      B  Q_RES       I156
  U5     C12  GPIOM5||NRTS1  AST2600A1GP  I45

FM_DBP_CPU_PREQ_GF_N   @SCM_LIB.SCM(SCH_1):FM_DBP_CPU_PREQ_GF_N
  R158     2      B  Q_RES       I16
  U5     C15  GPIOL4||TXD3  AST2600A1GP  I45

FM_DBP_CPU_PREQ_GF_R_N   @SCM_LIB.SCM(SCH_1):FM_DBP_CPU_PREQ_GF_R_N
  GF1    A49    A49  FCONN168_ME1016810106011  I171
  R158     1      A  Q_RES       I16

FM_ESPI_PLD_EN   @SCM_LIB.SCM(SCH_1):FM_ESPI_PLD_EN
  R444     1      A  Q_RES       I306
  R833     1      A  Q_RES       I312

FM_ESPI_PLD_R1_EN   @SCM_LIB.SCM(SCH_1):FM_ESPI_PLD_R1_EN
  R444     2      B  Q_RES       I306
  U5     H25  GPIOB6||TXD4||LHSIRQ#  AST2600A1GP  I45

FM_ESPI_PLD_R_EN   @SCM_LIB.SCM(SCH_1):FM_ESPI_PLD_R_EN
  R833     2      B  Q_RES       I312
  U25    J12  IO_70_5  10M02SCU169C8G  I330

FM_ID_LED_N     @SCM_LIB.SCM(SCH_1):FM_ID_LED_N
  Q12      4     S2  MOSFET_DUAL_6P  I105
  R502     2      B  Q_RES       I112
  U5     G26  GPIOB5||MDIO2||LHFRAME#  AST2600A1GP  I45

FM_INTRUDER_HDR_PCH_N   @SCM_LIB.SCM(SCH_1):FM_INTRUDER_HDR_PCH_N
  GF1    A54    A54  FCONN168_ME1016810106011  I171
  R440     2      B  Q_RES       I506

FM_INTRUDER_HDR_PCH_R_N   @SCM_LIB.SCM(SCH_1):FM_INTRUDER_HDR_PCH_R_N
  R440     1      A  Q_RES       I506
  R441     2      B  Q_RES       I415
  U5     R24  GPIOS3||OSCCLK  AST2600A1GP  I45

FM_JTAG_TCK_MUX_BMC_SEL   @SCM_LIB.SCM(SCH_1):FM_JTAG_TCK_MUX_BMC_SEL
  R159     1      A  Q_RES       I17
  R616     2      B  Q_RES       I36
  R620     1      A  Q_RES       I33
  U25     E4  IO_6_1A  10M02SCU169C8G  I394

FM_JTAG_TCK_MUX_BMC_SEL_R   @SCM_LIB.SCM(SCH_1):FM_JTAG_TCK_MUX_BMC_SEL_R
  R616     1      A  Q_RES       I36
  SW1      4      4  SW4S_DHNF02FTVTR   I1

FM_JTAG_TCK_MUX_BMC_SEL_R1   @SCM_LIB.SCM(SCH_1):FM_JTAG_TCK_MUX_BMC_SEL_R1
  R159     2      B  Q_RES       I17
  U5     F15  GPIOL5||RXD3  AST2600A1GP  I45

FM_MASTER_MB_N   @SCM_LIB.SCM(SCH_1):FM_MASTER_MB_N
  R845     2      B  Q_RES       I178
  U5     AC16  ADC12||GPIU4||SALT13  AST2600A1GP  I41
  U25     H9  IO_76_5  10M02SCU169C8G  I330

FM_MB_STBY_EN   @SCM_LIB.SCM(SCH_1):FM_MB_STBY_EN
  GF1    A45    A45  FCONN168_ME1016810106011  I171
  R105     2      B  Q_RES       I78
  R114     1      A  Q_RES       I385
  R618     2      B  Q_RES       I211

FM_MB_STBY_R_EN   @SCM_LIB.SCM(SCH_1):FM_MB_STBY_R_EN
  R114     2      B  Q_RES       I385
  U25     L5  IO_34_3  10M02SCU169C8G  I394

FM_ME_BT_DONE   @SCM_LIB.SCM(SCH_1):FM_ME_BT_DONE
  R266     2      B  Q_RES       I95
  U5     J26  GPIOB0||SALT1||LHAD0  AST2600A1GP  I45
  U25     J1  IO_19_2  10M02SCU169C8G  I394

FM_PCHHOT_R_N   @SCM_LIB.SCM(SCH_1):FM_PCHHOT_R_N
  U5     AD16  ADC14||GPIU6||SALT15  AST2600A1GP  I41
  U25     H8  IO_78_5  10M02SCU169C8G  I330

FM_PCH_BMC_THERMTRIP_N   @SCM_LIB.SCM(SCH_1):FM_PCH_BMC_THERMTRIP_N
  R62      2      B  Q_RES       I350
  R763     1      A  Q_RES       I243
  U25     H4  IO_24_CLK1P_2  10M02SCU169C8G  I394

FM_PCIE_M2_SSD0_PRSNT_N   @SCM_LIB.SCM(SCH_1):FM_PCIE_M2_SSD0_PRSNT_N
  U5     AD23  GPIOO2||PWM2  AST2600A1GP  I41
  U25     J2  IO_21_2  10M02SCU169C8G  I394

FM_PECI_SEL_N   @SCM_LIB.SCM(SCH_1):FM_PECI_SEL_N
  R439     1      A  Q_RES       I227
  R446     2      B  Q_RES       I299
  U25     L1  IO_27_VREFB2N0_2  10M02SCU169C8G  I394

FM_PECI_SEL_R_N   @SCM_LIB.SCM(SCH_1):FM_PECI_SEL_R_N
  R439     2      B  Q_RES       I227
  U5     E14  GPIOM3||NRI1  AST2600A1GP  I45

FM_PLT_BMC_THERMTRIP_N_R   @SCM_LIB.SCM(SCH_1):FM_PLT_BMC_THERMTRIP_N_R
  R763     2      B  Q_RES       I243
  U5     A21  GPIOG4||TXD8||SD2DAT2||SALT13  AST2600A1GP  I45

FM_PMBUS_ALERT_EN   @SCM_LIB.SCM(SCH_1):FM_PMBUS_ALERT_EN
  U5     AD26  GPIOO0||PWM0  AST2600A1GP  I41
  U25     J9  IO_72_5  10M02SCU169C8G  I330

FM_PRSNT_0_R_N   @SCM_LIB.SCM(SCH_1):FM_PRSNT_0_R_N
  GF1    OB3    OB3  FCONN168_ME1016810106011  I171
  R822     2      B  Q_RES       I456

FM_PRSNT_1_N    @SCM_LIB.SCM(SCH_1):FM_PRSNT_1_N
  GF1    A57    A57  FCONN168_ME1016810106011  I171
  R822     1      A  Q_RES       I456

FM_PWR_BTN      @SCM_LIB.SCM(SCH_1):FM_PWR_BTN
  R225     1      A  Q_RES       I290
  R432     2      B  Q_RES       I290
  U5     AB22  GPIOP0||PWM8||THRUIN0  AST2600A1GP  I41

FM_PWR_R_BTN    @SCM_LIB.SCM(SCH_1):FM_PWR_R_BTN
  R432     1      A  Q_RES       I290
  U25    A10  IO_107_8  10M02SCU169C8G  I330

FM_RISER1_JTAG_SEL_N   @SCM_LIB.SCM(SCH_1):FM_RISER1_JTAG_SEL_N
  R404     2      B  Q_RES       I269
  U25     B6  IO_117_8  10M02SCU169C8G  I330

FM_RISER1_JTAG_SEL_R_N   @SCM_LIB.SCM(SCH_1):FM_RISER1_JTAG_SEL_R_N
  R57      2      B  Q_RES       I280
  R404     1      A  Q_RES       I269
  U5     P23  GPIOS6||TXD11  AST2600A1GP  I45

FM_RISER2_JTAG_SEL_N   @SCM_LIB.SCM(SCH_1):FM_RISER2_JTAG_SEL_N
  R90      2      B  Q_RES       I287
  U25     A4  IO_118_8  10M02SCU169C8G  I330

FM_RISER2_JTAG_SEL_R_N   @SCM_LIB.SCM(SCH_1):FM_RISER2_JTAG_SEL_R_N
  R58      2      B  Q_RES       I281
  R90      1      A  Q_RES       I287
  U5     T24  GPIOS7||RXD11  AST2600A1GP  I45

FM_SLPS3_GF_N   @SCM_LIB.SCM(SCH_1):FM_SLPS3_GF_N
  R773     1      A  Q_RES       I314
  R774     2      B  Q_RES       I213
  U5     AB15  GPIOV0||SIOS3#  AST2600A1GP  I45

FM_SLPS3_GF_R_N   @SCM_LIB.SCM(SCH_1):FM_SLPS3_GF_R_N
  R773     2      B  Q_RES       I314
  U25    K12  IO_68_5  10M02SCU169C8G  I330

FM_SPD_REMOTE_EN_R   @SCM_LIB.SCM(SCH_1):FM_SPD_REMOTE_EN_R
  U5     AC23  GPIOO7||PWM7  AST2600A1GP  I41
  U25    M13  IO_54_3  10M02SCU169C8G  I394

FM_THERMTRIP_DLY_LVC1_R_N   @SCM_LIB.SCM(SCH_1):FM_THERMTRIP_DLY_LVC1_R_N
  U5     T26  GPIOS2||PEWAKE#  AST2600A1GP  I45
  U25     K7  IO_52_3  10M02SCU169C8G  I394

FM_THROTTLE_N   @SCM_LIB.SCM(SCH_1):FM_THROTTLE_N
  R45      2      B  Q_RES       I176
  R769     1      A  Q_RES       I315
  U5     B16  GPIOI6||SIOPBI#  AST2600A1GP  I45

FM_THROTTLE_R_N   @SCM_LIB.SCM(SCH_1):FM_THROTTLE_R_N
  R769     2      B  Q_RES       I315
  U25    K13  IO_71_VREFB5N0_5  10M02SCU169C8G  I330

FM_TPM_PRSNT_0_N   @SCM_LIB.SCM(SCH_1):FM_TPM_PRSNT_0_N
  J5       8      8  SCONN11_9192031111LF  I56
  R464     2      B  Q_RES       I75
  R767     1      A  Q_RES       I403

FM_TPM_PRSNT_0_R_N   @SCM_LIB.SCM(SCH_1):FM_TPM_PRSNT_0_R_N
  R767     2      B  Q_RES       I403
  U25     D1  IO_0_1A  10M02SCU169C8G  I394

FM_TPM_PRSNT_1_N   @SCM_LIB.SCM(SCH_1):FM_TPM_PRSNT_1_N
  J10      8      8  SCONN11_9192031111LF  I113
  R50      2      B  Q_RES       I104
  R123     1      A  Q_RES       I404

FM_TPM_PRSNT_1_R_N   @SCM_LIB.SCM(SCH_1):FM_TPM_PRSNT_1_R_N
  R123     2      B  Q_RES       I404
  U25     C1  IO_1_1A  10M02SCU169C8G  I394

FM_VIRTUAL_RESEAT   @SCM_LIB.SCM(SCH_1):FM_VIRTUAL_RESEAT
  GF1    OA14   OA14  FCONN168_ME1016810106011  I171
  R823     2      B  Q_RES       I234
  R824     1      A  Q_RES       I223

FM_VIRTUAL_RESEAT_BMC   @SCM_LIB.SCM(SCH_1):FM_VIRTUAL_RESEAT_BMC
  R824     2      B  Q_RES       I223
  U5     B13  GPIOM1||NDCD1  AST2600A1GP  I45

FRU_E0          @SCM_LIB.SCM(SCH_1):FRU_E0
  R12      2      B  Q_RES        I9
  R411     1      A  Q_RES        I6
  U19      1     E0  M24128BWDW6TP  I15

FRU_E1          @SCM_LIB.SCM(SCH_1):FRU_E1
  R13      2      B  Q_RES       I11
  R412     1      A  Q_RES        I8
  U19      2     E1  M24128BWDW6TP  I15

FRU_E2          @SCM_LIB.SCM(SCH_1):FRU_E2
  R14      2      B  Q_RES       I14
  R413     1      A  Q_RES       I12
  U19      3     E2  M24128BWDW6TP  I15

GND             @SCM_LIB.SCM(SCH_1):GND
  C1       2      B  Q_CAP        I4
  C2       2      B  Q_CAP        I5
  C3       2      B  Q_CAP        I6
  C4       2      B  Q_CAP        I7
  C5       2      B  Q_CAP       I23
  C6       2      B  Q_CAP       I19
  C7       2      B  Q_CAP       I24
  C8       2      B  Q_CAP       I21
  C9       2      B  Q_CAP       I25
  C10      2      B  Q_CAP       I85
  C11      2      B  Q_CAP       I26
  C12      2      B  Q_CAP       I106
  C13      2      B  Q_CAP       I186
  C14      2      B  Q_CAP       I187
  C15      2      B  Q_CAP       I134
  C16      2      B  Q_CAP       I113
  C17      2      B  Q_CAP       I190
  C18      2      B  Q_CAP       I192
  C19      2      B  Q_CAP       I21
  C20      2      B  Q_CAP       I47
  C21      2      B  Q_CAP       I24
  C22      2      B  Q_CAP       I27
  C23      2      B  Q_CAP       I28
  C30      2      B  Q_CAP       I29
  C31      2      B  Q_CAP       I30
  C32      2      B  Q_CAP       I31
  C33      2      B  Q_CAP       I32
  C34      2      B  Q_CAP       I42
  C35      2      B  Q_CAP       I14
  C36      2      B  Q_CAP       I16
  C37      2      B  Q_CAP       I24
  C38      2      B  Q_CAP       I36
  C39      2      B  Q_CAP       I37
  C40      2      B  Q_CAP       I67
  C41      2      B  Q_CAP       I68
  C42      2      B  Q_CAP       I117
  C43      2      B  Q_CAP       I119
  C44      2      B  Q_CAP       I88
  C45      2      B  Q_CAP       I89
  C46      2      B  Q_CAP       I122
  C47      2      B  Q_CAP       I128
  C48      2      B  Q_CAP       I148
  C49      2      B  Q_CAP       I118
  C50      2      B  Q_CAP       I126
  C51      2      B  Q_CAP       I145
  C52      2      B  Q_CAP       I31
  C53      2      B  Q_CAP       I135
  C54      2      B  Q_CAP       I32
  C55      2      B  Q_CAP       I23
  C56      2      B  Q_CAP       I33
  C57      2      B  Q_CAP       I133
  C58      2      B  Q_CAP       I52
  C59      2      B  Q_CAP       I79
  C60      2      B  Q_CAP       I141
  C61      2      B  Q_CAP       I55
  C62      2      B  Q_CAP       I53
  C63      2      B  Q_CAP       I46
  C64      2      B  Q_CAP       I81
  C65      2      B  Q_CAP       I139
  C66      2      B  Q_CAP       I54
  C67      2      B  Q_CAP       I48
  C68      2      B  Q_CAP       I82
  C69      2      B  Q_CAP       I59
  C70      2      B  Q_CAP       I57
  C71      2      B  Q_CAP       I49
  C72      2      B  Q_CAP       I58
  C73      2      B  Q_CAP       I51
  C74      2      B  Q_CAP       I66
  C75      2      B  Q_CAP       I93
  C76      2      B  Q_CAP       I183
  C77      2      B  Q_CAP       I100
  C78      2      B  Q_CAP       I160
  C79      2      B  Q_CAP       I157
  C80      2      B  Q_CAP       I153
  C81      2      B  Q_CAP       I151
  C82      2      B  Q_CAP       I180
  C83      2      B  Q_CAP       I106
  C84      2      B  Q_CAP       I179
  C85      2      B  Q_CAP       I120
  C86      2      B  Q_CAP       I149
  C87      2      B  Q_CAP       I147
  C88      2      B  Q_CAP       I123
  C89      2      B  Q_CAP       I118
  C90      2      B  Q_CAP       I173
  C91      2      B  Q_CAP       I151
  C92      2      B  Q_CAP       I150
  C93      2      B  Q_CAP       I148
  C94      2      B  Q_CAP       I124
  C95      2      B  Q_CAP       I119
  C96      2      B  Q_CAP       I178
  C97      2      B  Q_CAP       I169
  C98      2      B  Q_CAP       I163
  C99      2      B  Q_CAP       I154
  C100     2      B  Q_CAP       I152
  C101     2      B  Q_CAP       I132
  C102     2      B  Q_CAP       I126
  C103     2      B  Q_CAP       I164
  C104     2      B  Q_CAP       I155
  C105     2      B  Q_CAP       I153
  C106     2      B  Q_CAP       I127
  C107     2      B  Q_CAP       I165
  C108     2      B  Q_CAP       I157
  C109     2      B  Q_CAP       I156
  C110     2      B  Q_CAP       I133
  C111     2      B  Q_CAP       I128
  C112     2      B  Q_CAP       I166
  C113     2      B  Q_CAP       I160
  C114     2      B  Q_CAP       I158
  C115     2      B  Q_CAP       I135
  C116     2      B  Q_CAP       I129
  C117     2      B  Q_CAP       I167
  C118     2      B  Q_CAP       I162
  C119     2      B  Q_CAP       I159
  C120     2      B  Q_CAP       I136
  C121     2      B  Q_CAP       I131
  C122     2      B  Q_CAP       I168
  C123     2      B  Q_CAP       I171
  C124     2      B  Q_CAP       I169
  C125     2      B  Q_CAP       I145
  C126     2      B  Q_CAP       I143
  C127     2      B  Q_CAP       I173
  C128     2      B  Q_CAP       I165
  C129     2      B  Q_CAP       I174
  C130     2      B  Q_CAP       I163
  C131     2      B  Q_CAP       I176
  C132     2      B  Q_CAP       I177
  C133     1      A  Q_CAP       I104
  C134     1      A  Q_CAP       I106
  C135     1      A  Q_CAP       I107
  C136     1      A  Q_CAP       I110
  C139     2      B  Q_CAP       I98
  C140     2      B  Q_CAP       I97
  C141     2      B  Q_CAP       I206
  C142     1      A  Q_CAP       I28
  C143     2      B  Q_CAP       I108
  C144     2      B  Q_CAP       I102
  C145     2      B  Q_CAP       I201
  C146     2      B  Q_CAP       I292
  C147     2      B  Q_CAP       I17
  C148     2      B  Q_CAP       I48
  C149     2      B  Q_CAP       I17
  C150     2      B  Q_CAP       I49
  C151     2      B  Q_CAP       I93
  C152     2      B  Q_CAP       I87
  C153     2      B  Q_CAP       I64
  C154     2      B  Q_CAP       I100
  C155     2      B  Q_CAP       I52
  C156     2      B  Q_CAP       I51
  C157     2      B  Q_CAP        I3
  C158     2      B  Q_CAP       I18
  C159     2      B  Q_CAP       I15
  C160     2      B  Q_CAP       I48
  C162     2      B  Q_CAP       I51
  C163     2      B  Q_CAP       I125
  C164     2      B  Q_CAP       I124
  C165     2      B  Q_CAP       I78
  C166     2      B  Q_CAP       I69
  C167     2      B  Q_CAP       I66
  C168     2      B  Q_CAP       I32
  C170     2      B  Q_CAP       I33
  C171     2      B  Q_CAP       I38
  C172     2      B  Q_CAP       I35
  C173     2      B  Q_CAP       I24
  C174     2      B  Q_CAP       I503
  C175     2      B  Q_CAP       I114
  C177     2      B  Q_CAP       I34
  C178     2      B  Q_CAP       I31
  C179     2      B  Q_CAP       I30
  C180     2      B  Q_CAP        I6
  C181     2      B  Q_CAP       I13
  C182     2      B  Q_CAP        I8
  C183     2      B  Q_CAP       I102
  C184     2      B  Q_CAP       I101
  C187     2      B  Q_CAP       I93
  C188     2      B  Q_CAP       I79
  C189     2      B  Q_CAP       I78
  C190     2      B  Q_CAP       I76
  C191     2      B  Q_CAP       I25
  C192     2      B  Q_CAP       I17
  C193     2      B  Q_CAP       I17
  C194     2      B  Q_CAP       I13
  C195     2      B  Q_CAP       I11
  C196     2      B  Q_CAP       I109
  C197     2      B  Q_CAP       I96
  C198     2      B  Q_CAP       I44
  C199     2      B  Q_CAP       I55
  C200     2      B  Q_CAP       I43
  C201     2      B  Q_CAP       I51
  C202     2      B  Q_CAP       I11
  C203     2      B  Q_CAP       I12
  C204     2      B  Q_CAP       I45
  C205     2      B  Q_CAP       I25
  C206     2      B  Q_CAP       I26
  C207     2      B  Q_CAP       I29
  C208     2      B  Q_CAP       I30
  C209     2      B  Q_CAP       I54
  C210     2      B  Q_CAP       I55
  C211     2      B  Q_CAP       I67
  C212     2      B  Q_CAP       I77
  C213     2      B  Q_CAP       I83
  C214     2      B  Q_CAP       I84
  C215     2      B  Q_CAP       I22
  C217     2      B  Q_CAP       I21
  C220     2      B  Q_CAP       I35
  C221     2      B  Q_CAP       I199
  C222     2      B  Q_CAP       I198
  C223     2      B  Q_CAP       I46
  C224     2      B  Q_CAP       I180
  C225     2      B  Q_CAP       I197
  C226     2      B  Q_CAP       I71
  C227     2      B  Q_CAP       I72
  C228     2      B  Q_CAP       I73
  C230     2      B  Q_CAP       I16
  C231     2      B  Q_CAP        I2
  C232     2      B  Q_CAP       I20
  C233     2      B  Q_CAP       I21
  C234     2      B  Q_CAP       I23
  C235     2      B  Q_CAP       I24
  C240     2      B  Q_CAP       I63
  C241     2      B  Q_CAP       I113
  C244     2      B  Q_CAP       I42
  C246     2      B  Q_CAP       I45
  C248     2      B  Q_CAP       I69
  C249     2      B  Q_CAP       I67
  C251     2      B  Q_CAP       I66
  C252     2      B  Q_CAP       I73
  C253     2      B  Q_CAP       I57
  C255     2      B  Q_CAP       I278
  C256     2      B  Q_CAP       I29
  C257     2      B  Q_CAP       I21
  C258     2      B  Q_CAP       I40
  C259     2      B  Q_CAP       I35
  C262     2      B  Q_CAP       I116
  C263     2      B  Q_CAP       I54
  C264     2      B  Q_CAP       I59
  C265     2      B  Q_CAP       I157
  C266     2      B  Q_CAP       I52
  C267     2      B  Q_CAP       I166
  C268     2      B  Q_CAP       I241
  C269     2      B  Q_CAP       I49
  C270     2      B  Q_CAP       I239
  C272     2      B  Q_CAP       I42
  C273     2      B  Q_CAP       I234
  C274     2      B  Q_CAP       I48
  C275     2      B  Q_CAP       I180
  C277     2      B  Q_CAP       I253
  C278     2      B  Q_CAP       I47
  C279     2      B  Q_CAP       I255
  C281     2      B  Q_CAP       I38
  C282     2      B  Q_CAP       I252
  C284     2      B  Q_CAP       I250
  C287     2      B  Q_CAP       I33
  C288     2      B  Q_CAP       I150
  C289     2      B  Q_CAP       I46
  C290     2      B  Q_CAP       I201
  C293     2      B  Q_CAP       I156
  C295     2      B  Q_CAP       I207
  C297     2      B  Q_CAP       I165
  C298     2      B  Q_CAP       I45
  C299     2      B  Q_CAP       I215
  C301     2      B  Q_CAP       I159
  C302     2      B  Q_CAP       I44
  C303     2      B  Q_CAP       I235
  C305     2      B  Q_CAP       I170
  C306     2      B  Q_CAP       I43
  C307     2      B  Q_CAP       I240
  C308     2      B  Q_CAP       I28
  C309     2      B  Q_CAP       I247
  C310     2      B  Q_CAP       I26
  C311     2      B  Q_CAP       I256
  C312     2      B  Q_CAP       I19
  C313     2      B  Q_CAP       I25
  C314     2      B  Q_CAP       I259
  C315     2      B  Q_CAP       I15
  C317     2      B  Q_CAP       I23
  C318     2      B  Q_CAP       I433
  C319     2      B  Q_CAP       I14
  C320     2      B  Q_CAP       I22
  C321     2      B  Q_CAP       I95
  C323     2      B  Q_CAP       I21
  C324     2      B  Q_CAP       I122
  C326     2      B  Q_CAP       I133
  C327     2      B  Q_CAP       I32
  C328     2      B  Q_CAP       I166
  C329     2      B  Q_CAP       I449
  C330     2      B  Q_CAP       I448
  C331     2      B  Q_CAP       I160
  C332     2      B  Q_CAP       I171
  C333     2      B  Q_CAP       I115
  C334     2      B  Q_CAP       I154
  C339     2      B  Q_CAP       I31
  C340     2      B  Q_CAP       I20
  C341     2      B  Q_CAP       I41
  C342     2      B  Q_CAP       I39
  C343     2      B  Q_CAP       I37
  C344     2      B  Q_CAP       I36
  C345     2      B  Q_CAP       I32
  C346     2      B  Q_CAP       I211
  C347     2      B  Q_CAP       I168
  C348     2      B  Q_CAP       I163
  C349     2      B  Q_CAP       I212
  C350     2      B  Q_CAP       I178
  D10      2      2  BZA462A     I59
  D10      5      5  BZA462A     I59
  D12      2      2  BZA462A     I74
  D12      5      5  BZA462A     I74
  D13      4    GND  PCA9517ADP   I1
  GF1    A11    A11  FCONN168_ME1016810106011  I171
  GF1    A14    A14  FCONN168_ME1016810106011  I171
  GF1    A17    A17  FCONN168_ME1016810106011  I171
  GF1    A20    A20  FCONN168_ME1016810106011  I171
  GF1    A33    A33  FCONN168_ME1016810106011  I171
  GF1    A42    A42  FCONN168_ME1016810106011  I171
  GF1    A43    A43  FCONN168_ME1016810106011  I171
  GF1    A58    A58  FCONN168_ME1016810106011  I171
  GF1    A61    A61  FCONN168_ME1016810106011  I171
  GF1    A64    A64  FCONN168_ME1016810106011  I171
  GF1    A67    A67  FCONN168_ME1016810106011  I171
  GF1    A70    A70  FCONN168_ME1016810106011  I171
  GF1    B10    B10  FCONN168_ME1016810106011  I171
  GF1    B17    B17  FCONN168_ME1016810106011  I171
  GF1    B26    B26  FCONN168_ME1016810106011  I171
  GF1    B33    B33  FCONN168_ME1016810106011  I171
  GF1    B38    B38  FCONN168_ME1016810106011  I171
  GF1    B43    B43  FCONN168_ME1016810106011  I171
  GF1    B52    B52  FCONN168_ME1016810106011  I171
  GF1    B55    B55  FCONN168_ME1016810106011  I171
  GF1    B58    B58  FCONN168_ME1016810106011  I171
  GF1    B61    B61  FCONN168_ME1016810106011  I171
  GF1    B64    B64  FCONN168_ME1016810106011  I171
  GF1    B67    B67  FCONN168_ME1016810106011  I171
  GF1    B70    B70  FCONN168_ME1016810106011  I171
  GF1    OA3    OA3  FCONN168_ME1016810106011  I171
  GF1    OA4    OA4  FCONN168_ME1016810106011  I171
  GF1    OA13   OA13  FCONN168_ME1016810106011  I171
  GF1    OB4    OB4  FCONN168_ME1016810106011  I171
  GF1    OB7    OB7  FCONN168_ME1016810106011  I171
  GF1    OB10   OB10  FCONN168_ME1016810106011  I171
  H1       1      1  HOLE        I79
  H2       1      1  HOLE        I110
  H5       1      1  HOLE        I35
  H6       1      1  HOLE        I32
  H7       1      1  HOLE        I30
  H9       1      1  HOLE        I36
  J1      G1     G1  SCONN14_RS6QU0001  I95
  J1      G2     G2  SCONN14_RS6QU0001  I95
  J2       4    GND  CONN9_GSB311131HR  I22
  J2      G1     G1  CONN9_GSB311131HR  I22
  J2      G2     G2  CONN9_GSB311131HR  I22
  J3       1  GND_1  SCONN20_3VM11207D7307H  I127
  J3       7  GND_7  SCONN20_3VM11207D7307H  I127
  J3       8  GND_8  SCONN20_3VM11207D7307H  I127
  J3      13  GND_13  SCONN20_3VM11207D7307H  I127
  J3      14  GND_14  SCONN20_3VM11207D7307H  I127
  J3      19  GND_19  SCONN20_3VM11207D7307H  I127
  J3      G1     G1  SCONN20_3VM11207D7307H  I127
  J3      G2     G2  SCONN20_3VM11207D7307H  I127
  J3      G3     G3  SCONN20_3VM11207D7307H  I127
  J3      G4     G4  SCONN20_3VM11207D7307H  I127
  J4       4     ID  SCONN5_2UB2141000111F  I83
  J4       5    GND  SCONN5_2UB2141000111F  I83
  J4      G1     G1  SCONN5_2UB2141000111F  I83
  J4      G2     G2  SCONN5_2UB2141000111F  I83
  J4      G3     G3  SCONN5_2UB2141000111F  I83
  J4      G4     G4  SCONN5_2UB2141000111F  I83
  J5      11     11  SCONN11_9192031111LF  I56
  J5      G1     G1  SCONN11_9192031111LF  I56
  J5      G2     G2  SCONN11_9192031111LF  I56
  J6       2      2  CONN3_210P9103GBR1  I109
  J7       7      7  CONN7_4400547  I53
  J8       2      2  SCONN13_502240130C001  I151
  J8       4      4  SCONN13_502240130C001  I151
  J8       6      6  SCONN13_502240130C001  I151
  J8       8      8  SCONN13_502240130C001  I151
  J8      10     10  SCONN13_502240130C001  I151
  J8      G1     G1  SCONN13_502240130C001  I151
  J8      G2     G2  SCONN13_502240130C001  I151
  J10     11     11  SCONN11_9192031111LF  I113
  J10     G1     G1  SCONN11_9192031111LF  I113
  J10     G2     G2  SCONN11_9192031111LF  I113
  J40     10    GND  SCONN16_ACASPI006P06  I53
  J121    10    GND  SCONN16_ACASPI006P06  I97
  OSC1     2    GND  OSC4_7X25000018  I39
  OSC2     2    GND  OSC4_7X25000018  I431
  PC205    2      B  Q_CAP        I1
  PC206    2      B  Q_CAP       I47
  PC207    2      B  Q_CAP       I48
  PC208    2      B  Q_CAP       I13
  PC210    2      B  Q_CAP       I45
  PC212    2      B  Q_CAP       I31
  PC213    2      B  Q_CAP       I32
  PC214    2      B  Q_CAP       I33
  PC215    2      B  Q_CAP       I36
  PC217    2      B  Q_CAP       I37
  PC218    2      B  Q_CAP       I81
  PC219    2      B  Q_CAP       I80
  PC221    2      B  Q_CAP        I9
  PC223    2      B  Q_CAP       I11
  PC225    2      B  Q_CAP       I23
  PC226    2      B  Q_CAP       I35
  PC227    2      B  Q_CAP       I36
  PC228    2      B  Q_CAP       I37
  PC229    2      B  Q_CAP       I38
  PC233    2      B  Q_CAP       I15
  PC235    2      B  Q_CAP       I53
  PC237    2      B  Q_CAP       I52
  PC242    2      B  Q_CAP       I63
  PC243    2      B  Q_CAP       I57
  PC248    2      B  Q_CAP       I65
  PC249    2      B  Q_CAP       I66
  PC250    2      B  Q_CAP        I7
  PC251    2      B  Q_CAP       I43
  PC252    2      B  Q_CAP       I42
  PC253    2      B  Q_CAP       I16
  PC255    2      B  Q_CAP       I23
  PC256    2      B  Q_CAP       I24
  PC257    2      B  Q_CAP       I25
  PC258    2      B  Q_CAP       I28
  PC259    2      B  Q_CAP       I29
  PC260    2      B  Q_CAP        I7
  PC261    2      B  Q_CAP       I44
  PC262    2      B  Q_CAP       I43
  PC263    2      B  Q_CAP       I16
  PC266    2      B  Q_CAP       I23
  PC267    2      B  Q_CAP       I24
  PC268    2      B  Q_CAP       I25
  PC269    2      B  Q_CAP       I28
  PC270    2      B  Q_CAP       I29
  PC271    2      B  Q_CAP       I22
  PC273    2      B  Q_CAP       I86
  PC307    2      B  Q_CAP       I51
  PR245    2      B  Q_RES       I43
  PR276    1      A  Q_RES       I87
  PR496    2      B  Q_RES        I6
  PR522    2      B  Q_RES        I3
  PR525    2      B  Q_RES        I9
  PR526    2      B  Q_RES       I26
  PR530    1      A  Q_RES       I17
  PR532    1      A  Q_RES       I88
  PR543    2      B  Q_RES        I6
  PU1      1  PGND1  MPQ8626GDZ  I82
  PU1      7   AGND  MPQ8626GDZ  I82
  PU1     14  PGND2  MPQ8626GDZ  I82
  PU38   11_18   PGND  MPQ8633AGLEC807Z  I42
  PU38     2   AGND  MPQ8633AGLEC807Z  I42
  PU38     4   MODE  MPQ8633AGLEC807Z  I42
  PU38     6   RGND  MPQ8633AGLEC807Z  I42
  PU39    TH     EP  RT9059GQW   I60
  PU40    TH     EP  RT9059GQW   I96
  PU41     2   PGND  NB695GDZ    I15
  PU41     3     C1  NB695GDZ    I15
  PU41     4     C0  NB695GDZ    I15
  PU41    11   AGND  NB695GDZ    I15
  PU42     2   PGND  NB695GDZ    I15
  PU42     4     C0  NB695GDZ    I15
  PU42    11   AGND  NB695GDZ    I15
  Q1       E      2  MMBT39047F   I2
  Q3       E      2  MMBT39047F   I4
  Q9       S  SOURCE  MOSFET_N_GSD  I235
  Q10      S  SOURCE  MOSFET_N_GSD  I227
  Q12      1     S1  MOSFET_DUAL_6P  I105
  R2       2      B  Q_RES       I13
  R3       2      B  Q_RES       I17
  R4       2      B  Q_RES       I141
  R5       2      B  Q_RES       I142
  R6       2      B  Q_RES       I143
  R15      2      B  Q_RES       I32
  R22      2      B  Q_RES       I151
  R23      2      B  Q_RES       I150
  R25      2      B  Q_RES       I149
  R40      1      A  Q_RES       I171
  R63      2      B  Q_RES       I231
  R64      2      B  Q_RES       I233
  R66      1      A  Q_RES       I181
  R87      2      B  Q_RES       I57
  R88      2      B  Q_RES       I59
  R89      2      B  Q_RES       I65
  R94      2      B  Q_RES       I201
  R118     1      A  Q_RES       I53
  R127     1      A  Q_RES       I46
  R202     1      A  Q_RES       I125
  R205     2      B  Q_RES       I79
  R206     1      A  Q_RES       I116
  R209     2      B  Q_RES       I19
  R210     1      A  Q_RES       I47
  R219     2      B  Q_RES       I75
  R220     2      B  Q_RES       I62
  R228     1      A  Q_RES       I107
  R229     1      A  Q_RES       I106
  R233     1      A  Q_RES       I87
  R234     1      A  Q_RES       I86
  R235     1      A  Q_RES       I187
  R296     2      B  Q_RES       I11
  R308     2      B  Q_RES       I16
  R310     2      B  Q_RES       I18
  R312     2      B  Q_RES       I19
  R313     2      B  Q_RES       I30
  R314     2      B  Q_RES       I26
  R325     2      B  Q_RES       I27
  R326     1      A  Q_RES       I193
  R327     1      A  Q_RES       I177
  R328     1      A  Q_RES       I176
  R329     1      A  Q_RES       I175
  R330     1      A  Q_RES       I174
  R331     1      A  Q_RES       I173
  R332     1      A  Q_RES       I171
  R333     1      A  Q_RES       I172
  R334     1      A  Q_RES       I164
  R335     1      A  Q_RES       I163
  R336     1      A  Q_RES       I162
  R337     1      A  Q_RES       I161
  R338     1      A  Q_RES       I160
  R339     1      A  Q_RES       I159
  R340     1      A  Q_RES       I124
  R341     1      A  Q_RES       I125
  R342     1      A  Q_RES       I122
  R343     1      A  Q_RES       I123
  R344     1      A  Q_RES       I121
  R345     1      A  Q_RES       I119
  R346     1      A  Q_RES       I120
  R347     1      A  Q_RES       I117
  R348     1      A  Q_RES       I118
  R349     1      A  Q_RES       I116
  R350     1      A  Q_RES       I114
  R377     2      B  Q_RES       I63
  R378     2      B  Q_RES       I54
  R388     2      B  Q_RES       I15
  R390     2      B  Q_RES       I17
  R391     2      B  Q_RES       I34
  R392     2      B  Q_RES       I35
  R395     2      B  Q_RES       I114
  R396     2      B  Q_RES       I113
  R400     2      B  Q_RES       I148
  R411     2      B  Q_RES        I6
  R412     2      B  Q_RES        I8
  R413     2      B  Q_RES       I12
  R415     2      B  Q_RES       I27
  R417     2      B  Q_RES       I28
  R419     2      B  Q_RES       I38
  R431     2      B  Q_RES       I17
  R467     2      B  Q_RES       I313
  R487     2      B  Q_RES       I51
  R506     2      B  Q_RES       I49
  R507     2      B  Q_RES       I50
  R614     2      B  Q_RES       I35
  R618     1      A  Q_RES       I211
  R620     2      B  Q_RES       I33
  R684     2      B  Q_RES       I122
  R685     2      B  Q_RES       I124
  R776     2      B  Q_RES       I184
  R778     2      B  Q_RES       I181
  R786     2      B  Q_RES       I203
  R788     2      B  Q_RES       I211
  R790     2      B  Q_RES       I220
  R792     2      B  Q_RES       I236
  R794     2      B  Q_RES       I242
  R798     2      B  Q_RES       I262
  R811     2      B  Q_RES       I277
  R817     2      B  Q_RES       I393
  R818     2      B  Q_RES       I392
  R819     2      B  Q_RES       I391
  R820     2      B  Q_RES       I390
  R823     1      A  Q_RES       I234
  R830     2      B  Q_RES       I61
  R832     2      B  Q_RES       I97
  R839     2      B  Q_RES       I140
  R866     2      B  Q_RES       I311
  SW6      1      1  SW2S_TA31E2KQTR  I136
  SW6     G1     G1  SW2S_TA31E2KQTR  I136
  SW6     G2     G2  SW2S_TA31E2KQTR  I136
  SW6     G3     G3  SW2S_TA31E2KQTR  I136
  SW7      1      1  SW2S_TA31E2KQTR  I137
  SW7     G1     G1  SW2S_TA31E2KQTR  I137
  SW7     G2     G2  SW2S_TA31E2KQTR  I137
  SW7     G3     G3  SW2S_TA31E2KQTR  I137
  U1      A2  VSSQ0  K4A8G165WCBCTD  I196
  U1      A8  VSSQ1  K4A8G165WCBCTD  I196
  U1      B2   VSS0  K4A8G165WCBCTD  I196
  U1      C9  VSSQ2  K4A8G165WCBCTD  I196
  U1      D2  VSSQ3  K4A8G165WCBCTD  I196
  U1      D8  VSSQ4  K4A8G165WCBCTD  I196
  U1      E1   VSS1  K4A8G165WCBCTD  I196
  U1      E3  VSSQ5  K4A8G165WCBCTD  I196
  U1      E8  VSSQ6  K4A8G165WCBCTD  I196
  U1      F1  VSSQ7  K4A8G165WCBCTD  I196
  U1      G8   VSS3  K4A8G165WCBCTD  I196
  U1      H1  VSSQ8  K4A8G165WCBCTD  I196
  U1      H9  VSSQ9  K4A8G165WCBCTD  I196
  U1      K1   VSS4  K4A8G165WCBCTD  I196
  U1      K9   VSS5  K4A8G165WCBCTD  I196
  U1      N1   VSS7  K4A8G165WCBCTD  I196
  U1      T1   VSS8  K4A8G165WCBCTD  I196
  U1      T7    NC1  K4A8G165WCBCTD  I196
  U2       2    GND  SN74LVC1G3157DCKR  I20
  U3       2    GND  SN74LVC1G3157DCKR  I43
  U4       4    GND  TMP75AIDGKR  I23
  U5      A1  GND_A1  AST2600A1GP  I116
  U5      A2  RGMII1RXCTL||GPIO18A7  AST2600A1GP  I35
  U5      A3  RGMII1TXD1||RMII1TXD1||GPIO18A3  AST2600A1GP  I35
  U5      A5  GND_A5  AST2600A1GP  I116
  U5     A26  GND_A26  AST2600A1GP  I116
  U5     AA1  GND_AA1  AST2600A1GP  I116
  U5     AA3  GND_AA3  AST2600A1GP  I116
  U5     AA6  GND_AA6  AST2600A1GP  I116
  U5     AA7  GND_AA7  AST2600A1GP  I116
  U5     AA8  GND_AA8  AST2600A1GP  I116
  U5     AA10  GND_AA10  AST2600A1GP  I116
  U5     AA14  GND_AA14  AST2600A1GP  I116
  U5     AA15  GND_AA15  AST2600A1GP  I116
  U5     AA19  GND_AA19  AST2600A1GP  I116
  U5     AA20  GND_AA20  AST2600A1GP  I116
  U5     AA22  GND_AA22  AST2600A1GP  I116
  U5     AC2  GND_AC2  AST2600A1GP  I116
  U5     AC6  GND_AC6  AST2600A1GP  I116
  U5     AC25  GND_AC25  AST2600A1GP  I116
  U5     AD1  GND_AD1  AST2600A1GP  I116
  U5     AD4  GND_AD4  AST2600A1GP  I116
  U5     AE3  GND_AE3  AST2600A1GP  I116
  U5     AE6  GND_AE6  AST2600A1GP  I116
  U5     AE9  GND_AE9  AST2600A1GP  I116
  U5     AE13  GND_AE13  AST2600A1GP  I116
  U5     AE17  GND_AE17  AST2600A1GP  I116
  U5     AE20  GND_AE20  AST2600A1GP  I116
  U5     AE23  GND_AE23  AST2600A1GP  I116
  U5     AF1  GND_AF1  AST2600A1GP  I116
  U5     AF4  GND_AF4  AST2600A1GP  I116
  U5     AF26  GND_AF26  AST2600A1GP  I116
  U5      B1  RGMII1RXD1||RMII1RXD1||GPIO18B1  AST2600A1GP  I35
  U5      B2  RGMII1RXD0||RMII1RXD0||GPIO18B0  AST2600A1GP  I35
  U5      B3  RGMII1RXCK||RMII1RCLKI||GPIO18A6  AST2600A1GP  I35
  U5      B5  GND_B5  AST2600A1GP  I116
  U5     B11  GND_B11  AST2600A1GP  I116
  U5     B15  GND_B15  AST2600A1GP  I116
  U5     B19  GND_B19  AST2600A1GP  I116
  U5     B23  GND_B23  AST2600A1GP  I116
  U5      C1  RGMII2TXD0||RMII2TXD0||GPIO18B6  AST2600A1GP  I35
  U5      C2  RGMII2TXCTL||RMII2TXEN||GPIO18B5  AST2600A1GP  I35
  U5      C3  GND_C3  AST2600A1GP  I116
  U5      C4  RGMII1RXD2||RMII1CRSDV||GPIO18B2  AST2600A1GP  I35
  U5      C5  RGMII1TXD2||GPIO18A4  AST2600A1GP  I35
  U5      C6  RGMII1TXCK||RMII1RCLKO||GPIO18A0  AST2600A1GP  I35
  U5     C26  RGMII4RXCTL||NDCD4||GPIOE3  AST2600A1GP  I45
  U5      D1  RGMII2RXD0||RMII2RXD0||GPIO18C4  AST2600A1GP  I35
  U5      D2  RGMII2RXCK||RMII2RCLKI||GPIO18C2  AST2600A1GP  I35
  U5      D3  RGMII2TXD1||RMII2TXD1||GPIO18B7  AST2600A1GP  I35
  U5      D4  RGMII2TXCK||RMII2RCLKO||GPIO18B4  AST2600A1GP  I35
  U5      D5  RGMII1TXD0||RMII1TXD0||GPIO18A2  AST2600A1GP  I35
  U5      D6  RGMII1TXCTL||RMII1TXEN||GPIO18A1  AST2600A1GP  I35
  U5     D25  GND_D25  AST2600A1GP  I116
  U5      E1  RGMII2RXD3||RMII2RXER||GPIO18C7  AST2600A1GP  I35
  U5      E2  RGMII2RXD2||RMII2CRSDV||GPIO18C6  AST2600A1GP  I35
  U5      E3  RGMII2RXCTL||GPIO18C3  AST2600A1GP  I35
  U5      E4  RGMII2TXD2||GPIO18C0  AST2600A1GP  I35
  U5      E5  RGMII1RXD3||RMII1RXER||GPIO18B3  AST2600A1GP  I35
  U5      E6  RGMII1TXD3||GPIO18A5  AST2600A1GP  I35
  U5      E8  GND_E8  AST2600A1GP  I116
  U5      F4  RGMII2RXD1||RMII2RXD1||GPIO18C5  AST2600A1GP  I35
  U5      F5  RGMII2TXD3||GPIO18C1  AST2600A1GP  I35
  U5      F6  GND_F6  AST2600A1GP  I116
  U5      F8  GND_F8  AST2600A1GP  I116
  U5     F10  GND_F10  AST2600A1GP  I116
  U5     F12  GND_F12  AST2600A1GP  I116
  U5     F14  GND_F14  AST2600A1GP  I116
  U5     F16  GND_F16  AST2600A1GP  I116
  U5     F17  GND_F17  AST2600A1GP  I116
  U5     F18  GND_F18  AST2600A1GP  I116
  U5     F21  GND_F21  AST2600A1GP  I116
  U5      G2  GND_G2  AST2600A1GP  I116
  U5     G25  GND_G25  AST2600A1GP  I116
  U5      H4  GND_H4  AST2600A1GP  I116
  U5      H9  GND_H9  AST2600A1GP  I116
  U5     H10  GND_H10  AST2600A1GP  I116
  U5     H11  GND_H11  AST2600A1GP  I116
  U5     H13  GND_H13  AST2600A1GP  I116
  U5      J2  GND_J2  AST2600A1GP  I116
  U5     J11  GND_J11  AST2600A1GP  I116
  U5     J13  GND_J13  AST2600A1GP  I116
  U5     J14  GND_J14  AST2600A1GP  I116
  U5     J15  GND_J15  AST2600A1GP  I116
  U5     J16  GND_J16  AST2600A1GP  I116
  U5     J17  GND_J17  AST2600A1GP  I116
  U5     J18  GND_J18  AST2600A1GP  I116
  U5     J19  GND_J19  AST2600A1GP  I116
  U5      K4  GND_K4  AST2600A1GP  I116
  U5      K8  GND_K8  AST2600A1GP  I116
  U5      K9  GND_K9  AST2600A1GP  I116
  U5     K13  GND_K13  AST2600A1GP  I116
  U5     K14  GND_K14  AST2600A1GP  I116
  U5     K15  GND_K15  AST2600A1GP  I116
  U5     K22  GND_K22  AST2600A1GP  I116
  U5      L2  GND_L2  AST2600A1GP  I116
  U5      L8  GND_L8  AST2600A1GP  I116
  U5     L11  GND_L11  AST2600A1GP  I116
  U5     L12  GND_L12  AST2600A1GP  I116
  U5     L15  GND_L15  AST2600A1GP  I116
  U5     L16  GND_L16  AST2600A1GP  I116
  U5     L17  GND_L17  AST2600A1GP  I116
  U5     L18  GND_L18  AST2600A1GP  I116
  U5     L19  GND_L19  AST2600A1GP  I116
  U5     L25  GND_L25  AST2600A1GP  I116
  U5      M4  GND_M4  AST2600A1GP  I116
  U5      M9  GND_M9  AST2600A1GP  I116
  U5     M10  GND_M10  AST2600A1GP  I116
  U5     M12  GND_M12  AST2600A1GP  I116
  U5     M15  GND_M15  AST2600A1GP  I116
  U5     M16  GND_M16  AST2600A1GP  I116
  U5     M17  GND_M17  AST2600A1GP  I116
  U5     M18  GND_M18  AST2600A1GP  I116
  U5     M19  GND_M19  AST2600A1GP  I116
  U5      N2  GND_N2  AST2600A1GP  I116
  U5      N6  GND_N6  AST2600A1GP  I116
  U5      N9  GND_N9  AST2600A1GP  I116
  U5     N10  GND_N10  AST2600A1GP  I116
  U5     N15  GND_N15  AST2600A1GP  I116
  U5     N16  GND_N16  AST2600A1GP  I116
  U5     N17  GND_N17  AST2600A1GP  I116
  U5     N18  GND_N18  AST2600A1GP  I116
  U5     N19  GND_N19  AST2600A1GP  I116
  U5      P4  GND_P4  AST2600A1GP  I116
  U5      P9  GND_P9  AST2600A1GP  I116
  U5     P10  GND_P10  AST2600A1GP  I116
  U5     P15  GND_P15  AST2600A1GP  I116
  U5     P16  GND_P16  AST2600A1GP  I116
  U5     P17  GND_P17  AST2600A1GP  I116
  U5     P18  GND_P18  AST2600A1GP  I116
  U5     P19  GND_P19  AST2600A1GP  I116
  U5      R2  GND_R2  AST2600A1GP  I116
  U5      R8  GND_R8  AST2600A1GP  I116
  U5     R11  GND_R11  AST2600A1GP  I116
  U5     R15  GND_R15  AST2600A1GP  I116
  U5     R16  GND_R16  AST2600A1GP  I116
  U5     R17  GND_R17  AST2600A1GP  I116
  U5     R18  GND_R18  AST2600A1GP  I116
  U5     R19  GND_R19  AST2600A1GP  I116
  U5     R25  GND_R25  AST2600A1GP  I116
  U5      T4  GND_T4  AST2600A1GP  I116
  U5     T11  GND_T11  AST2600A1GP  I116
  U5     T12  GND_T12  AST2600A1GP  I116
  U5     T15  GND_T15  AST2600A1GP  I116
  U5     T16  GND_T16  AST2600A1GP  I116
  U5     T17  GND_T17  AST2600A1GP  I116
  U5     T18  GND_T18  AST2600A1GP  I116
  U5     T19  GND_T19  AST2600A1GP  I116
  U5      U2  GND_U2  AST2600A1GP  I116
  U5      U8  GND_U8  AST2600A1GP  I116
  U5      U9  GND_U9  AST2600A1GP  I116
  U5     U10  GND_U10  AST2600A1GP  I116
  U5     U11  GND_U11  AST2600A1GP  I116
  U5     U12  GND_U12  AST2600A1GP  I116
  U5     U14  GND_U14  AST2600A1GP  I116
  U5     U19  GND_U19  AST2600A1GP  I116
  U5     U22  GND_U22  AST2600A1GP  I116
  U5     U23  GND_U23  AST2600A1GP  I116
  U5      V5  GND_V5  AST2600A1GP  I116
  U5     V11  GND_V11  AST2600A1GP  I116
  U5     V12  GND_V12  AST2600A1GP  I116
  U5     V14  GND_V14  AST2600A1GP  I116
  U5     V15  GND_V15  AST2600A1GP  I116
  U5     V16  GND_V16  AST2600A1GP  I116
  U5     V17  GND_V17  AST2600A1GP  I116
  U5     V18  GND_V18  AST2600A1GP  I116
  U5     V19  GND_V19  AST2600A1GP  I116
  U5      W5  GND_W5  AST2600A1GP  I116
  U5      W6  GND_W6  AST2600A1GP  I116
  U5      W8  GND_W8  AST2600A1GP  I116
  U5      W9  GND_W9  AST2600A1GP  I116
  U5     W10  GND_W10  AST2600A1GP  I116
  U5     W11  GND_W11  AST2600A1GP  I116
  U5     W12  GND_W12  AST2600A1GP  I116
  U5     W22  GND_W22  AST2600A1GP  I116
  U5     W25  GND_W25  AST2600A1GP  I116
  U5      Y6  GND_Y6  AST2600A1GP  I116
  U5     Y22  GND_Y22  AST2600A1GP  I116
  U6       2    GND  SN74LVC2G07DCKR  I64
  U7       5  TEST3  BCM54612EB1KMLG  I126
  U7       6  TEST2  BCM54612EB1KMLG  I126
  U7      TH     TH  BCM54612EB1KMLG  I126
  U8       2    GND  TPD4E001DBVR  I93
  U9       2    GND  TPD4E001DBVR  I94
  U10      2    GND  TPS2553DBVR1  I51
  U12      S  SOURCE  MOSFET_N    I14
  U13      3    GND  SN74LVC1G07DCKR  I15
  U14      2    GND  AP22811AW57  I79
  U15      5    GND  TPS22965DSGR   I2
  U15     TH     TH  TPS22965DSGR   I2
  U16      2    GND  TPD4E001DBVR  I51
  U17      5   GND1  FT234XDR    I98
  U17     13   GND2  FT234XDR    I98
  U18      3    GND  TPD2EUSB30DRTR  I84
  U19      4    VSS  M24128BWDW6TP  I15
  U20     A6  VSS_A6  MTFC8GAKAJCN1MWT  I38
  U20     C4  VSSQ_C4  MTFC8GAKAJCN1MWT  I38
  U20     E7  VSS_E7  MTFC8GAKAJCN1MWT  I38
  U20     G5  VSS_G5  MTFC8GAKAJCN1MWT  I38
  U20    H10  VSS_H10  MTFC8GAKAJCN1MWT  I38
  U20     J5  VSS_J5  MTFC8GAKAJCN1MWT  I38
  U20     K8  VSS_K8  MTFC8GAKAJCN1MWT  I38
  U20     N2  VSSQ_N2  MTFC8GAKAJCN1MWT  I38
  U20     N5  VSSQ_N5  MTFC8GAKAJCN1MWT  I38
  U20     P4  VSSQ_P4  MTFC8GAKAJCN1MWT  I38
  U20     P6  VSSQ_P6  MTFC8GAKAJCN1MWT  I38
  U21      8    GND  IDTQS3VH257PAG  I296
  U23      3    GND  SN74LVC1G07DBVR   I2
  U24      2    GND  SN74LVC2G07DCKR  I115
  U25     A1  GND_13  10M02SCU169C8G  I96
  U25    A13  GND_12  10M02SCU169C8G  I96
  U25     B8  GND_11  10M02SCU169C8G  I96
  U25     C3  GND_10  10M02SCU169C8G  I96
  U25     D5  GND_9  10M02SCU169C8G  I96
  U25    E11  GND_8  10M02SCU169C8G  I96
  U25     F3  GND_7  10M02SCU169C8G  I96
  U25     G7  GND_6  10M02SCU169C8G  I96
  U25    H12  GND_5  10M02SCU169C8G  I96
  U25     J4  GND_4  10M02SCU169C8G  I96
  U25     L9  GND_3  10M02SCU169C8G  I96
  U25     M6  GND_2  10M02SCU169C8G  I96
  U25     N1  GND_1  10M02SCU169C8G  I96
  U25    N13  GND_0  10M02SCU169C8G  I96
  U26      3    GND  74HC1G126GW  I33
  U28     10    GND  MX66L1G45GMI08G  I64
  U29      3    GND  74HC1G126GW  I67
  U30      8    GND  IDTQS3VH257PAG  I271
  U31      3    GND  74LVC1G07GW  I151
  U32      3    GND  74LVC1G17GW  I49
  U33      3    GND  74HC1G126GW  I32
  U34      2    GND  TPD4E001DBVR  I48
  U35      2    GND  TPD4E001DBVR  I70
  U36      3    GND  74HC1G126GW  I43
  U38      1    GND  PRTR5V0U2X   I6
  U43      2    GND  TPS3808G33DBVR  I60
  Y1       2     G1  Q_XTAL_4P_13BI_24GND  I204
  Y1       4     G2  Q_XTAL_4P_13BI_24GND  I204

GND_P1          @SCM_LIB.SCM(SCH_1):GND_P1
  J9       3      3  DELTA_L      I1
  J12      3      3  DELTA_L     I31
  J17      3      3  DELTA_L     I23
  J20      3      3  DELTA_L     I28
  J22      3      3  DELTA_L     I42
  J24      3      3  DELTA_L     I33
  J25      3      3  DELTA_L     I44
  J27      3      3  DELTA_L     I37
  J28      3      3  DELTA_L     I45
  J30      3      3  DELTA_L     I43

GND_P2          @SCM_LIB.SCM(SCH_1):GND_P2
  J11      3      3  DELTA_L     I11
  J16      3      3  DELTA_L     I21
  J19      3      3  DELTA_L     I27
  J23      3      3  DELTA_L     I32
  J26      3      3  DELTA_L     I36
  J29      3      3  DELTA_L     I29

H_CPU0_MEMTRIP_LVC1_N   @SCM_LIB.SCM(SCH_1):H_CPU0_MEMTRIP_LVC1_N
  U5     AB23  GPIOP5||PWM13||THRUOUT2  AST2600A1GP  I41
  U25    N12  IO_53_3  10M02SCU169C8G  I394

H_CPU0_PROCHOT_LVC1_N   @SCM_LIB.SCM(SCH_1):H_CPU0_PROCHOT_LVC1_N
  R51      1      A  Q_RES       I317
  U5     D14  GPIOM0||NCTS1  AST2600A1GP  I45

H_CPU0_PROCHOT_LVC1_R_N   @SCM_LIB.SCM(SCH_1):H_CPU0_PROCHOT_LVC1_R_N
  R51      2      B  Q_RES       I317
  U25    J13  IO_73_5  10M02SCU169C8G  I330

H_CPU1_MEMTRIP_LVC1_N   @SCM_LIB.SCM(SCH_1):H_CPU1_MEMTRIP_LVC1_N
  U5     AB24  GPIOP6||PWM14||THRUIN3  AST2600A1GP  I41
  U25    N10  IO_55_3  10M02SCU169C8G  I394

H_CPU1_PROCHOT_LVC1_N   @SCM_LIB.SCM(SCH_1):H_CPU1_PROCHOT_LVC1_N
  R177     1      A  Q_RES       I87
  U5     P24  GPIOS5||RXD10  AST2600A1GP  I45

H_CPU1_PROCHOT_LVC1_R_N   @SCM_LIB.SCM(SCH_1):H_CPU1_PROCHOT_LVC1_R_N
  R177     2      B  Q_RES       I87
  U25     M2  IO_25_2  10M02SCU169C8G  I394

I3C1_SCL_R      @SCM_LIB.SCM(SCH_1):I3C1_SCL_R
  R184     2      B  Q_RES       I33
  U5     AF23  I3C1SCL  AST2600A1GP  I35

I3C1_SDA_R      @SCM_LIB.SCM(SCH_1):I3C1_SDA_R
  R185     2      B  Q_RES       I32
  U5     AE24  I3C1SDA  AST2600A1GP  I35

I3C1_SPD_SCL    @SCM_LIB.SCM(SCH_1):I3C1_SPD_SCL
  GF1    OA5    OA5  FCONN168_ME1016810106011  I171
  R184     1      A  Q_RES       I33
  R194     2      B  Q_RES       I86

I3C1_SPD_SDA    @SCM_LIB.SCM(SCH_1):I3C1_SPD_SDA
  GF1    OA6    OA6  FCONN168_ME1016810106011  I171
  R185     1      A  Q_RES       I32
  R195     2      B  Q_RES       I89

I3C2_SCL_R      @SCM_LIB.SCM(SCH_1):I3C2_SCL_R
  R186     2      B  Q_RES       I31
  U5     AF22  I3C2SCL  AST2600A1GP  I35

I3C2_SDA_R      @SCM_LIB.SCM(SCH_1):I3C2_SDA_R
  R187     2      B  Q_RES       I30
  U5     AE22  I3C2SDA  AST2600A1GP  I35

I3C2_SPD_SCL    @SCM_LIB.SCM(SCH_1):I3C2_SPD_SCL
  GF1    OA7    OA7  FCONN168_ME1016810106011  I171
  R186     1      A  Q_RES       I31
  R190     2      B  Q_RES       I11

I3C2_SPD_SDA    @SCM_LIB.SCM(SCH_1):I3C2_SPD_SDA
  GF1    OA8    OA8  FCONN168_ME1016810106011  I171
  R187     1      A  Q_RES       I30
  R191     2      B  Q_RES       I10

I3C3_SCL_R      @SCM_LIB.SCM(SCH_1):I3C3_SCL_R
  R198     1      A  Q_RES       I44
  U5     AF25  I3C3SCL||FSI1CLK  AST2600A1GP  I35

I3C3_SDA_R      @SCM_LIB.SCM(SCH_1):I3C3_SDA_R
  R199     1      A  Q_RES       I43
  U5     AE26  I3C3SDA||FSI1DATA  AST2600A1GP  I35

I3C3_SPD_SCL    @SCM_LIB.SCM(SCH_1):I3C3_SPD_SCL
  GF1    OA9    OA9  FCONN168_ME1016810106011  I171
  R188     2      B  Q_RES       I82
  R198     2      B  Q_RES       I44

I3C3_SPD_SDA    @SCM_LIB.SCM(SCH_1):I3C3_SPD_SDA
  GF1    OA10   OA10  FCONN168_ME1016810106011  I171
  R189     2      B  Q_RES       I85
  R199     2      B  Q_RES       I43

I3C4_SCL_R      @SCM_LIB.SCM(SCH_1):I3C4_SCL_R
  R200     1      A  Q_RES       I41
  U5     AE25  I3C4SCL||FSI2CLK  AST2600A1GP  I35

I3C4_SDA_R      @SCM_LIB.SCM(SCH_1):I3C4_SDA_R
  R201     1      A  Q_RES       I42
  U5     AF24  I3C4SDA||FSI2DATA  AST2600A1GP  I35

I3C4_SPD_SCL    @SCM_LIB.SCM(SCH_1):I3C4_SPD_SCL
  GF1    OA11   OA11  FCONN168_ME1016810106011  I171
  R196     2      B  Q_RES       I27
  R200     2      B  Q_RES       I41

I3C4_SPD_SDA    @SCM_LIB.SCM(SCH_1):I3C4_SPD_SDA
  GF1    OA12   OA12  FCONN168_ME1016810106011  I171
  R197     2      B  Q_RES       I25
  R201     2      B  Q_RES       I42

IBMC_MIOZ       @SCM_LIB.SCM(SCH_1):IBMC_MIOZ
  R127     2      B  Q_RES       I46
  U5      P5   MIOZ  AST2600A1GP  I45

ID_LED_BUF      @SCM_LIB.SCM(SCH_1):ID_LED_BUF
  Q12      3     D2  MOSFET_DUAL_6P  I105
  R813     1      A  Q_RES       I129

ID_LED_BUF_R    @SCM_LIB.SCM(SCH_1):ID_LED_BUF_R
  C324     1      A  Q_CAP       I122
  D15      C      C  Q_LED       I143
  R813     2      B  Q_RES       I129
  R815     2      B  Q_RES       I132

ID_LED_P3V3_AUX   @SCM_LIB.SCM(SCH_1):ID_LED_P3V3_AUX
  C197     1      A  Q_CAP       I96
  D15      A      A  Q_LED       I143
  R569     2      B  Q_RES       I98

ID_RST_BTN_BMC_N   @SCM_LIB.SCM(SCH_1):ID_RST_BTN_BMC_N
  R565     2      B  Q_RES       I127
  U32      4      Y  74LVC1G17GW  I49

ID_RST_BTN_BMC_R_N   @SCM_LIB.SCM(SCH_1):ID_RST_BTN_BMC_R_N
  R565     1      A  Q_RES       I127
  U5     AA23  GPIOP2||PWM10||THRUIN1  AST2600A1GP  I41

IRQ_BMC_CPU_NMI   @SCM_LIB.SCM(SCH_1):IRQ_BMC_CPU_NMI
  R166     2      B  Q_RES       I50
  U5     J24  GPIOB7||RXD4||LHRST#  AST2600A1GP  I45

IRQ_BMC_CPU_NMI_R   @SCM_LIB.SCM(SCH_1):IRQ_BMC_CPU_NMI_R
  R166     1      A  Q_RES       I50
  U25     C2  IO_2_1A  10M02SCU169C8G  I394

IRQ_BMC_LPC_SERIRQ_ESPI_GF   @SCM_LIB.SCM(SCH_1):IRQ_BMC_LPC_SERIRQ_ESPI_GF
  GF1     B3     B3  FCONN168_ME1016810106011  I171
  R116     2      B  Q_RES        I3
  R119     1      A  Q_RES       I34

IRQ_BMC_PCH_NMI_N   @SCM_LIB.SCM(SCH_1):IRQ_BMC_PCH_NMI_N
  R61      2      B  Q_RES       I204
  R571     1      A  Q_RES       I407
  U5     R23  GPIOS0||MDC1  AST2600A1GP  I45

IRQ_BMC_PCH_NMI_R_N   @SCM_LIB.SCM(SCH_1):IRQ_BMC_PCH_NMI_R_N
  R571     2      B  Q_RES       I407
  U25     M1  IO_23_2  10M02SCU169C8G  I394

IRQ_BMC_TPM_SPI_R_N   @SCM_LIB.SCM(SCH_1):IRQ_BMC_TPM_SPI_R_N
  J10      9      9  SCONN11_9192031111LF  I113
  R113     2      B  Q_RES       I105

IRQ_CPU0_VRHOT_N   @SCM_LIB.SCM(SCH_1):IRQ_CPU0_VRHOT_N
  U5     V26  GPIOR3||TACH11  AST2600A1GP  I41
  U25     N7  IO_43_3  10M02SCU169C8G  I394

IRQ_CPU1_VRHOT_N   @SCM_LIB.SCM(SCH_1):IRQ_CPU1_VRHOT_N
  U5     U25  GPIOR4||TACH12  AST2600A1GP  I41
  U25     M7  IO_44_3  10M02SCU169C8G  I394

IRQ_ESPI_LPC_SERIRQ_ALERT0_N   @SCM_LIB.SCM(SCH_1):IRQ_ESPI_LPC_SERIRQ_ALERT0_N
  R119     2      B  Q_RES       I34
  U5     AD7  GPIOW6||LSIRQ#||ESPIALT#  AST2600A1GP  I45

IRQ_OC_DETECT_EN_N   @SCM_LIB.SCM(SCH_1):IRQ_OC_DETECT_EN_N
  U5     V24  GPIOR2||TACH10  AST2600A1GP  I41
  U25     M8  IO_47_3  10M02SCU169C8G  I394

IRQ_OC_DETECT_N   @SCM_LIB.SCM(SCH_1):IRQ_OC_DETECT_N
  U5     V25  GPIOR0||TACH8  AST2600A1GP  I41
  U25     N8  IO_45_3  10M02SCU169C8G  I394

IRQ_PCH_SCI_WHEA_R_N   @SCM_LIB.SCM(SCH_1):IRQ_PCH_SCI_WHEA_R_N
  U5     A15  GPIOI7||SIOSCI#  AST2600A1GP  I45
  U25     M4  IO_35_3  10M02SCU169C8G  I394

IRQ_SGPIO_BMC_N   @SCM_LIB.SCM(SCH_1):IRQ_SGPIO_BMC_N
  R689     2      B  Q_RES       I264
  U5     A24  GPIOF6||SD1CD#||PWM14  AST2600A1GP  I45

IRQ_SGPIO_N     @SCM_LIB.SCM(SCH_1):IRQ_SGPIO_N
  GF1    B40    B40  FCONN168_ME1016810106011  I171
  R68      2      B  Q_RES       I179
  R689     1      A  Q_RES       I264
  R690     2      B  Q_RES       I392

IRQ_SGPIO_R_N   @SCM_LIB.SCM(SCH_1):IRQ_SGPIO_R_N
  R690     1      A  Q_RES       I392
  U25    M12  IO_56_3  10M02SCU169C8G  I394

IRQ_SMI_ACTIVE_BMC_N   @SCM_LIB.SCM(SCH_1):IRQ_SMI_ACTIVE_BMC_N
  R37      2      B  Q_RES       I133
  U5     AC9  GPIOX2||SPI2CS2#  AST2600A1GP  I45

IRQ_SMI_ACTIVE_GF_N   @SCM_LIB.SCM(SCH_1):IRQ_SMI_ACTIVE_GF_N
  GF1    A56    A56  FCONN168_ME1016810106011  I171
  R37      1      A  Q_RES       I133

IRQ_TPM_SPI_N   @SCM_LIB.SCM(SCH_1):IRQ_TPM_SPI_N
  R59      2      B  Q_RES       I98
  R113     1      A  Q_RES       I105
  R497     2      B  Q_RES       I78
  R505     1      A  Q_RES       I74
  U5     AF15  GPIOV7||LPCSMI#  AST2600A1GP  I45

IRQ_TPM_SPI_R_N   @SCM_LIB.SCM(SCH_1):IRQ_TPM_SPI_R_N
  J5       9      9  SCONN11_9192031111LF  I56
  R505     2      B  Q_RES       I74

IRQ_UV_DETECT_N   @SCM_LIB.SCM(SCH_1):IRQ_UV_DETECT_N
  U5     U24  GPIOR1||TACH9  AST2600A1GP  I41
  U25     H2  IO_16_1B  10M02SCU169C8G  I394

JTAG_1_BMC_TCK_R   @SCM_LIB.SCM(SCH_1):JTAG_1_BMC_TCK_R
  R222     1      A  Q_RES       I80
  U5     E17  GPIOI2||MTCK2||TXD13  AST2600A1GP  I41

JTAG_1_BMC_TDI_R   @SCM_LIB.SCM(SCH_1):JTAG_1_BMC_TDI_R
  R639     1      A  Q_RES       I88
  U5     A16  GPIOI1||MTDI2||RXD12  AST2600A1GP  I41

JTAG_1_BMC_TDO_R   @SCM_LIB.SCM(SCH_1):JTAG_1_BMC_TDO_R
  R224     1      A  Q_RES       I87
  U5     C16  GPIOI4||MTDO2  AST2600A1GP  I41

JTAG_1_BMC_TMS_R   @SCM_LIB.SCM(SCH_1):JTAG_1_BMC_TMS_R
  R223     1      A  Q_RES       I78
  U5     D16  GPIOI3||MTMS2||RXD13  AST2600A1GP  I41

JTAG_1_BMC_TRST_R   @SCM_LIB.SCM(SCH_1):JTAG_1_BMC_TRST_R
  R221     1      A  Q_RES       I81
  U5     D17  GPIOI0||MNTRST2||TXD12  AST2600A1GP  I41

JTAG_MB_TCK     @SCM_LIB.SCM(SCH_1):JTAG_MB_TCK
  GF1    A34    A34  FCONN168_ME1016810106011  I171
  R222     2      B  Q_RES       I80
  R228     2      B  Q_RES       I107

JTAG_MB_TDI     @SCM_LIB.SCM(SCH_1):JTAG_MB_TDI
  GF1    A36    A36  FCONN168_ME1016810106011  I171
  R226     2      B  Q_RES       I103
  R639     2      B  Q_RES       I88

JTAG_MB_TDO     @SCM_LIB.SCM(SCH_1):JTAG_MB_TDO
  GF1    A37    A37  FCONN168_ME1016810106011  I171
  R224     2      B  Q_RES       I87
  R230     2      B  Q_RES       I105

JTAG_MB_TMS     @SCM_LIB.SCM(SCH_1):JTAG_MB_TMS
  GF1    A35    A35  FCONN168_ME1016810106011  I171
  R223     2      B  Q_RES       I78
  R227     2      B  Q_RES       I104

JTAG_MB_TRST_N   @SCM_LIB.SCM(SCH_1):JTAG_MB_TRST_N
  R221     2      B  Q_RES       I81
  R229     2      B  Q_RES       I106

JTAG_SCM_CONN_TCK   @SCM_LIB.SCM(SCH_1):JTAG_SCM_CONN_TCK
  J7       2      2  CONN7_4400547  I53
  R514     2      B  Q_RES       I94

JTAG_SCM_CONN_TDI   @SCM_LIB.SCM(SCH_1):JTAG_SCM_CONN_TDI
  J7       5      5  CONN7_4400547  I53
  R516     2      B  Q_RES       I95

JTAG_SCM_CONN_TDO   @SCM_LIB.SCM(SCH_1):JTAG_SCM_CONN_TDO
  J7       3      3  CONN7_4400547  I53
  R517     2      B  Q_RES       I97

JTAG_SCM_CONN_TMS   @SCM_LIB.SCM(SCH_1):JTAG_SCM_CONN_TMS
  J7       4      4  CONN7_4400547  I53
  R515     2      B  Q_RES       I96

JTAG_SCM_NTRST   @SCM_LIB.SCM(SCH_1):JTAG_SCM_NTRST
  R206     2      B  Q_RES       I116
  U5     F11  NTRST||MNTRST1  AST2600A1GP  I41

JTAG_SCM_PLD_JTAGEN   @SCM_LIB.SCM(SCH_1):JTAG_SCM_PLD_JTAGEN
  R509     2      B  Q_RES       I47
  R518     2      B  Q_RES       I23
  U25     E5  IO_8_JTAGEN_1B  10M02SCU169C8G  I394

JTAG_SCM_PLD_R1_JTAGEN   @SCM_LIB.SCM(SCH_1):JTAG_SCM_PLD_R1_JTAGEN
  J7       6      6  CONN7_4400547  I53
  R518     1      A  Q_RES       I23

JTAG_SCM_PLD_TCK   @SCM_LIB.SCM(SCH_1):JTAG_SCM_PLD_TCK
  R510     2      B  Q_RES       I126
  R514     1      A  Q_RES       I94
  U25     G2  IO_11_TCK_1B  10M02SCU169C8G  I394

JTAG_SCM_PLD_TDI   @SCM_LIB.SCM(SCH_1):JTAG_SCM_PLD_TDI
  R512     2      B  Q_RES       I129
  R516     1      A  Q_RES       I95
  U25     F5  IO_12_TDI_1B  10M02SCU169C8G  I394

JTAG_SCM_PLD_TDO   @SCM_LIB.SCM(SCH_1):JTAG_SCM_PLD_TDO
  R513     2      B  Q_RES       I128
  R517     1      A  Q_RES       I97
  U25     F6  IO_13_TDO_1B  10M02SCU169C8G  I394

JTAG_SCM_PLD_TMS   @SCM_LIB.SCM(SCH_1):JTAG_SCM_PLD_TMS
  R511     2      B  Q_RES       I127
  R515     1      A  Q_RES       I96
  U25     G1  IO_9_TMS_1B  10M02SCU169C8G  I394

JTAG_SCM_TCK    @SCM_LIB.SCM(SCH_1):JTAG_SCM_TCK
  R202     2      B  Q_RES       I125
  R510     1      A  Q_RES       I126
  U5      B9  TCK||MNTCK1  AST2600A1GP  I41

JTAG_SCM_TDI    @SCM_LIB.SCM(SCH_1):JTAG_SCM_TDI
  R204     2      B  Q_RES       I120
  R512     1      A  Q_RES       I129
  U5      D9  TDI||MTDI1  AST2600A1GP  I41

JTAG_SCM_TDO    @SCM_LIB.SCM(SCH_1):JTAG_SCM_TDO
  R513     1      A  Q_RES       I128
  R523     2      B  Q_RES       I119
  U5      C9  TDO||MTDO1  AST2600A1GP  I41

JTAG_SCM_TMS    @SCM_LIB.SCM(SCH_1):JTAG_SCM_TMS
  R203     2      B  Q_RES       I117
  R511     1      A  Q_RES       I127
  U5      A9  TMS||MTMS1  AST2600A1GP  I41

LED1_AD1_100M   @SCM_LIB.SCM(SCH_1):LED1_AD1_100M
  J1      L2     L2  SCONN14_RS6QU0001  I95
  R305     2      B  Q_RES       I72

LED2_RXDELAY_1G   @SCM_LIB.SCM(SCH_1):LED2_RXDELAY_1G
  J1      L1     L1  SCONN14_RS6QU0001  I95
  R306     2      B  Q_RES       I71

LED3_AD0_ACT    @SCM_LIB.SCM(SCH_1):LED3_AD0_ACT
  J1      L3     L3  SCONN14_RS6QU0001  I95
  R304     2      B  Q_RES       I80

LED_POSTCODE_0_N   @SCM_LIB.SCM(SCH_1):LED_POSTCODE_0_N
  D0       C      C  Q_LED        I7
  U5     P25  GPION0||NCTS2  AST2600A1GP  I45

LED_POSTCODE_1_N   @SCM_LIB.SCM(SCH_1):LED_POSTCODE_1_N
  D1       C      C  Q_LED        I9
  U5     N23  GPION1||NDCD2  AST2600A1GP  I45

LED_POSTCODE_2_N   @SCM_LIB.SCM(SCH_1):LED_POSTCODE_2_N
  D2       C      C  Q_LED       I11
  U5     N25  GPION2||NDSR2  AST2600A1GP  I45

LED_POSTCODE_3_N   @SCM_LIB.SCM(SCH_1):LED_POSTCODE_3_N
  D3       C      C  Q_LED       I13
  U5     N24  GPION3||NRI2  AST2600A1GP  I45

LED_POSTCODE_4_N   @SCM_LIB.SCM(SCH_1):LED_POSTCODE_4_N
  D4       C      C  Q_LED       I10
  U5     P26  GPION4||NDTR2  AST2600A1GP  I45

LED_POSTCODE_5_N   @SCM_LIB.SCM(SCH_1):LED_POSTCODE_5_N
  D5       C      C  Q_LED       I12
  U5     M23  GPION5||NRTS2  AST2600A1GP  I45

LED_POSTCODE_6_N   @SCM_LIB.SCM(SCH_1):LED_POSTCODE_6_N
  D6       C      C  Q_LED       I14
  U5     N26  GPION6||TXD2  AST2600A1GP  I45

LED_POSTCODE_7_N   @SCM_LIB.SCM(SCH_1):LED_POSTCODE_7_N
  D7       C      C  Q_LED        I5
  U5     M26  GPION7||RXD2  AST2600A1GP  I45

LOADSW_CT       @SCM_LIB.SCM(SCH_1):LOADSW_CT
  C181     1      A  Q_CAP       I13
  U15      6     CT  TPS22965DSGR   I2

LOADSW_VBIAS    @SCM_LIB.SCM(SCH_1):LOADSW_VBIAS
  R387     2      B  Q_RES       I14
  R388     1      A  Q_RES       I15
  U15      4  VBIAS  TPS22965DSGR   I2

LPC_ESPI_SEL    @SCM_LIB.SCM(SCH_1):LPC_ESPI_SEL
  GF1     B9     B9  FCONN168_ME1016810106011  I171
  R41      2      B  Q_RES       I225
  R713     2      B  Q_RES       I228
  R714     1      A  Q_RES       I165

LPC_ESPI_SEL_LV5   @SCM_LIB.SCM(SCH_1):LPC_ESPI_SEL_LV5
  C268     1      A  Q_CAP       I241
  Q8       2     G1  MOSFET_DUAL_6P  I210
  Q9       D  DRAIN  MOSFET_N_GSD  I235
  R715     2      B  Q_RES       I237

LPC_ESPI_SEL_N   @SCM_LIB.SCM(SCH_1):LPC_ESPI_SEL_N
  C270     1      A  Q_CAP       I239
  Q8       5     G2  MOSFET_DUAL_6P  I210
  Q9       G   GATE  MOSFET_N_GSD  I235
  Q10      D  DRAIN  MOSFET_N_GSD  I227
  R716     2      B  Q_RES       I230

LPC_ESPI_SEL_R   @SCM_LIB.SCM(SCH_1):LPC_ESPI_SEL_R
  C273     1      A  Q_CAP       I234
  Q10      G   GATE  MOSFET_N_GSD  I227
  R713     1      A  Q_RES       I228

LPC_ESPI_SEL_R1   @SCM_LIB.SCM(SCH_1):LPC_ESPI_SEL_R1
  C267     1      A  Q_CAP       I166
  Q7       1      G  MOSFET_N_123  I157
  R714     2      B  Q_RES       I165

MB_JTAG_PLD_R_JTAGEN   @SCM_LIB.SCM(SCH_1):MB_JTAG_PLD_R_JTAGEN
  R508     2      B  Q_RES       I45
  R509     1      A  Q_RES       I47
  SW3      4      4  SW4S_DHNF02FTVTR  I37

M_BMC_DDR4_ALERT_N   @SCM_LIB.SCM(SCH_1):M_BMC_DDR4_ALERT_N
  R9       1      A  Q_RES       I111
  U1      P9  ALERT_N  K4A8G165WCBCTD  I196
  U5      N4  MALERT#  AST2600A1GP  I45

M_BMC_DDR4_BG1   @SCM_LIB.SCM(SCH_1):M_BMC_DDR4_BG1
  R1       1      A  Q_RES       I14
  R2       1      A  Q_RES       I13
  U1      M9   VSS6  K4A8G165WCBCTD  I196

M_BMC_DDR4_DQ<0>   @SCM_LIB.SCM(SCH_1):M_BMC_DDR4_DQ<0>
  U1      G2   DQL0  K4A8G165WCBCTD  I196
  U5      T3   MDQ0  AST2600A1GP  I45

M_BMC_DDR4_DQ<1>   @SCM_LIB.SCM(SCH_1):M_BMC_DDR4_DQ<1>
  U1      F7   DQL1  K4A8G165WCBCTD  I196
  U5      R4   MDQ1  AST2600A1GP  I45

M_BMC_DDR4_DQ<2>   @SCM_LIB.SCM(SCH_1):M_BMC_DDR4_DQ<2>
  U1      H3   DQL2  K4A8G165WCBCTD  I196
  U5      U1   MDQ2  AST2600A1GP  I45

M_BMC_DDR4_DQ<3>   @SCM_LIB.SCM(SCH_1):M_BMC_DDR4_DQ<3>
  U1      H7   DQL3  K4A8G165WCBCTD  I196
  U5      R3   MDQ3  AST2600A1GP  I45

M_BMC_DDR4_DQ<4>   @SCM_LIB.SCM(SCH_1):M_BMC_DDR4_DQ<4>
  U1      H2   DQL4  K4A8G165WCBCTD  I196
  U5      R1   MDQ4  AST2600A1GP  I45

M_BMC_DDR4_DQ<5>   @SCM_LIB.SCM(SCH_1):M_BMC_DDR4_DQ<5>
  U1      H8   DQL5  K4A8G165WCBCTD  I196
  U5      P1   MDQ5  AST2600A1GP  I45

M_BMC_DDR4_DQ<6>   @SCM_LIB.SCM(SCH_1):M_BMC_DDR4_DQ<6>
  U1      J3   DQL6  K4A8G165WCBCTD  I196
  U5      P2   MDQ6  AST2600A1GP  I45

M_BMC_DDR4_DQ<7>   @SCM_LIB.SCM(SCH_1):M_BMC_DDR4_DQ<7>
  U1      J7   DQL7  K4A8G165WCBCTD  I196
  U5      P3   MDQ7  AST2600A1GP  I45

M_BMC_DDR4_DQ<8>   @SCM_LIB.SCM(SCH_1):M_BMC_DDR4_DQ<8>
  U1      A3   DQU0  K4A8G165WCBCTD  I196
  U5      W2   MDQ8  AST2600A1GP  I45

M_BMC_DDR4_DQ<9>   @SCM_LIB.SCM(SCH_1):M_BMC_DDR4_DQ<9>
  U1      B8   DQU1  K4A8G165WCBCTD  I196
  U5      V3   MDQ9  AST2600A1GP  I45

M_BMC_DDR4_DQ<10>   @SCM_LIB.SCM(SCH_1):M_BMC_DDR4_DQ<10>
  U1      C3   DQU2  K4A8G165WCBCTD  I196
  U5      W1  MDQ10  AST2600A1GP  I45

M_BMC_DDR4_DQ<11>   @SCM_LIB.SCM(SCH_1):M_BMC_DDR4_DQ<11>
  U1      C7   DQU3  K4A8G165WCBCTD  I196
  U5      W3  MDQ11  AST2600A1GP  I45

M_BMC_DDR4_DQ<12>   @SCM_LIB.SCM(SCH_1):M_BMC_DDR4_DQ<12>
  U1      C2   DQU4  K4A8G165WCBCTD  I196
  U5      W4  MDQ12  AST2600A1GP  I45

M_BMC_DDR4_DQ<13>   @SCM_LIB.SCM(SCH_1):M_BMC_DDR4_DQ<13>
  U1      C8   DQU5  K4A8G165WCBCTD  I196
  U5      U4  MDQ13  AST2600A1GP  I45

M_BMC_DDR4_DQ<14>   @SCM_LIB.SCM(SCH_1):M_BMC_DDR4_DQ<14>
  U1      D3   DQU6  K4A8G165WCBCTD  I196
  U5      V4  MDQ14  AST2600A1GP  I45

M_BMC_DDR4_DQ<15>   @SCM_LIB.SCM(SCH_1):M_BMC_DDR4_DQ<15>
  U1      D7   DQU7  K4A8G165WCBCTD  I196
  U5      U3  MDQ15  AST2600A1GP  I45

M_BMC_DDR4_DQS0_N   @SCM_LIB.SCM(SCH_1):M_BMC_DDR4_DQS0_N
  U1      F3  DQSL_C  K4A8G165WCBCTD  I196
  U5      T1  MDQS0#  AST2600A1GP  I45

M_BMC_DDR4_DQS0_P   @SCM_LIB.SCM(SCH_1):M_BMC_DDR4_DQS0_P
  U1      G3  DQSL_T  K4A8G165WCBCTD  I196
  U5      T2  MDQS0  AST2600A1GP  I45

M_BMC_DDR4_DQS1_N   @SCM_LIB.SCM(SCH_1):M_BMC_DDR4_DQS1_N
  U1      A7  DQSU_C  K4A8G165WCBCTD  I196
  U5      V1  MDQS1#  AST2600A1GP  I45

M_BMC_DDR4_DQS1_P   @SCM_LIB.SCM(SCH_1):M_BMC_DDR4_DQS1_P
  U1      B7  DQSU_T  K4A8G165WCBCTD  I196
  U5      V2  MDQS1  AST2600A1GP  I45

M_BMC_DDR4_MA<0>   @SCM_LIB.SCM(SCH_1):M_BMC_DDR4_MA<0>
  R326     2      B  Q_RES       I193
  R351     1      A  Q_RES       I194
  U1      P3     A0  K4A8G165WCBCTD  I196
  U5      F3    MA0  AST2600A1GP  I45

M_BMC_DDR4_MA<1>   @SCM_LIB.SCM(SCH_1):M_BMC_DDR4_MA<1>
  R327     2      B  Q_RES       I177
  R352     1      A  Q_RES       I184
  U1      P7     A1  K4A8G165WCBCTD  I196
  U5      K5    MA1  AST2600A1GP  I45

M_BMC_DDR4_MA<2>   @SCM_LIB.SCM(SCH_1):M_BMC_DDR4_MA<2>
  R328     2      B  Q_RES       I176
  R353     1      A  Q_RES       I183
  U1      R3     A2  K4A8G165WCBCTD  I196
  U5      F1    MA2  AST2600A1GP  I45

M_BMC_DDR4_MA<3>   @SCM_LIB.SCM(SCH_1):M_BMC_DDR4_MA<3>
  R329     2      B  Q_RES       I175
  R354     1      A  Q_RES       I181
  U1      N7     A3  K4A8G165WCBCTD  I196
  U5      H3    MA3  AST2600A1GP  I45

M_BMC_DDR4_MA<4>   @SCM_LIB.SCM(SCH_1):M_BMC_DDR4_MA<4>
  R330     2      B  Q_RES       I174
  R355     1      A  Q_RES       I182
  U1      N3     A4  K4A8G165WCBCTD  I196
  U5      J3    MA4  AST2600A1GP  I45

M_BMC_DDR4_MA<5>   @SCM_LIB.SCM(SCH_1):M_BMC_DDR4_MA<5>
  R331     2      B  Q_RES       I173
  R356     1      A  Q_RES       I180
  U1      P8     A5  K4A8G165WCBCTD  I196
  U5      L1    MA5  AST2600A1GP  I45

M_BMC_DDR4_MA<6>   @SCM_LIB.SCM(SCH_1):M_BMC_DDR4_MA<6>
  R332     2      B  Q_RES       I171
  R357     1      A  Q_RES       I179
  U1      P2     A6  K4A8G165WCBCTD  I196
  U5      M5    MA6  AST2600A1GP  I45

M_BMC_DDR4_MA<7>   @SCM_LIB.SCM(SCH_1):M_BMC_DDR4_MA<7>
  R333     2      B  Q_RES       I172
  R358     1      A  Q_RES       I178
  U1      R8     A7  K4A8G165WCBCTD  I196
  U5      M2    MA7  AST2600A1GP  I45

M_BMC_DDR4_MA<8>   @SCM_LIB.SCM(SCH_1):M_BMC_DDR4_MA<8>
  R334     2      B  Q_RES       I164
  R359     1      A  Q_RES       I170
  U1      R2     A8  K4A8G165WCBCTD  I196
  U5      M1    MA8  AST2600A1GP  I45

M_BMC_DDR4_MA<9>   @SCM_LIB.SCM(SCH_1):M_BMC_DDR4_MA<9>
  R335     2      B  Q_RES       I163
  R360     1      A  Q_RES       I169
  U1      R7     A9  K4A8G165WCBCTD  I196
  U5      N1    MA9  AST2600A1GP  I45

M_BMC_DDR4_MA<10>   @SCM_LIB.SCM(SCH_1):M_BMC_DDR4_MA<10>
  R336     2      B  Q_RES       I162
  R361     1      A  Q_RES       I167
  U1      M3  A10||AP  K4A8G165WCBCTD  I196
  U5      F2   MA10  AST2600A1GP  I45

M_BMC_DDR4_MA<11>   @SCM_LIB.SCM(SCH_1):M_BMC_DDR4_MA<11>
  R337     2      B  Q_RES       I161
  R362     1      A  Q_RES       I168
  U1      T2    A11  K4A8G165WCBCTD  I196
  U5      G1   MA11  AST2600A1GP  I45

M_BMC_DDR4_MA<12>   @SCM_LIB.SCM(SCH_1):M_BMC_DDR4_MA<12>
  R338     2      B  Q_RES       I160
  R363     1      A  Q_RES       I166
  U1      M7  A12||BC_N  K4A8G165WCBCTD  I196
  U5      L4   MA12  AST2600A1GP  I45

M_BMC_DDR4_MA<13>   @SCM_LIB.SCM(SCH_1):M_BMC_DDR4_MA<13>
  R339     2      B  Q_RES       I159
  R364     1      A  Q_RES       I165
  U1      T8    A13  K4A8G165WCBCTD  I196
  U5      K3   MA13  AST2600A1GP  I45

M_BMC_DDR4_MACT_N   @SCM_LIB.SCM(SCH_1):M_BMC_DDR4_MACT_N
  R344     2      B  Q_RES       I121
  R369     1      A  Q_RES       I132
  U1      L3  ACT_N  K4A8G165WCBCTD  I196
  U5      H1  MA14||MACT#  AST2600A1GP  I45

M_BMC_DDR4_MBA0   @SCM_LIB.SCM(SCH_1):M_BMC_DDR4_MBA0
  R346     2      B  Q_RES       I120
  R371     1      A  Q_RES       I130
  U1      N2    BA0  K4A8G165WCBCTD  I196
  U5      G4   MBA0  AST2600A1GP  I45

M_BMC_DDR4_MBA1   @SCM_LIB.SCM(SCH_1):M_BMC_DDR4_MBA1
  R347     2      B  Q_RES       I117
  R372     1      A  Q_RES       I129
  U1      N8    BA1  K4A8G165WCBCTD  I196
  U5      H5   MBA1  AST2600A1GP  I45

M_BMC_DDR4_MBG0   @SCM_LIB.SCM(SCH_1):M_BMC_DDR4_MBG0
  R345     2      B  Q_RES       I119
  R370     1      A  Q_RES       I131
  U1      M2    BG0  K4A8G165WCBCTD  I196
  U5      G3  MBA2||MBG0  AST2600A1GP  I45

M_BMC_DDR4_MBG1   @SCM_LIB.SCM(SCH_1):M_BMC_DDR4_MBG1
  R1       2      B  Q_RES       I14
  R350     2      B  Q_RES       I114
  R375     1      A  Q_RES       I115
  U5      M3  MA15||MBG1  AST2600A1GP  I45

M_BMC_DDR4_MCAS_N   @SCM_LIB.SCM(SCH_1):M_BMC_DDR4_MCAS_N
  R341     2      B  Q_RES       I125
  R366     1      A  Q_RES       I137
  U1      M8  CAS_N||A15  K4A8G165WCBCTD  I196
  U5      J4  MCAS#  AST2600A1GP  I45

M_BMC_DDR4_MCKE   @SCM_LIB.SCM(SCH_1):M_BMC_DDR4_MCKE
  R349     2      B  Q_RES       I116
  R374     1      A  Q_RES       I127
  U1      K2    CKE  K4A8G165WCBCTD  I196
  U5      L5   MCKE  AST2600A1GP  I45

M_BMC_DDR4_MCLK_C   @SCM_LIB.SCM(SCH_1):M_BMC_DDR4_MCLK_C
  C12      1      A  Q_CAP       I106
  C229     1      A  Q_CAP       I107
  R7       2      B  Q_RES       I90
  R8       2      B  Q_RES       I89

M_BMC_DDR4_MCLK_DN   @SCM_LIB.SCM(SCH_1):M_BMC_DDR4_MCLK_DN
  R7       1      A  Q_RES       I90
  U1      K8   CK_C  K4A8G165WCBCTD  I196
  U5      K1   MCK#  AST2600A1GP  I45

M_BMC_DDR4_MCLK_DP   @SCM_LIB.SCM(SCH_1):M_BMC_DDR4_MCLK_DP
  R8       1      A  Q_RES       I89
  U1      K7   CK_T  K4A8G165WCBCTD  I196
  U5      K2    MCK  AST2600A1GP  I45

M_BMC_DDR4_MCS_N   @SCM_LIB.SCM(SCH_1):M_BMC_DDR4_MCS_N
  R343     2      B  Q_RES       I123
  R368     1      A  Q_RES       I135
  U1      L7   CS_N  K4A8G165WCBCTD  I196
  U5      H2   MCS#  AST2600A1GP  I45

M_BMC_DDR4_MDM0   @SCM_LIB.SCM(SCH_1):M_BMC_DDR4_MDM0
  U1      E7  DML_N||DBIL_N  K4A8G165WCBCTD  I196
  U5      N3   MDM0  AST2600A1GP  I45

M_BMC_DDR4_MDM1   @SCM_LIB.SCM(SCH_1):M_BMC_DDR4_MDM1
  U1      E2  DMU_N||DBIU_N  K4A8G165WCBCTD  I196
  U5      R5   MDM1  AST2600A1GP  I45

M_BMC_DDR4_MODT   @SCM_LIB.SCM(SCH_1):M_BMC_DDR4_MODT
  R348     2      B  Q_RES       I118
  R373     1      A  Q_RES       I128
  U1      K3    ODT  K4A8G165WCBCTD  I196
  U5      J1   MODT  AST2600A1GP  I45

M_BMC_DDR4_MRAS_N   @SCM_LIB.SCM(SCH_1):M_BMC_DDR4_MRAS_N
  R342     2      B  Q_RES       I122
  R367     1      A  Q_RES       I136
  U1      L8  RAS_N  K4A8G165WCBCTD  I196
  U5      J5  MRAS#  AST2600A1GP  I45

M_BMC_DDR4_MWE_N   @SCM_LIB.SCM(SCH_1):M_BMC_DDR4_MWE_N
  R340     2      B  Q_RES       I124
  R365     1      A  Q_RES       I138
  U1      L2  WE_N||A14  K4A8G165WCBCTD  I196
  U5      G5   MWE#  AST2600A1GP  I45

M_BMC_DDR4_RST_N   @SCM_LIB.SCM(SCH_1):M_BMC_DDR4_RST_N
  U1      P1  RESET_N  K4A8G165WCBCTD  I196
  U5      L3  MRESET#  AST2600A1GP  I45

M_BMC_DDR4_ZQU   @SCM_LIB.SCM(SCH_1):M_BMC_DDR4_ZQU
  R3       1      A  Q_RES       I17
  U1      E9   VSS2  K4A8G165WCBCTD  I196

NC              NC
  U28      6   DNU2  MX66L1G45GMI08G  I64
  U28      5   DNU1  MX66L1G45GMI08G  I64
  U28      4    NC1  MX66L1G45GMI08G  I64
  U28     14    NC3  MX66L1G45GMI08G  I64
  U28     13    NC2  MX66L1G45GMI08G  I64
  U28     12   DNU4  MX66L1G45GMI08G  I64
  U28     11   DNU3  MX66L1G45GMI08G  I64
  U14      3   FLG#  AP22811AW57  I79
  GF1    OB13   OB13  FCONN168_ME1016810106011  I171
  GF1    OB14   OB14  FCONN168_ME1016810106011  I171
  GF1    OB11   OB11  FCONN168_ME1016810106011  I171
  U5     AA9  GPIOX1||SPI2CS1#  AST2600A1GP  I45
  GF1    A52    A52  FCONN168_ME1016810106011  I171
  U17      8   RTS#  FT234XDR    I98
  U20    P10  RFU_P10  MTFC8GAKAJCN1MWT   I1
  U20     K7  RFU_K7  MTFC8GAKAJCN1MWT   I1
  U20     K6  RFU_K6  MTFC8GAKAJCN1MWT   I1
  U20    K10  RFU_K10  MTFC8GAKAJCN1MWT   I1
  U20    G10  RFU_G10  MTFC8GAKAJCN1MWT   I1
  U20    F10  RFU_F10  MTFC8GAKAJCN1MWT   I1
  U20     E9  RFU_E9  MTFC8GAKAJCN1MWT   I1
  U20     E8  RFU_E8  MTFC8GAKAJCN1MWT   I1
  U20     E5  RFU_E5  MTFC8GAKAJCN1MWT   I1
  U20    E10  RFU_E10  MTFC8GAKAJCN1MWT   I1
  U20     A7  RFU_A7  MTFC8GAKAJCN1MWT   I1
  U31      1     NC  74LVC1G07GW  I151
  U25     E9  IO_92_6  10M02SCU169C8G  I330
  U25     D8  IO_110_DEV_OE_8  10M02SCU169C8G  I330
  U25     D6  IO_123_CRC_ERROR_8  10M02SCU169C8G  I330
  U25    D11  IO_101_6  10M02SCU169C8G  I330
  U25     C9  IO_104_8  10M02SCU169C8G  I330
  U25    C12  IO_94_6  10M02SCU169C8G  I330
  U25    C11  IO_96_6  10M02SCU169C8G  I330
  U25    C10  IO_102_8  10M02SCU169C8G  I330
  U25     B9  IO_108_DEV_CLRN_8  10M02SCU169C8G  I330
  U25    B13  IO_95_6  10M02SCU169C8G  I330
  U25    B12  IO_91_6  10M02SCU169C8G  I330
  U25    B11  IO_93_6  10M02SCU169C8G  I330
  U25    B10  IO_106_8  10M02SCU169C8G  I330
  U25     A9  IO_105_8  10M02SCU169C8G  I330
  U25     A8  IO_103_8  10M02SCU169C8G  I330
  U25    A12  IO_97_6  10M02SCU169C8G  I330
  U7      42   LED4  BCM54612EB1KMLG  I126
  GF1    B68    B68  FCONN168_ME1016810106011  I171
  GF1    B65    B65  FCONN168_ME1016810106011  I171
  GF1    B62    B62  FCONN168_ME1016810106011  I171
  GF1    B59    B59  FCONN168_ME1016810106011  I171
  GF1    B69    B69  FCONN168_ME1016810106011  I171
  GF1    B66    B66  FCONN168_ME1016810106011  I171
  GF1    B63    B63  FCONN168_ME1016810106011  I171
  GF1    B60    B60  FCONN168_ME1016810106011  I171
  GF1    A68    A68  FCONN168_ME1016810106011  I171
  GF1    A65    A65  FCONN168_ME1016810106011  I171
  GF1    A62    A62  FCONN168_ME1016810106011  I171
  GF1    A59    A59  FCONN168_ME1016810106011  I171
  GF1    A69    A69  FCONN168_ME1016810106011  I171
  GF1    A66    A66  FCONN168_ME1016810106011  I171
  GF1    A63    A63  FCONN168_ME1016810106011  I171
  GF1    A60    A60  FCONN168_ME1016810106011  I171
  J40      6    NC3  SCONN16_ACASPI006P06  I53
  J40      5    NC2  SCONN16_ACASPI006P06  I53
  J40      4    NC1  SCONN16_ACASPI006P06  I53
  J40     14    NC8  SCONN16_ACASPI006P06  I53
  J40     13    NC7  SCONN16_ACASPI006P06  I53
  J40     12    NC6  SCONN16_ACASPI006P06  I53
  J40     11    NC4  SCONN16_ACASPI006P06  I53
  J121     6    NC3  SCONN16_ACASPI006P06  I97
  J121     5    NC2  SCONN16_ACASPI006P06  I97
  J121     4    NC1  SCONN16_ACASPI006P06  I97
  J121    14    NC8  SCONN16_ACASPI006P06  I97
  J121    13    NC7  SCONN16_ACASPI006P06  I97
  J121    12    NC6  SCONN16_ACASPI006P06  I97
  J121    11    NC4  SCONN16_ACASPI006P06  I97
  U32      1     NC  74LVC1G17GW  I49
  GF1    OB8    OB8  FCONN168_ME1016810106011  I171
  GF1    OB9    OB9  FCONN168_ME1016810106011  I171
  U35      6    IO4  TPD4E001DBVR  I70
  D10      6      6  BZA462A     I59
  U20     H5     DS  MTFC8GAKAJCN1MWT  I38
  J3      10  ML_LANE_3_P  SCONN20_3VM11207D7307H  I127
  J3      12  ML_LANE_3_N  SCONN20_3VM11207D7307H  I127
  J3      15  ML_LANE_2_P  SCONN20_3VM11207D7307H  I127
  J3      17  ML_LANE_2_N  SCONN20_3VM11207D7307H  I127
  U17     11   CTS#  FT234XDR    I98
  U5     A10  RGMIICK  AST2600A1GP  I45
  U17      6  CBUS0  FT234XDR    I98
  U5     AF2  RCTXP  AST2600A1GP  I45
  U5     AF3  RCTXN  AST2600A1GP  I45
  U5     AD2  RCRXP  AST2600A1GP  I45
  U5     AD3  RCRXN  AST2600A1GP  I45
  U5     AE1  RCREFCLKP  AST2600A1GP  I45
  U5     AE2  RCREFCLKN  AST2600A1GP  I45
  U21     14   I_0D  IDTQS3VH257PAG  I296
  U21     13   I_1D  IDTQS3VH257PAG  I296
  U21     12     YD  IDTQS3VH257PAG  I296
  U30     14   I_0D  IDTQS3VH257PAG  I271
  U30     13   I_1D  IDTQS3VH257PAG  I271
  U30     12     YD  IDTQS3VH257PAG  I271
  R530     2      B  Q_RES       I85
  R585     2      B  Q_RES       I87
  R529     2      B  Q_RES       I84
  U20     P9  NC_P9  MTFC8GAKAJCN1MWT   I1
  U20     P8  NC_P8  MTFC8GAKAJCN1MWT   I1
  U20     P7  NC_P7  MTFC8GAKAJCN1MWT   I1
  U20     P2  NC_P2  MTFC8GAKAJCN1MWT   I1
  U20    P14  NC_P14  MTFC8GAKAJCN1MWT   I1
  U20    P13  NC_P13  MTFC8GAKAJCN1MWT   I1
  U20    P12  NC_P12  MTFC8GAKAJCN1MWT   I1
  U20    P11  NC_P11  MTFC8GAKAJCN1MWT   I1
  U20     P1  NC_P1  MTFC8GAKAJCN1MWT   I1
  U20     N9  NC_N9  MTFC8GAKAJCN1MWT   I1
  U20     N8  NC_N8  MTFC8GAKAJCN1MWT   I1
  U20     N7  NC_N7  MTFC8GAKAJCN1MWT   I1
  U20     N6  NC_N6  MTFC8GAKAJCN1MWT   I1
  U20     N3  NC_N3  MTFC8GAKAJCN1MWT   I1
  U20    N14  NC_N14  MTFC8GAKAJCN1MWT   I1
  U20    N13  NC_N13  MTFC8GAKAJCN1MWT   I1
  U20    N12  NC_N12  MTFC8GAKAJCN1MWT   I1
  U20    N11  NC_N11  MTFC8GAKAJCN1MWT   I1
  U20    N10  NC_N10  MTFC8GAKAJCN1MWT   I1
  U20     N1  NC_N1  MTFC8GAKAJCN1MWT   I1
  U20     M9  NC_M9  MTFC8GAKAJCN1MWT   I1
  U20     M8  NC_M8  MTFC8GAKAJCN1MWT   I1
  U20     M7  NC_M7  MTFC8GAKAJCN1MWT   I1
  U20     M3  NC_M3  MTFC8GAKAJCN1MWT   I1
  U20     M2  NC_M2  MTFC8GAKAJCN1MWT   I1
  U20    M14  NC_M14  MTFC8GAKAJCN1MWT   I1
  U20    M13  NC_M13  MTFC8GAKAJCN1MWT   I1
  U20    M12  NC_M12  MTFC8GAKAJCN1MWT   I1
  U20    M11  NC_M11  MTFC8GAKAJCN1MWT   I1
  U20    M10  NC_M10  MTFC8GAKAJCN1MWT   I1
  U20     M1  NC_M1  MTFC8GAKAJCN1MWT   I1
  U20     L3  NC_L3  MTFC8GAKAJCN1MWT   I1
  U20     L2  NC_L2  MTFC8GAKAJCN1MWT   I1
  U20    L14  NC_L14  MTFC8GAKAJCN1MWT   I1
  U20    L13  NC_L13  MTFC8GAKAJCN1MWT   I1
  U20    L12  NC_L12  MTFC8GAKAJCN1MWT   I1
  U20     L1  NC_L1  MTFC8GAKAJCN1MWT   I1
  U20     K3  NC_K3  MTFC8GAKAJCN1MWT   I1
  U20     K2  NC_K2  MTFC8GAKAJCN1MWT   I1
  U20    K14  NC_K14  MTFC8GAKAJCN1MWT   I1
  U20    K13  NC_K13  MTFC8GAKAJCN1MWT   I1
  U20    K12  NC_K12  MTFC8GAKAJCN1MWT   I1
  U20     K1  NC_K1  MTFC8GAKAJCN1MWT   I1
  U20     J3  NC_J3  MTFC8GAKAJCN1MWT   I1
  U20     J2  NC_J2  MTFC8GAKAJCN1MWT   I1
  U20    J14  NC_J14  MTFC8GAKAJCN1MWT   I1
  U20    J13  NC_J13  MTFC8GAKAJCN1MWT   I1
  U20    J12  NC_J12  MTFC8GAKAJCN1MWT   I1
  U20     J1  NC_J1  MTFC8GAKAJCN1MWT   I1
  U20     H3  NC_H3  MTFC8GAKAJCN1MWT   I1
  U20     H2  NC_H2  MTFC8GAKAJCN1MWT   I1
  U20    H14  NC_H14  MTFC8GAKAJCN1MWT   I1
  U20    H13  NC_H13  MTFC8GAKAJCN1MWT   I1
  U20    H12  NC_H12  MTFC8GAKAJCN1MWT   I1
  U20     H1  NC_H1  MTFC8GAKAJCN1MWT   I1
  U20     G3  NC_G3  MTFC8GAKAJCN1MWT   I1
  U20     G2  NC_G2  MTFC8GAKAJCN1MWT   I1
  U20    G14  NC_G14  MTFC8GAKAJCN1MWT   I1
  U20    G13  NC_G13  MTFC8GAKAJCN1MWT   I1
  U20    G12  NC_G12  MTFC8GAKAJCN1MWT   I1
  U20     G1  NC_G1  MTFC8GAKAJCN1MWT   I1
  U20     F3  NC_F3  MTFC8GAKAJCN1MWT   I1
  U20     F2  NC_F2  MTFC8GAKAJCN1MWT   I1
  U20    F14  NC_F14  MTFC8GAKAJCN1MWT   I1
  U20    F13  NC_F13  MTFC8GAKAJCN1MWT   I1
  U20    F12  NC_F12  MTFC8GAKAJCN1MWT   I1
  U20     F1  NC_F1  MTFC8GAKAJCN1MWT   I1
  U20     E3  NC_E3  MTFC8GAKAJCN1MWT   I1
  U20     E2  NC_E2  MTFC8GAKAJCN1MWT   I1
  U20    E14  NC_E14  MTFC8GAKAJCN1MWT   I1
  U20    E13  NC_E13  MTFC8GAKAJCN1MWT   I1
  U20    E12  NC_E12  MTFC8GAKAJCN1MWT   I1
  U20     E1  NC_E1  MTFC8GAKAJCN1MWT   I1
  U20     D4  NC_D4  MTFC8GAKAJCN1MWT   I1
  U20     D3  NC_D3  MTFC8GAKAJCN1MWT   I1
  U20     D2  NC_D2  MTFC8GAKAJCN1MWT   I1
  U20    D14  NC_D14  MTFC8GAKAJCN1MWT   I1
  U20    D13  NC_D13  MTFC8GAKAJCN1MWT   I1
  U20    D12  NC_D12  MTFC8GAKAJCN1MWT   I1
  U20     D1  NC_D1  MTFC8GAKAJCN1MWT   I1
  U20     C9  NC_C9  MTFC8GAKAJCN1MWT   I1
  U20     C8  NC_C8  MTFC8GAKAJCN1MWT   I1
  U20     C7  NC_C7  MTFC8GAKAJCN1MWT   I1
  U20     C5  NC_C5  MTFC8GAKAJCN1MWT   I1
  U20     C3  NC_C3  MTFC8GAKAJCN1MWT   I1
  U20    C14  NC_C14  MTFC8GAKAJCN1MWT   I1
  U20    C13  NC_C13  MTFC8GAKAJCN1MWT   I1
  U20    C12  NC_C12  MTFC8GAKAJCN1MWT   I1
  U20    C11  NC_C11  MTFC8GAKAJCN1MWT   I1
  U20    C10  NC_C10  MTFC8GAKAJCN1MWT   I1
  U20     C1  NC_C1  MTFC8GAKAJCN1MWT   I1
  U20     B9  NC_B9  MTFC8GAKAJCN1MWT   I1
  U20     B8  NC_B8  MTFC8GAKAJCN1MWT   I1
  U20     B7  NC_B7  MTFC8GAKAJCN1MWT   I1
  U20    B14  NC_B14  MTFC8GAKAJCN1MWT   I1
  U20    B13  NC_B13  MTFC8GAKAJCN1MWT   I1
  U20    B12  NC_B12  MTFC8GAKAJCN1MWT   I1
  U20    B11  NC_B11  MTFC8GAKAJCN1MWT   I1
  U20    B10  NC_B10  MTFC8GAKAJCN1MWT   I1
  U20     B1  NC_B1  MTFC8GAKAJCN1MWT   I1
  U20     A9  NC_A9  MTFC8GAKAJCN1MWT   I1
  U20     A8  NC_A8  MTFC8GAKAJCN1MWT   I1
  U20     A2  NC_A2  MTFC8GAKAJCN1MWT   I1
  U20    A14  NC_A14  MTFC8GAKAJCN1MWT   I1
  U20    A13  NC_A13  MTFC8GAKAJCN1MWT   I1
  U20    A12  NC_A12  MTFC8GAKAJCN1MWT   I1
  U20    A11  NC_A11  MTFC8GAKAJCN1MWT   I1
  U20    A10  NC_A10  MTFC8GAKAJCN1MWT   I1
  U20     A1  NC_A1  MTFC8GAKAJCN1MWT   I1
  U5     AD24  GPIOO3||PWM3  AST2600A1GP  I41
  U25     D2   NC_2  10M02SCU169C8G  I96
  U25     D3   NC_1  10M02SCU169C8G  I96
  U25     E2   NC_0  10M02SCU169C8G  I96
  U13      1    NC1  SN74LVC1G07DCKR  I15
  U23      1     NC  SN74LVC1G07DBVR   I2
  DM19     1      1  DUMMY_SYMBOL  I26
  DM10     1      1  DUMMY_SYMBOL  I15
  DM7      1      1  DUMMY_SYMBOL  I10
  DM4      1      1  DUMMY_SYMBOL   I9
  DM5      1      1  DUMMY_SYMBOL   I5
  DM2      1      1  DUMMY_SYMBOL   I3
  H2B2     1      1  HOLE        I34
  H2B1     1      1  HOLE        I14

P0V6_DDR_VREF_AUX   @SCM_LIB.SCM(SCH_1):P0V6_DDR_VREF_AUX
  C10      1      A  Q_CAP       I85
  C21      1      A  Q_CAP       I24
  C22      1      A  Q_CAP       I27
  C23      1      A  Q_CAP       I28
  C168     1      A  Q_CAP       I32
  C169     2      B  Q_CAP       I34
  C170     1      A  Q_CAP       I33
  R324     2      B  Q_RES       I28
  R325     1      A  Q_RES       I27
  U1      M1  VREFCA  K4A8G165WCBCTD  I196
  U5      T5  MVREF_T5  AST2600A1GP  I45
  U5      U5  MVREF_U5  AST2600A1GP  I45

P12V_AUX        @SCM_LIB.SCM(SCH_1):P12V_AUX
  C329     1      A  Q_CAP       I449
  C330     1      A  Q_CAP       I448
  GF1    OA1    OA1  FCONN168_ME1016810106011  I171
  GF1    OA2    OA2  FCONN168_ME1016810106011  I171
  GF1    OB1    OB1  FCONN168_ME1016810106011  I171
  GF1    OB2    OB2  FCONN168_ME1016810106011  I171
  PL4      1      1  Q_INDUCTOR  I39
  PL19     1      1  Q_INDUCTOR  I32
  PL29     1      1  Q_INDUCTOR  I31
  PL32     1      1  Q_INDUCTOR  I34
  PR521    1      A  Q_RES        I4
  R785     1      A  Q_RES       I202

P12V_SENSOR     @SCM_LIB.SCM(SCH_1):P12V_SENSOR
  C290     1      A  Q_CAP       I201
  R785     2      B  Q_RES       I202
  R786     1      A  Q_RES       I203
  U5     AD20  ADC0||GPIT0  AST2600A1GP  I41

P1V0_AUX        @SCM_LIB.SCM(SCH_1):P1V0_AUX
  C86      1      A  Q_CAP       I149
  C92      1      A  Q_CAP       I150
  C99      1      A  Q_CAP       I154
  C104     1      A  Q_CAP       I155
  C108     1      A  Q_CAP       I157
  C113     1      A  Q_CAP       I160
  C118     1      A  Q_CAP       I162
  C123     1      A  Q_CAP       I171
  L6       1      1  Q_INDUCTOR  I124
  L8       1      1  Q_INDUCTOR  I29
  L13      1      1  Q_INDUCTOR  I158
  L15      1      1  Q_INDUCTOR  I170
  PC266    1      A  Q_CAP       I23
  PC267    1      A  Q_CAP       I24
  PC268    1      A  Q_CAP       I25
  PC269    1      A  Q_CAP       I28
  PC270    1      A  Q_CAP       I29
  PL33     2      2  Q_INDUCTOR  I37
  PU42    12   VOUT  NB695GDZ    I15
  R279     1      A  Q_RES       I95
  R281     1      A  Q_RES       I92
  R796     1      A  Q_RES       I255
  U5      L9  IV10D_L9  AST2600A1GP  I181
  U5     L10  IV10D_L10  AST2600A1GP  I181
  U5      M8  IV10D_M8  AST2600A1GP  I181
  U5     M11  IV10D_M11  AST2600A1GP  I181
  U5      N8  IV10D_N8  AST2600A1GP  I181
  U5     N11  IV10D_N11  AST2600A1GP  I181
  U5      P8  IV10D_P8  AST2600A1GP  I181
  U5     P11  IV10D_P11  AST2600A1GP  I181
  U5      R9  IV10D_R9  AST2600A1GP  I181
  U5     R10  IV10D_R10  AST2600A1GP  I181
  U43      5  SENSE  TPS3808G33DBVR  I60

P1V0_AUX_MODE   @SCM_LIB.SCM(SCH_1):P1V0_AUX_MODE
  PR543    1      A  Q_RES        I6
  PU42     7   MODE  NB695GDZ    I15

P1V0_AUX_VCC    @SCM_LIB.SCM(SCH_1):P1V0_AUX_VCC
  PC260    1      A  Q_CAP        I7
  PR541    2      B  Q_RES        I8
  PU42     3     C1  NB695GDZ    I15
  PU42     6    LP#  NB695GDZ    I15
  PU42    10    3V3  NB695GDZ    I15

P1V0_SENSOR     @SCM_LIB.SCM(SCH_1):P1V0_SENSOR
  C311     1      A  Q_CAP       I256
  R796     2      B  Q_RES       I255
  U5     AB17  ADC10||GPIU2||SALT11  AST2600A1GP  I41

P1V0_STBY_DP_VCC10A   @SCM_LIB.SCM(SCH_1):P1V0_STBY_DP_VCC10A
  C90      1      A  Q_CAP       I173
  C97      1      A  Q_CAP       I169
  L15      2      2  Q_INDUCTOR  I170
  U5      T8  DP_VCC10A  AST2600A1GP  I181

P1V0_STBY_PE_VCC10A   @SCM_LIB.SCM(SCH_1):P1V0_STBY_PE_VCC10A
  C78      1      A  Q_CAP       I160
  C79      1      A  Q_CAP       I157
  L13      2      2  Q_INDUCTOR  I158
  U5      T9  RC_VCC10A  AST2600A1GP  I181

P1V0_STBY_PLAVDD   @SCM_LIB.SCM(SCH_1):P1V0_STBY_PLAVDD
  C52      1      A  Q_CAP       I31
  C54      1      A  Q_CAP       I32
  C56      1      A  Q_CAP       I33
  C59      1      A  Q_CAP       I79
  C64      1      A  Q_CAP       I81
  C68      1      A  Q_CAP       I82
  L8       2      2  Q_INDUCTOR  I29
  U5      E7  PLLAVDD_E7  AST2600A1GP  I181
  U5      E9  PLLDVDD_E9  AST2600A1GP  I181
  U5      F7  PLLAVDD_F7  AST2600A1GP  I181
  U5      F9  PLLDVDD_F9  AST2600A1GP  I181
  U5      J9  DPLLAVDD  AST2600A1GP  I181

P1V0_STBY_RC_VCC10A   @SCM_LIB.SCM(SCH_1):P1V0_STBY_RC_VCC10A
  C47      1      A  Q_CAP       I128
  C50      1      A  Q_CAP       I126
  L6       2      2  Q_INDUCTOR  I124
  U5     T10  PE_VCC10A  AST2600A1GP  I181

P1V2_AUX        @SCM_LIB.SCM(SCH_1):P1V2_AUX
  C1       1      A  Q_CAP        I4
  C2       1      A  Q_CAP        I5
  C3       1      A  Q_CAP        I6
  C4       1      A  Q_CAP        I7
  C5       1      A  Q_CAP       I23
  C7       1      A  Q_CAP       I24
  C9       1      A  Q_CAP       I25
  C13      1      A  Q_CAP       I186
  C14      1      A  Q_CAP       I187
  C15      1      A  Q_CAP       I134
  C16      1      A  Q_CAP       I113
  C17      1      A  Q_CAP       I190
  C18      1      A  Q_CAP       I192
  C55      1      A  Q_CAP       I23
  C58      1      A  Q_CAP       I52
  C62      1      A  Q_CAP       I53
  C66      1      A  Q_CAP       I54
  C70      1      A  Q_CAP       I57
  C72      1      A  Q_CAP       I58
  C74      1      A  Q_CAP       I66
  C76      1      A  Q_CAP       I183
  C82      1      A  Q_CAP       I180
  C84      1      A  Q_CAP       I179
  C91      1      A  Q_CAP       I151
  C98      1      A  Q_CAP       I163
  C103     1      A  Q_CAP       I164
  C107     1      A  Q_CAP       I165
  C112     1      A  Q_CAP       I166
  C117     1      A  Q_CAP       I167
  C122     1      A  Q_CAP       I168
  C127     1      A  Q_CAP       I173
  C129     1      A  Q_CAP       I174
  C131     1      A  Q_CAP       I176
  C132     1      A  Q_CAP       I177
  C169     1      A  Q_CAP       I34
  C221     1      A  Q_CAP       I199
  C222     1      A  Q_CAP       I198
  C225     1      A  Q_CAP       I197
  C229     2      B  Q_CAP       I107
  L2       1      1  Q_INDUCTOR  I272
  L11      1      1  Q_INDUCTOR  I47
  PC255    1      A  Q_CAP       I23
  PC256    1      A  Q_CAP       I24
  PC257    1      A  Q_CAP       I25
  PC258    1      A  Q_CAP       I28
  PC259    1      A  Q_CAP       I29
  PL31     2      2  Q_INDUCTOR  I21
  PU41    12   VOUT  NB695GDZ    I15
  R9       2      B  Q_RES       I111
  R278     1      A  Q_RES       I101
  R280     1      A  Q_RES       I94
  R324     1      A  Q_RES       I28
  R351     2      B  Q_RES       I194
  R352     2      B  Q_RES       I184
  R353     2      B  Q_RES       I183
  R354     2      B  Q_RES       I181
  R355     2      B  Q_RES       I182
  R356     2      B  Q_RES       I180
  R357     2      B  Q_RES       I179
  R358     2      B  Q_RES       I178
  R359     2      B  Q_RES       I170
  R360     2      B  Q_RES       I169
  R361     2      B  Q_RES       I167
  R362     2      B  Q_RES       I168
  R363     2      B  Q_RES       I166
  R364     2      B  Q_RES       I165
  R365     2      B  Q_RES       I138
  R366     2      B  Q_RES       I137
  R367     2      B  Q_RES       I136
  R368     2      B  Q_RES       I135
  R369     2      B  Q_RES       I132
  R370     2      B  Q_RES       I131
  R371     2      B  Q_RES       I130
  R372     2      B  Q_RES       I129
  R373     2      B  Q_RES       I128
  R374     2      B  Q_RES       I127
  R375     2      B  Q_RES       I115
  R782     1      A  Q_RES       I264
  R784     1      A  Q_RES       I267
  R795     1      A  Q_RES       I252
  U1      A1  VDDQ0  K4A8G165WCBCTD  I196
  U1      A9  VDDQ1  K4A8G165WCBCTD  I196
  U1      B3   VDD0  K4A8G165WCBCTD  I196
  U1      B9   VDD1  K4A8G165WCBCTD  I196
  U1      C1  VDDQ2  K4A8G165WCBCTD  I196
  U1      D1   VDD2  K4A8G165WCBCTD  I196
  U1      D9  VDDQ3  K4A8G165WCBCTD  I196
  U1      F2  VDDQ4  K4A8G165WCBCTD  I196
  U1      F8  VDDQ5  K4A8G165WCBCTD  I196
  U1      G1  VDDQ6  K4A8G165WCBCTD  I196
  U1      G7   VDD3  K4A8G165WCBCTD  I196
  U1      G9  VDDQ7  K4A8G165WCBCTD  I196
  U1      J1   VDD4  K4A8G165WCBCTD  I196
  U1      J2  VDDQ8  K4A8G165WCBCTD  I196
  U1      J8  VDDQ9  K4A8G165WCBCTD  I196
  U1      J9   VDD5  K4A8G165WCBCTD  I196
  U1      L1   VDD6  K4A8G165WCBCTD  I196
  U1      L9   VDD7  K4A8G165WCBCTD  I196
  U1      R1   VDD8  K4A8G165WCBCTD  I196
  U1      T9   VDD9  K4A8G165WCBCTD  I196
  U5      G6  MVDD_G6  AST2600A1GP  I181
  U5      H6  MVDD_H6  AST2600A1GP  I181
  U5      J6  MVDD_J6  AST2600A1GP  I181
  U5      K6  MVDD_K6  AST2600A1GP  I181
  U5     K16  IV12D_K16  AST2600A1GP  I181
  U5     K17  IV12D_K17  AST2600A1GP  I181
  U5     K18  IV12D_K18  AST2600A1GP  I181
  U5     K19  IV12D_K19  AST2600A1GP  I181
  U5      L6  MVDD_L6  AST2600A1GP  I181
  U5     L14  IV12D_L14  AST2600A1GP  I181
  U5     L21  IV12D_L21  AST2600A1GP  I181
  U5     M14  IV12D_M14  AST2600A1GP  I181
  U5     M21  IV12D_M21  AST2600A1GP  I181
  U5     N14  IV12D_N14  AST2600A1GP  I181
  U5     N21  IV12D_N21  AST2600A1GP  I181
  U5      P6  MVDD_P6  AST2600A1GP  I181
  U5     P14  IV12D_P14  AST2600A1GP  I181
  U5     P21  IV12D_P21  AST2600A1GP  I181
  U5      R6  MVDD_R6  AST2600A1GP  I181
  U5     R14  IV12D_R14  AST2600A1GP  I181
  U5     R21  IV12D_R21  AST2600A1GP  I181
  U5      T6  MVDD_T6  AST2600A1GP  I181
  U5     T14  IV12D_T14  AST2600A1GP  I181
  U5     T21  IV12D_T21  AST2600A1GP  I181
  U5     U15  IV12D_U15  AST2600A1GP  I181
  U5     U16  IV12D_U16  AST2600A1GP  I181
  U5     U17  IV12D_U17  AST2600A1GP  I181
  U5     U18  IV12D_U18  AST2600A1GP  I181

P1V2_AUX_MODE   @SCM_LIB.SCM(SCH_1):P1V2_AUX_MODE
  PR496    1      A  Q_RES        I6
  PU41     7   MODE  NB695GDZ    I15

P1V2_AUX_VCC    @SCM_LIB.SCM(SCH_1):P1V2_AUX_VCC
  PC250    1      A  Q_CAP        I7
  PR539    2      B  Q_RES        I8
  PU41     6    LP#  NB695GDZ    I15
  PU41    10    3V3  NB695GDZ    I15

P1V2_P1V0_I3C_VDDL1   @SCM_LIB.SCM(SCH_1):P1V2_P1V0_I3C_VDDL1
  C139     1      A  Q_CAP       I98
  R188     1      A  Q_RES       I82
  R189     1      A  Q_RES       I85
  R190     1      A  Q_RES       I11
  R191     1      A  Q_RES       I10
  R194     1      A  Q_RES       I86
  R195     1      A  Q_RES       I89
  R196     1      A  Q_RES       I27
  R197     1      A  Q_RES       I25
  R278     2      B  Q_RES       I101
  R279     2      B  Q_RES       I95
  U5     V22  I3CVDDL1  AST2600A1GP  I181

P1V2_P1V0_I3C_VDDL2   @SCM_LIB.SCM(SCH_1):P1V2_P1V0_I3C_VDDL2
  C140     1      A  Q_CAP       I97
  R280     2      B  Q_RES       I94
  R281     2      B  Q_RES       I92
  U5     U21  I3CVDDL2  AST2600A1GP  I181

P1V2_PHY0       @SCM_LIB.SCM(SCH_1):P1V2_PHY0
  C305     1      A  Q_CAP       I170
  C332     1      A  Q_CAP       I171
  C349     1      A  Q_CAP       I212
  L32      2      2  Q_INDUCTOR  I173
  L33      2      2  Q_INDUCTOR  I172
  U7       2  DVDD_1  BCM54612EB1KMLG  I126
  U7       3  REGOUT  BCM54612EB1KMLG  I126
  U7      30  DVDD_2  BCM54612EB1KMLG  I126

P1V2_PHY0_AVDDL   @SCM_LIB.SCM(SCH_1):P1V2_PHY0_AVDDL
  C297     1      A  Q_CAP       I165
  C328     1      A  Q_CAP       I166
  C347     1      A  Q_CAP       I168
  L32      1      1  Q_INDUCTOR  I173
  U7      13  AVDDL_1  BCM54612EB1KMLG  I126
  U7      19  AVDDL_2  BCM54612EB1KMLG  I126
  U7      25  AVDDL_3  BCM54612EB1KMLG  I126

P1V2_PHY0_PLLVDD   @SCM_LIB.SCM(SCH_1):P1V2_PHY0_PLLVDD
  C265     1      A  Q_CAP       I157
  C346     1      A  Q_CAP       I211
  L33      1      1  Q_INDUCTOR  I172
  U7      11  PLLVDD  BCM54612EB1KMLG  I126

P1V2_SENSOR     @SCM_LIB.SCM(SCH_1):P1V2_SENSOR
  C309     1      A  Q_CAP       I247
  R795     2      B  Q_RES       I252
  U5     AB18  ADC6||GPIT6  AST2600A1GP  I41

P1V2_STBY_MVDD_CK   @SCM_LIB.SCM(SCH_1):P1V2_STBY_MVDD_CK
  C63      1      A  Q_CAP       I46
  C67      1      A  Q_CAP       I48
  C71      1      A  Q_CAP       I49
  C73      1      A  Q_CAP       I51
  L11      2      2  Q_INDUCTOR  I47
  U5      M6  MVDD_CK  AST2600A1GP  I181

P1V8_AUX        @SCM_LIB.SCM(SCH_1):P1V8_AUX
  C87      1      A  Q_CAP       I147
  C89      1      A  Q_CAP       I118
  C93      1      A  Q_CAP       I148
  C95      1      A  Q_CAP       I119
  C100     1      A  Q_CAP       I152
  C102     1      A  Q_CAP       I126
  C105     1      A  Q_CAP       I153
  C106     1      A  Q_CAP       I127
  C109     1      A  Q_CAP       I156
  C111     1      A  Q_CAP       I128
  C114     1      A  Q_CAP       I158
  C116     1      A  Q_CAP       I129
  C119     1      A  Q_CAP       I159
  C121     1      A  Q_CAP       I131
  C124     1      A  Q_CAP       I169
  C126     1      A  Q_CAP       I143
  C226     1      A  Q_CAP       I71
  C227     1      A  Q_CAP       I72
  C232     1      A  Q_CAP       I20
  C233     1      A  Q_CAP       I21
  L3       1      1  Q_INDUCTOR  I65
  L5       1      1  Q_INDUCTOR  I120
  L10      1      1  Q_INDUCTOR  I24
  L14      1      1  Q_INDUCTOR  I154
  L16      1      1  Q_INDUCTOR  I166
  PC248    1      A  Q_CAP       I65
  PC249    1      A  Q_CAP       I66
  PU40     1  VOUT1  RT9059GQW   I96
  PU40     2  VOUT2  RT9059GQW   I96
  PU40     3  VOUT3  RT9059GQW   I96
  Q8       3     D2  MOSFET_DUAL_6P  I210
  R154     1      A  Q_RES        I3
  R164     1      A  Q_RES       I17
  R208     1      A  Q_RES        I2
  R214     1      A  Q_RES       I32
  R232     1      A  Q_RES       I136
  R655     1      A  Q_RES       I59
  R656     1      A  Q_RES       I60
  R657     1      A  Q_RES       I61
  R658     1      A  Q_RES       I58
  R659     1      A  Q_RES       I57
  R660     1      A  Q_RES       I55
  R661     1      A  Q_RES       I53
  R662     1      A  Q_RES       I54
  R663     1      A  Q_RES       I52
  R686     1      A  Q_RES       I125
  R687     1      A  Q_RES       I126
  R781     1      A  Q_RES       I263
  R783     1      A  Q_RES       I260
  R793     1      A  Q_RES       I244
  R831     1      A  Q_RES       I98
  U5      H8  PV18D_H8  AST2600A1GP  I181
  U5     H12  PV18D_RGM_H12  AST2600A1GP  I181
  U5      J8  PV18D_J8  AST2600A1GP  I181
  U5     J12  PV18D_RGM_J12  AST2600A1GP  I181
  U5     L13  PV18D_SLI_L13  AST2600A1GP  I181
  U5     M13  PV18D_SLI_M13  AST2600A1GP  I181
  U5     N12  PV18D_N12  AST2600A1GP  I181
  U5     N13  PV18D_SLI_N13  AST2600A1GP  I181
  U5     P12  PV18D_P12  AST2600A1GP  I181
  U5     P13  PV18D_SLI_P13  AST2600A1GP  I181
  U5     R12  PV18D_R12  AST2600A1GP  I181
  U5     R13  PV18D_SLI_R13  AST2600A1GP  I181
  U5     T13  PV18D_SLI_T13  AST2600A1GP  I181
  U5      U6  PV18D_U6  AST2600A1GP  I181
  U5     U13  PV18D_SLI_U13  AST2600A1GP  I181
  U5      V6  PV18D_V6  AST2600A1GP  I181
  U5     V13  PV18D_SLI_V13  AST2600A1GP  I181
  U5     W13  PV18D_SLI_W13  AST2600A1GP  I181
  U5     W14  PV18D_SLI_W14  AST2600A1GP  I181
  U20     C6  VCCQ_C6  MTFC8GAKAJCN1MWT  I38
  U20     M4  VCCQ_M4  MTFC8GAKAJCN1MWT  I38
  U20     N4  VCCQ_N4  MTFC8GAKAJCN1MWT  I38
  U20     P3  VCCQ_P3  MTFC8GAKAJCN1MWT  I38
  U20     P5  VCCQ_P5  MTFC8GAKAJCN1MWT  I38

P1V8_BMC_USB2AV18   @SCM_LIB.SCM(SCH_1):P1V8_BMC_USB2AV18
  C40      1      A  Q_CAP       I67
  C41      1      A  Q_CAP       I68
  L3       2      2  Q_INDUCTOR  I65
  U5     K10  USB2AV18  AST2600A1GP  I41

P1V8_SENSOR     @SCM_LIB.SCM(SCH_1):P1V8_SENSOR
  C307     1      A  Q_CAP       I240
  R793     2      B  Q_RES       I244
  R794     1      A  Q_RES       I242
  U5     AC19  ADC4||GPIT4  AST2600A1GP  I41

P1V8_STBY_AVDDPLL   @SCM_LIB.SCM(SCH_1):P1V8_STBY_AVDDPLL
  C46      1      A  Q_CAP       I122
  C49      1      A  Q_CAP       I118
  L5       2      2  Q_INDUCTOR  I120
  U5      N5  AVDDPLL  AST2600A1GP  I181

P1V8_STBY_DP_VCC18A   @SCM_LIB.SCM(SCH_1):P1V8_STBY_DP_VCC18A
  C128     1      A  Q_CAP       I165
  C130     1      A  Q_CAP       I163
  L16      2      2  Q_INDUCTOR  I166
  U5      V8  DP_VCC18A  AST2600A1GP  I181

P1V8_STBY_PE_VCC18A   @SCM_LIB.SCM(SCH_1):P1V8_STBY_PE_VCC18A
  C61      1      A  Q_CAP       I55
  C69      1      A  Q_CAP       I59
  L10      2      2  Q_INDUCTOR  I24
  U5      V9  RC_VCC18A  AST2600A1GP  I181

P1V8_STBY_RC_VCC18A   @SCM_LIB.SCM(SCH_1):P1V8_STBY_RC_VCC18A
  C80      1      A  Q_CAP       I153
  C81      1      A  Q_CAP       I151
  L14      2      2  Q_INDUCTOR  I154
  U5     V10  PE_VCC18A  AST2600A1GP  I181

P2E_BMC_RX_DN   @SCM_LIB.SCM(SCH_1):P2E_BMC_RX_DN
  C25      1      A  Q_CAP       I153
  U5     AE5  PETXN  AST2600A1GP  I45

P2E_BMC_RX_DP   @SCM_LIB.SCM(SCH_1):P2E_BMC_RX_DP
  C24      1      A  Q_CAP       I152
  U5     AE4  PETXP  AST2600A1GP  I45

P2V5_AUX        @SCM_LIB.SCM(SCH_1):P2V5_AUX
  C6       1      A  Q_CAP       I19
  C8       1      A  Q_CAP       I21
  PC235    1      A  Q_CAP       I53
  PC237    1      A  Q_CAP       I52
  PU39     1  VOUT1  RT9059GQW   I60
  PU39     2  VOUT2  RT9059GQW   I60
  PU39     3  VOUT3  RT9059GQW   I60
  R156     1      A  Q_RES        I4
  R779     1      A  Q_RES       I259
  R780     1      A  Q_RES       I256
  R791     1      A  Q_RES       I245
  R829     1      A  Q_RES       I62
  U1      B1   VPP0  K4A8G165WCBCTD  I196
  U1      R9   VPP1  K4A8G165WCBCTD  I196

P2V5_SENSOR     @SCM_LIB.SCM(SCH_1):P2V5_SENSOR
  C303     1      A  Q_CAP       I235
  R791     2      B  Q_RES       I245
  R792     1      A  Q_RES       I236
  U5     AD19  ADC3||GPIT3  AST2600A1GP  I41

P3V3_AUX        @SCM_LIB.SCM(SCH_1):P3V3_AUX
  C19      1      A  Q_CAP       I21
  C20      1      A  Q_CAP       I47
  C34      1      A  Q_CAP       I42
  C88      1      A  Q_CAP       I123
  C94      1      A  Q_CAP       I124
  C101     1      A  Q_CAP       I132
  C110     1      A  Q_CAP       I133
  C115     1      A  Q_CAP       I135
  C120     1      A  Q_CAP       I136
  C125     1      A  Q_CAP       I145
  C143     1      A  Q_CAP       I108
  C144     1      A  Q_CAP       I102
  C146     1      A  Q_CAP       I292
  C147     1      A  Q_CAP       I17
  C148     1      A  Q_CAP       I48
  C149     1      A  Q_CAP       I17
  C157     1      A  Q_CAP        I3
  C158     1      A  Q_CAP       I18
  C159     1      A  Q_CAP       I15
  C175     1      A  Q_CAP       I114
  C180     1      A  Q_CAP        I6
  C191     1      A  Q_CAP       I25
  C192     1      A  Q_CAP       I17
  C200     1      A  Q_CAP       I43
  C201     1      A  Q_CAP       I51
  C215     1      A  Q_CAP       I22
  C217     1      A  Q_CAP       I21
  C228     1      A  Q_CAP       I73
  C234     1      A  Q_CAP       I23
  C235     1      A  Q_CAP       I24
  C240     1      A  Q_CAP       I63
  C241     1      A  Q_CAP       I113
  C244     1      A  Q_CAP       I42
  C246     1      A  Q_CAP       I45
  C248     1      A  Q_CAP       I69
  C249     1      A  Q_CAP       I67
  C253     1      A  Q_CAP       I57
  C255     1      A  Q_CAP       I278
  C256     1      A  Q_CAP       I29
  C257     1      A  Q_CAP       I21
  C258     1      A  Q_CAP       I40
  C259     1      A  Q_CAP       I35
  C262     1      A  Q_CAP       I116
  C263     1      A  Q_CAP       I54
  C266     1      A  Q_CAP       I52
  C269     1      A  Q_CAP       I49
  C274     1      A  Q_CAP       I48
  C278     1      A  Q_CAP       I47
  C289     1      A  Q_CAP       I46
  C298     1      A  Q_CAP       I45
  C302     1      A  Q_CAP       I44
  C306     1      A  Q_CAP       I43
  C308     1      A  Q_CAP       I28
  C310     1      A  Q_CAP       I26
  C312     1      A  Q_CAP       I19
  C313     1      A  Q_CAP       I25
  C315     1      A  Q_CAP       I15
  C317     1      A  Q_CAP       I23
  C318     1      A  Q_CAP       I433
  C319     1      A  Q_CAP       I14
  C320     1      A  Q_CAP       I22
  C323     1      A  Q_CAP       I21
  C333     1      A  Q_CAP       I115
  C350     1      A  Q_CAP       I178
  D13      1   VCCA  PCA9517ADP   I1
  D13      8   VCCB  PCA9517ADP   I1
  J5       7      7  SCONN11_9192031111LF  I56
  J7       1      1  CONN7_4400547  I53
  J10      7      7  SCONN11_9192031111LF  I113
  J40      2    VCC  SCONN16_ACASPI006P06  I53
  J121     2    VCC  SCONN16_ACASPI006P06  I97
  L4       1      1  Q_INDUCTOR  I82
  L7       1      1  Q_INDUCTOR  I146
  L9       1      1  Q_INDUCTOR  I142
  L12      1      1  Q_INDUCTOR  I99
  L18      2      2  Q_INDUCTOR  I152
  L20      2      2  Q_INDUCTOR  I49
  L26      1      1  Q_INDUCTOR  I50
  L27      1      1  Q_INDUCTOR  I16
  L31      2      2  Q_INDUCTOR  I161
  L34      2      2  Q_INDUCTOR  I164
  OSC2     4    VDD  OSC4_7X25000018  I431
  PC225    1      A  Q_CAP       I23
  PC226    1      A  Q_CAP       I35
  PC227    1      A  Q_CAP       I36
  PC228    1      A  Q_CAP       I37
  PC229    1      A  Q_CAP       I38
  PC239    2      B  Q_CAP       I91
  PC242    1      A  Q_CAP       I63
  PC307    1      A  Q_CAP       I51
  PL35     2      2  Q_INDUCTOR  I92
  PR193    1      A  Q_RES       I47
  PR242    1      A  Q_RES       I13
  PR244    1      A  Q_RES       I46
  PR255    1      A  Q_RES       I55
  PR274    1      A  Q_RES       I45
  PR498    1      A  Q_RES       I18
  PR500    1      A  Q_RES       I18
  PR534    2      B  Q_RES       I25
  PU39     7   VIN1  RT9059GQW   I60
  PU39     8   VIN2  RT9059GQW   I60
  PU39     9   VIN3  RT9059GQW   I60
  PU40     7   VIN1  RT9059GQW   I96
  PU40     8   VIN2  RT9059GQW   I96
  PU40     9   VIN3  RT9059GQW   I96
  Q8       6     D1  MOSFET_DUAL_6P  I210
  R10      1      A  Q_RES       I42
  R11      1      A  Q_RES       I44
  R12      1      A  Q_RES        I9
  R13      1      A  Q_RES       I11
  R14      1      A  Q_RES       I14
  R34      1      A  Q_RES       I194
  R38      1      A  Q_RES       I200
  R41      1      A  Q_RES       I225
  R42      1      A  Q_RES       I159
  R44      1      A  Q_RES       I175
  R45      1      A  Q_RES       I176
  R50      1      A  Q_RES       I104
  R55      1      A  Q_RES       I278
  R56      1      A  Q_RES       I279
  R57      1      A  Q_RES       I280
  R58      1      A  Q_RES       I281
  R59      1      A  Q_RES       I98
  R61      1      A  Q_RES       I204
  R62      1      A  Q_RES       I350
  R67      1      A  Q_RES       I121
  R68      1      A  Q_RES       I179
  R69      1      A  Q_RES       I227
  R70      1      A  Q_RES       I197
  R72      1      A  Q_RES       I123
  R73      1      A  Q_RES       I118
  R74      1      A  Q_RES       I117
  R75      1      A  Q_RES       I110
  R76      1      A  Q_RES       I230
  R77      1      A  Q_RES       I128
  R78      1      A  Q_RES       I129
  R79      1      A  Q_RES       I130
  R81      1      A  Q_RES       I245
  R82      1      A  Q_RES       I232
  R101     1      A  Q_RES       I214
  R103     1      A  Q_RES       I219
  R105     1      A  Q_RES       I78
  R124     1      A  Q_RES       I67
  R140     1      A  Q_RES       I200
  R145     1      A  Q_RES       I154
  R149     1      A  Q_RES       I153
  R155     1      A  Q_RES        I5
  R161     1      A  Q_RES       I218
  R163     1      A  Q_RES       I212
  R167     1      A  Q_RES       I33
  R169     1      A  Q_RES       I253
  R193     1      A  Q_RES       I46
  R207     1      A  Q_RES        I4
  R213     1      A  Q_RES       I34
  R226     1      A  Q_RES       I103
  R227     1      A  Q_RES       I104
  R230     1      A  Q_RES       I105
  R231     1      A  Q_RES       I131
  R238     1      A  Q_RES       I184
  R239     1      A  Q_RES       I185
  R240     1      A  Q_RES       I187
  R241     1      A  Q_RES       I186
  R244     1      A  Q_RES       I147
  R245     1      A  Q_RES       I146
  R246     1      A  Q_RES       I145
  R247     1      A  Q_RES       I109
  R248     1      A  Q_RES       I107
  R249     1      A  Q_RES       I108
  R250     1      A  Q_RES       I106
  R251     1      A  Q_RES       I104
  R252     1      A  Q_RES       I105
  R253     1      A  Q_RES       I103
  R254     1      A  Q_RES       I101
  R255     1      A  Q_RES       I102
  R256     1      A  Q_RES       I100
  R257     1      A  Q_RES       I99
  R258     1      A  Q_RES       I98
  R259     1      A  Q_RES       I96
  R260     1      A  Q_RES       I97
  R261     1      A  Q_RES       I94
  R262     1      A  Q_RES       I93
  R264     1      A  Q_RES       I89
  R265     1      A  Q_RES       I88
  R266     1      A  Q_RES       I95
  R267     1      A  Q_RES       I85
  R268     1      A  Q_RES       I86
  R269     1      A  Q_RES       I84
  R274     1      A  Q_RES       I16
  R287     1      A  Q_RES        I5
  R289     1      A  Q_RES        I7
  R291     1      A  Q_RES        I9
  R295     1      A  Q_RES        I8
  R298     1      A  Q_RES       I31
  R299     1      A  Q_RES       I32
  R383     1      A  Q_RES       I42
  R387     1      A  Q_RES       I14
  R389     1      A  Q_RES       I16
  R407     1      A  Q_RES       I42
  R414     1      A  Q_RES       I29
  R416     1      A  Q_RES       I30
  R418     1      A  Q_RES       I39
  R422     1      A  Q_RES       I203
  R428     1      A  Q_RES       I210
  R429     1      A  Q_RES       I209
  R430     1      A  Q_RES       I188
  R438     1      A  Q_RES       I208
  R441     1      A  Q_RES       I415
  R446     1      A  Q_RES       I299
  R452     1      A  Q_RES       I339
  R455     1      A  Q_RES       I125
  R464     1      A  Q_RES       I75
  R488     1      A  Q_RES       I33
  R490     1      A  Q_RES       I34
  R492     1      A  Q_RES       I35
  R496     1      A  Q_RES       I48
  R497     1      A  Q_RES       I78
  R502     1      A  Q_RES       I112
  R504     1      A  Q_RES       I82
  R508     1      A  Q_RES       I45
  R521     1      A  Q_RES       I91
  R555     1      A  Q_RES       I28
  R556     1      A  Q_RES       I19
  R557     1      A  Q_RES       I37
  R558     1      A  Q_RES       I32
  R563     1      A  Q_RES       I48
  R568     1      A  Q_RES       I93
  R569     1      A  Q_RES       I98
  R581     1      A  Q_RES        I2
  R586     1      A  Q_RES       I49
  R587     1      A  Q_RES       I47
  R588     1      A  Q_RES       I45
  R591     1      A  Q_RES       I43
  R592     1      A  Q_RES       I41
  R593     1      A  Q_RES       I39
  R595     1      A  Q_RES       I37
  R596     1      A  Q_RES       I35
  R597     1      A  Q_RES       I18
  R598     1      A  Q_RES       I20
  R599     1      A  Q_RES       I23
  R600     1      A  Q_RES       I25
  R601     1      A  Q_RES       I31
  R602     1      A  Q_RES       I33
  R603     1      A  Q_RES       I35
  R604     1      A  Q_RES       I37
  R605     1      A  Q_RES       I33
  R606     1      A  Q_RES       I31
  R607     1      A  Q_RES       I29
  R608     1      A  Q_RES       I27
  R609     1      A  Q_RES       I25
  R610     1      A  Q_RES       I92
  R611     1      A  Q_RES       I23
  R612     1      A  Q_RES       I21
  R613     1      A  Q_RES       I19
  R615     1      A  Q_RES       I34
  R617     1      A  Q_RES       I17
  R619     1      A  Q_RES       I15
  R621     1      A  Q_RES       I13
  R622     1      A  Q_RES       I11
  R624     1      A  Q_RES       I44
  R625     1      A  Q_RES       I401
  R626     1      A  Q_RES        I9
  R627     1      A  Q_RES        I7
  R632     1      A  Q_RES        I5
  R633     1      A  Q_RES       I81
  R640     1      A  Q_RES       I51
  R641     1      A  Q_RES       I53
  R683     1      A  Q_RES       I188
  R692     1      A  Q_RES       I90
  R699     1      A  Q_RES       I163
  R706     1      A  Q_RES       I354
  R710     1      A  Q_RES       I55
  R716     1      A  Q_RES       I230
  R717     1      A  Q_RES       I174
  R768     1      A  Q_RES       I89
  R774     1      A  Q_RES       I213
  R789     1      A  Q_RES       I219
  R806     1      A  Q_RES       I436
  R808     2      B  Q_RES       I273
  R809     2      B  Q_RES       I274
  R810     2      B  Q_RES       I275
  R814     1      A  Q_RES       I130
  R815     1      A  Q_RES       I132
  R816     2      B  Q_RES       I125
  R821     1      A  Q_RES       I220
  R828     1      A  Q_RES       I241
  R842     1      A  Q_RES       I168
  R843     1      A  Q_RES       I177
  R844     1      A  Q_RES       I179
  R845     1      A  Q_RES       I178
  R846     1      A  Q_RES       I181
  R848     1      A  Q_RES       I182
  R851     1      A  Q_RES       I184
  R870     1      A  Q_RES       I315
  U2       5    VCC  SN74LVC1G3157DCKR  I20
  U3       5    VCC  SN74LVC1G3157DCKR  I43
  U4       8     V+  TMP75AIDGKR  I23
  U5     H15  PV33D_H15  AST2600A1GP  I181
  U5     H16  PV33D_H16  AST2600A1GP  I181
  U5     H17  PV33D_H17  AST2600A1GP  I181
  U5     N22  PV33D_N22  AST2600A1GP  I181
  U5     P22  PV33D_P22  AST2600A1GP  I181
  U5     R22  PV33D_R22  AST2600A1GP  I181
  U5     T22  PV33D_T22  AST2600A1GP  I181
  U5     W16  PV33D_W16  AST2600A1GP  I181
  U5     W17  PV33D_W17  AST2600A1GP  I181
  U5     W18  PV33D_W18  AST2600A1GP  I181
  U5     W19  PV33D_W19  AST2600A1GP  I181
  U6       5    VCC  SN74LVC2G07DCKR  I64
  U7       1   OVDD  BCM54612EB1KMLG  I126
  U7       4  REGSUPPLY  BCM54612EB1KMLG  I126
  U7      29  OVDD_RGMII_1  BCM54612EB1KMLG  I126
  U7      34  OVDD_RGMII_2  BCM54612EB1KMLG  I126
  U13      5    VCC  SN74LVC1G07DCKR  I15
  U14      5     IN  AP22811AW57  I79
  U15      1   VIN1  TPS22965DSGR   I2
  U15      2   VIN2  TPS22965DSGR   I2
  U19      8    VCC  M24128BWDW6TP  I15
  U20     E6  VCC_E6  MTFC8GAKAJCN1MWT  I38
  U20     F5  VCC_F5  MTFC8GAKAJCN1MWT  I38
  U20    J10  VCC_J10  MTFC8GAKAJCN1MWT  I38
  U20     K9  VCC_K9  MTFC8GAKAJCN1MWT  I38
  U21     16    VCC  IDTQS3VH257PAG  I296
  U23      5    VCC  SN74LVC1G07DBVR   I2
  U24      5    VCC  SN74LVC2G07DCKR  I115
  U25     C6  VCCIO8_2  10M02SCU169C8G  I96
  U25     C7  VCCIO8_1  10M02SCU169C8G  I96
  U25     C8  VCCIO8_0  10M02SCU169C8G  I96
  U25     F2  VCCIO1_0  10M02SCU169C8G  I96
  U25    F11  VCCIO6_1  10M02SCU169C8G  I96
  U25     G3  VCCIO1_1  10M02SCU169C8G  I96
  U25    G11  VCCIO6_0  10M02SCU169C8G  I96
  U25    H11  VCCIO5_1  10M02SCU169C8G  I96
  U25     J3  VCCIO2_1  10M02SCU169C8G  I96
  U25    J11  VCCIO5_0  10M02SCU169C8G  I96
  U25     K3  VCCIO2_0  10M02SCU169C8G  I96
  U25     L6  VCCIO3_2  10M02SCU169C8G  I96
  U25     L7  VCCIO3_1  10M02SCU169C8G  I96
  U25     L8  VCCIO3_0  10M02SCU169C8G  I96
  U28      2    VCC  MX66L1G45GMI08G  I64
  U29      5      5  74HC1G126GW  I67
  U30     16    VCC  IDTQS3VH257PAG  I271
  U31      5    VCC  74LVC1G07GW  I151
  U32      5    VCC  74LVC1G17GW  I49
  U36      5      5  74HC1G126GW  I43
  U43      6    VDD  TPS3808G33DBVR  I60

P3V3_AUX_CS     @SCM_LIB.SCM(SCH_1):P3V3_AUX_CS
  PR276    2      B  Q_RES       I87
  PU1      4     CS  MPQ8626GDZ  I82

P3V3_AUX_DVDD   @SCM_LIB.SCM(SCH_1):P3V3_AUX_DVDD
  R283     1      A  Q_RES       I31
  R284     1      A  Q_RES       I27
  R285     1      A  Q_RES       I29
  R307     1      A  Q_RES       I20
  R309     1      A  Q_RES       I22
  R311     1      A  Q_RES       I23
  R319     1      A  Q_RES       I118

P3V3_AUX_FB_RC   @SCM_LIB.SCM(SCH_1):P3V3_AUX_FB_RC
  PC239    1      A  Q_CAP       I91
  PR530    2      B  Q_RES       I17
  PR534    1      A  Q_RES       I25
  PU1      6     FB  MPQ8626GDZ  I82

P3V3_AUX_MODE   @SCM_LIB.SCM(SCH_1):P3V3_AUX_MODE
  PR532    2      B  Q_RES       I88
  PU1     12   MODE  MPQ8626GDZ  I82

P3V3_AUX_REF    @SCM_LIB.SCM(SCH_1):P3V3_AUX_REF
  PC273    1      A  Q_CAP       I86
  PU1      8  TRK_REF  MPQ8626GDZ  I82

P3V3_AUX_RJ45   @SCM_LIB.SCM(SCH_1):P3V3_AUX_RJ45
  C160     1      A  Q_CAP       I48
  C162     1      A  Q_CAP       I51
  L20      1      1  Q_INDUCTOR  I49
  R301     1      A  Q_RES        I2

P3V3_AUX_VCC    @SCM_LIB.SCM(SCH_1):P3V3_AUX_VCC
  PC221    1      A  Q_CAP        I9
  PU1     13    VCC  MPQ8626GDZ  I82

P3V3_AVDD       @SCM_LIB.SCM(SCH_1):P3V3_AVDD
  C293     1      A  Q_CAP       I156
  C301     1      A  Q_CAP       I159
  C331     1      A  Q_CAP       I160
  C348     1      A  Q_CAP       I163
  L34      1      1  Q_INDUCTOR  I164
  U7      16  AVDD_1  BCM54612EB1KMLG  I126
  U7      22  AVDD_2  BCM54612EB1KMLG  I126

P3V3_BIASVDD    @SCM_LIB.SCM(SCH_1):P3V3_BIASVDD
  C334     1      A  Q_CAP       I154
  L31      1      1  Q_INDUCTOR  I161
  U7      12  BIASVDD  BCM54612EB1KMLG  I126

P3V3_BMC_USB2AV33   @SCM_LIB.SCM(SCH_1):P3V3_BMC_USB2AV33
  C44      1      A  Q_CAP       I88
  C45      1      A  Q_CAP       I89
  L4       2      2  Q_INDUCTOR  I82
  U5     J10  USB2AV33  AST2600A1GP  I41

P3V3_DP         @SCM_LIB.SCM(SCH_1):P3V3_DP
  C182     1      A  Q_CAP        I8
  L1       1      1  Q_FUSE      I108
  U15      7  VOUT1  TPS22965DSGR   I2
  U15      8  VOUT2  TPS22965DSGR   I2

P3V3_DP_L       @SCM_LIB.SCM(SCH_1):P3V3_DP_L
  C183     1      A  Q_CAP       I102
  C184     1      A  Q_CAP       I101
  J3      20  DP_PWR  SCONN20_3VM11207D7307H  I127
  L1       2      2  Q_FUSE      I108
  U16      5    VCC  TPD4E001DBVR  I51

P3V3_LED        @SCM_LIB.SCM(SCH_1):P3V3_LED
  C196     1      A  Q_CAP       I109
  Q12      5     G2  MOSFET_DUAL_6P  I105
  R816     1      A  Q_RES       I125

P3V3_P1V8_I2C_I3C   @SCM_LIB.SCM(SCH_1):P3V3_P1V8_I2C_I3C
  C53      1      A  Q_CAP       I135
  C57      1      A  Q_CAP       I133
  R231     2      B  Q_RES       I131
  R232     2      B  Q_RES       I136
  U5     F19  I3CVDDH_F19  AST2600A1GP  I181
  U5     F20  I3CVDDH_F20  AST2600A1GP  I181

P3V3_P1V8_SD1VDD   @SCM_LIB.SCM(SCH_1):P3V3_P1V8_SD1VDD
  C35      1      A  Q_CAP       I14
  C36      1      A  Q_CAP       I16
  R207     2      B  Q_RES        I4
  R208     2      B  Q_RES        I2
  U5     G21  SD1VDD_G21  AST2600A1GP  I181
  U5     H21  SD1VDD_H21  AST2600A1GP  I181

P3V3_P1V8_SD2VDD   @SCM_LIB.SCM(SCH_1):P3V3_P1V8_SD2VDD
  C38      1      A  Q_CAP       I36
  C39      1      A  Q_CAP       I37
  R213     2      B  Q_RES       I34
  R214     2      B  Q_RES       I32
  U5     H18  SD2VDD_H18  AST2600A1GP  I181
  U5     H19  SD2VDD_H19  AST2600A1GP  I181

P3V3_P2V5_P1V8_RVDD   @SCM_LIB.SCM(SCH_1):P3V3_P2V5_P1V8_RVDD
  C30      1      A  Q_CAP       I29
  C31      1      A  Q_CAP       I30
  C32      1      A  Q_CAP       I31
  C33      1      A  Q_CAP       I32
  R154     2      B  Q_RES        I3
  R155     2      B  Q_RES        I5
  R156     2      B  Q_RES        I4
  U5     J21  RVDD_J21  AST2600A1GP  I181
  U5     K21  RVDD_K21  AST2600A1GP  I181
  U5     L22  RVDD_L22  AST2600A1GP  I181
  U5     M22  RVDD_M22  AST2600A1GP  I181

P3V3_PL2303     @SCM_LIB.SCM(SCH_1):P3V3_PL2303
  C187     1      A  Q_CAP       I93
  R398     1      A  Q_RES       I96
  R401     1      A  Q_RES       I90
  U17      2  RESET#  FT234XDR    I98
  U17      3  3V3OUT  FT234XDR    I98
  U17      9  VCCIO  FT234XDR    I98

P3V3_RGM        @SCM_LIB.SCM(SCH_1):P3V3_RGM
  C37      1      A  Q_CAP       I24
  C85      1      A  Q_CAP       I120
  C251     1      A  Q_CAP       I66
  OSC1     4    VDD  OSC4_7X25000018  I39
  R31      1      A  Q_RES       I27
  R32      1      A  Q_RES       I50
  R86      1      A  Q_RES       I51
  R203     1      A  Q_RES       I117
  R204     1      A  Q_RES       I120
  R211     1      A  Q_RES       I51
  R212     1      A  Q_RES       I21
  R523     1      A  Q_RES       I119
  R559     1      A  Q_RES       I58
  R560     1      A  Q_RES       I56
  R623     1      A  Q_RES       I152
  R709     1      A  Q_RES       I72
  U5     K11  PV33D_RGM_K11  AST2600A1GP  I181
  U5     K12  PV33D_RGM_K12  AST2600A1GP  I181
  U14      1    OUT  AP22811AW57  I79

P3V3_RTC_AUX    @SCM_LIB.SCM(SCH_1):P3V3_RTC_AUX
  C83      1      A  Q_CAP       I106
  U5     V23  BATVDD  AST2600A1GP  I181

P3V3_SENSOR     @SCM_LIB.SCM(SCH_1):P3V3_SENSOR
  C299     1      A  Q_CAP       I215
  R789     2      B  Q_RES       I219
  R790     1      A  Q_RES       I220
  U5     AE19  ADC2||GPIT2  AST2600A1GP  I41

P3V3_STBY_DACAV33   @SCM_LIB.SCM(SCH_1):P3V3_STBY_DACAV33
  C48      1      A  Q_CAP       I148
  C51      1      A  Q_CAP       I145
  L7       2      2  Q_INDUCTOR  I146
  U5     V21  DACAV33_V21  AST2600A1GP  I181
  U5     W21  DACAV33_W21  AST2600A1GP  I181

P3V3_STBY_PLLAHVDD   @SCM_LIB.SCM(SCH_1):P3V3_STBY_PLLAHVDD
  C60      1      A  Q_CAP       I141
  C65      1      A  Q_CAP       I139
  L2       2      2  Q_INDUCTOR  I272
  L9       2      2  Q_INDUCTOR  I142
  U5     H14  PLLAHVDD  AST2600A1GP  I181

P3V3_XTALVDD    @SCM_LIB.SCM(SCH_1):P3V3_XTALVDD
  C288     1      A  Q_CAP       I150
  L18      1      1  Q_INDUCTOR  I152
  U7       9  XTALVDD  BCM54612EB1KMLG  I126

P3V_BAT_R       @SCM_LIB.SCM(SCH_1):P3V_BAT_R
  C174     1      A  Q_CAP       I503
  GF1    B41    B41  FCONN168_ME1016810106011  I171
  R777     1      A  Q_RES       I289

P3V_BAT_R1      @SCM_LIB.SCM(SCH_1):P3V_BAT_R1
  Q11      D  DRAIN  MOSFET_N_GSD  I179
  R777     2      B  Q_RES       I289

P3V_BAT_SENSOR   @SCM_LIB.SCM(SCH_1):P3V_BAT_SENSOR
  C275     1      A  Q_CAP       I180
  Q11      S  SOURCE  MOSFET_N_GSD  I179
  R778     1      A  Q_RES       I181
  U5     AE18  ADC7||GPIT7  AST2600A1GP  I41

P5V_AUX         @SCM_LIB.SCM(SCH_1):P5V_AUX
  C171     1      A  Q_CAP       I38
  C172     1      A  Q_CAP       I35
  C202     1      A  Q_CAP       I11
  C203     1      A  Q_CAP       I12
  D9       A      A  SCHOTTKY_AC  I42
  D11      A      A  SCHOTTKY_AC  I41
  PC212    1      A  Q_CAP       I31
  PC213    1      A  Q_CAP       I32
  PC214    1      A  Q_CAP       I33
  PC215    1      A  Q_CAP       I36
  PC217    1      A  Q_CAP       I37
  PC233    1      A  Q_CAP       I15
  PC243    1      A  Q_CAP       I57
  PC272    2      B  Q_CAP       I27
  PL34     2      2  Q_INDUCTOR  I28
  PR205    1      A  Q_RES       I48
  PR275    1      A  Q_RES       I48
  PR527    2      B  Q_RES       I30
  PU39    10    VDD  RT9059GQW   I60
  PU40    10    VDD  RT9059GQW   I96
  R18      1      A  Q_RES       I19
  R27      1      A  Q_RES       I40
  R376     1      A  Q_RES       I62
  R715     1      A  Q_RES       I237
  R787     1      A  Q_RES       I223
  U10      1     IN  TPS2553DBVR1  I51

P5V_AUX_CS      @SCM_LIB.SCM(SCH_1):P5V_AUX_CS
  PR525    1      A  Q_RES        I9
  PU38     3     CS  MPQ8633AGLEC807Z  I42

P5V_AUX_FB      @SCM_LIB.SCM(SCH_1):P5V_AUX_FB
  PC272    1      A  Q_CAP       I27
  PR526    1      A  Q_RES       I26
  PR527    1      A  Q_RES       I30
  PU38     7     FB  MPQ8633AGLEC807Z  I42

P5V_AUX_REF     @SCM_LIB.SCM(SCH_1):P5V_AUX_REF
  PC271    1      A  Q_CAP       I22
  PU38     5  TRK_REF  MPQ8633AGLEC807Z  I42

P5V_AUX_VBUS    @SCM_LIB.SCM(SCH_1):P5V_AUX_VBUS
  J4       1   VBUS  SCONN5_2UB2141000111F  I83
  R406     2      B  Q_RES       I75

P5V_AUX_VCC     @SCM_LIB.SCM(SCH_1):P5V_AUX_VCC
  PC208    1      A  Q_CAP       I13
  PR241    1      A  Q_RES       I21
  PU38    19    VCC  MPQ8633AGLEC807Z  I42

P5V_BUS         @SCM_LIB.SCM(SCH_1):P5V_BUS
  C188     1      A  Q_CAP       I79
  C189     1      A  Q_CAP       I78
  C190     1      A  Q_CAP       I76
  R406     1      A  Q_RES       I75
  U17      4    VCC  FT234XDR    I98

P5V_SENSOR      @SCM_LIB.SCM(SCH_1):P5V_SENSOR
  C295     1      A  Q_CAP       I207
  R787     2      B  Q_RES       I223
  R788     1      A  Q_RES       I211
  U5     AC18  ADC1||GPIT1  AST2600A1GP  I41

P5V_USB_REAR    @SCM_LIB.SCM(SCH_1):P5V_USB_REAR
  C177     1      A  Q_CAP       I34
  C178     1      A  Q_CAP       I31
  C179     1      A  Q_CAP       I30
  C327     1      A  Q_CAP       I32
  J2       1   VBUS  CONN9_GSB311131HR  I22
  U10      6    OUT  TPS2553DBVR1  I51
  U38      4    VCC  PRTR5V0U2X   I6

PCIE_BMC_RX_C_DN   @SCM_LIB.SCM(SCH_1):PCIE_BMC_RX_C_DN
  C25      2      B  Q_CAP       I153
  GF1    A19    A19  FCONN168_ME1016810106011  I171

PCIE_BMC_RX_C_DP   @SCM_LIB.SCM(SCH_1):PCIE_BMC_RX_C_DP
  C24      2      B  Q_CAP       I152
  GF1    A18    A18  FCONN168_ME1016810106011  I171

PCIE_BMC_TX_DN   @SCM_LIB.SCM(SCH_1):PCIE_BMC_TX_DN
  GF1    A16    A16  FCONN168_ME1016810106011  I171
  U5     AF6  PERXN  AST2600A1GP  I45

PCIE_BMC_TX_DP   @SCM_LIB.SCM(SCH_1):PCIE_BMC_TX_DP
  GF1    A15    A15  FCONN168_ME1016810106011  I171
  U5     AF5  PERXP  AST2600A1GP  I45

PD_BIOS_MUX_EN_N   @SCM_LIB.SCM(SCH_1):PD_BIOS_MUX_EN_N
  R405     2      B  Q_RES       I268
  R467     1      A  Q_RES       I313
  R870     2      B  Q_RES       I315
  U21     15     E*  IDTQS3VH257PAG  I296
  U30     15     E*  IDTQS3VH257PAG  I271

PD_BIOS_MUX_EN_R_N   @SCM_LIB.SCM(SCH_1):PD_BIOS_MUX_EN_R_N
  R405     1      A  Q_RES       I268
  U5     E16  GPIOI5||SIOPBO#  AST2600A1GP  I45

PD_BMC_DEBUG    @SCM_LIB.SCM(SCH_1):PD_BMC_DEBUG
  R506     1      A  Q_RES       I49
  SW3      1      1  SW4S_DHNF02FTVTR  I37

PD_BMC_DISABLE   @SCM_LIB.SCM(SCH_1):PD_BMC_DISABLE
  R431     1      A  Q_RES       I17
  SW1      1      1  SW4S_DHNF02FTVTR   I1

PD_FPGA_CONFIG_SEL   @SCM_LIB.SCM(SCH_1):PD_FPGA_CONFIG_SEL
  R811     1      A  Q_RES       I277
  U25     D7  IO_113_CONFIG_SEL_8  10M02SCU169C8G  I330

PD_FRU_WC_N     @SCM_LIB.SCM(SCH_1):PD_FRU_WC_N
  R15      1      A  Q_RES       I32
  U19      7    WC#  M24128BWDW6TP  I15

PD_INTRUDER_BMC_N   @SCM_LIB.SCM(SCH_1):PD_INTRUDER_BMC_N
  R220     1      A  Q_RES       I62
  U5     AB21  CHASI#  AST2600A1GP  I41

PD_JTAGEN       @SCM_LIB.SCM(SCH_1):PD_JTAGEN
  R507     1      A  Q_RES       I50
  SW3      2      2  SW4S_DHNF02FTVTR  I37

PD_M_BMC_DDR4_PAR   @SCM_LIB.SCM(SCH_1):PD_M_BMC_DDR4_PAR
  R4       1      A  Q_RES       I141
  U1      T3    PAR  K4A8G165WCBCTD  I196

PD_M_BMC_DDR4_TEN   @SCM_LIB.SCM(SCH_1):PD_M_BMC_DDR4_TEN
  R5       1      A  Q_RES       I142
  U1      N9    TEN  K4A8G165WCBCTD  I196

PD_M_BMC_DDR4_ZQ   @SCM_LIB.SCM(SCH_1):PD_M_BMC_DDR4_ZQ
  R6       1      A  Q_RES       I143
  U1      F9     ZQ  K4A8G165WCBCTD  I196

PD_SPI_BMC_BOOT_MOSI   @SCM_LIB.SCM(SCH_1):PD_SPI_BMC_BOOT_MOSI
  R94      1      A  Q_RES       I201
  SW2      1      1  SW4S_DHNF02FTVTR  I195

PD_SP_ENTEST    @SCM_LIB.SCM(SCH_1):PD_SP_ENTEST
  R210     2      B  Q_RES       I47
  U5     C10  ENTEST  AST2600A1GP  I41

PECI_BMC        @SCM_LIB.SCM(SCH_1):PECI_BMC
  GF1    B27    B27  FCONN168_ME1016810106011  I171
  R209     1      A  Q_RES       I19
  R216     2      B  Q_RES       I91

PECI_BMC_R      @SCM_LIB.SCM(SCH_1):PECI_BMC_R
  R216     1      A  Q_RES       I91
  U5     AF16   PECI  AST2600A1GP  I41

PGPPA_BMC_AUX   @SCM_LIB.SCM(SCH_1):PGPPA_BMC_AUX
  C96      1      A  Q_CAP       I178
  C224     1      A  Q_CAP       I180
  L17      2      2  Q_INDUCTOR  I176
  R115     1      A  Q_RES        I4
  R116     1      A  Q_RES        I3
  R117     1      A  Q_RES        I2
  R797     1      A  Q_RES       I261
  U5     W15  LPVDD  AST2600A1GP  I181

PGPPA_BMC_AUX_L   @SCM_LIB.SCM(SCH_1):PGPPA_BMC_AUX_L
  L17      1      1  Q_INDUCTOR  I176
  Q8       1     S1  MOSFET_DUAL_6P  I210
  Q8       4     S2  MOSFET_DUAL_6P  I210

PGPPA_BMC_AUX_SENSOR   @SCM_LIB.SCM(SCH_1):PGPPA_BMC_AUX_SENSOR
  C314     1      A  Q_CAP       I259
  R797     2      B  Q_RES       I261
  R798     1      A  Q_RES       I262
  U5     AB19  ADC5||GPIT5  AST2600A1GP  I41

PHYA0           @SCM_LIB.SCM(SCH_1):PHYA0
  R455     2      B  Q_RES       I125
  U7      41  PHYA0  BCM54612EB1KMLG  I126

PHY_CT          @SCM_LIB.SCM(SCH_1):PHY_CT
  C163     1      A  Q_CAP       I125
  C164     1      A  Q_CAP       I124
  J1      R5    CT1  SCONN14_RS6QU0001  I95
  J1      R6    CT2  SCONN14_RS6QU0001  I95

PHY_LED1        @SCM_LIB.SCM(SCH_1):PHY_LED1
  C166     1      A  Q_CAP       I69
  R305     1      A  Q_RES       I72
  R307     2      B  Q_RES       I20
  R308     1      A  Q_RES       I16
  U7      45   LED1  BCM54612EB1KMLG  I126

PHY_LED2        @SCM_LIB.SCM(SCH_1):PHY_LED2
  C167     1      A  Q_CAP       I66
  R306     1      A  Q_RES       I71
  R309     2      B  Q_RES       I22
  R310     1      A  Q_RES       I18
  U7      44   LED2  BCM54612EB1KMLG  I126

PHY_LED3        @SCM_LIB.SCM(SCH_1):PHY_LED3
  C165     1      A  Q_CAP       I78
  R304     1      A  Q_RES       I80
  R311     2      B  Q_RES       I23
  R312     1      A  Q_RES       I19
  U7      43   LED3  BCM54612EB1KMLG  I126

PHY_RDAC        @SCM_LIB.SCM(SCH_1):PHY_RDAC
  R400     1      A  Q_RES       I148
  U7      10   RDAC  BCM54612EB1KMLG  I126

PHY_TRD_0_N     @SCM_LIB.SCM(SCH_1):PHY_TRD_0_N
  J1      R2   TD1-  SCONN14_RS6QU0001  I95
  U7      15  TRD0-  BCM54612EB1KMLG  I126
  U8       1    IO1  TPD4E001DBVR  I93

PHY_TRD_0_P     @SCM_LIB.SCM(SCH_1):PHY_TRD_0_P
  J1      R1   TD1+  SCONN14_RS6QU0001  I95
  U7      14  TRD0+  BCM54612EB1KMLG  I126
  U8       6    IO4  TPD4E001DBVR  I93

PHY_TRD_1_N     @SCM_LIB.SCM(SCH_1):PHY_TRD_1_N
  J1      R4   TD2-  SCONN14_RS6QU0001  I95
  U7      17  TRD1-  BCM54612EB1KMLG  I126
  U8       3    IO2  TPD4E001DBVR  I93

PHY_TRD_1_P     @SCM_LIB.SCM(SCH_1):PHY_TRD_1_P
  J1      R3   TD2+  SCONN14_RS6QU0001  I95
  U7      18  TRD1+  BCM54612EB1KMLG  I126
  U8       4    IO3  TPD4E001DBVR  I93

PHY_TRD_2_N     @SCM_LIB.SCM(SCH_1):PHY_TRD_2_N
  J1      R8   TD3-  SCONN14_RS6QU0001  I95
  U7      21  TRD2-  BCM54612EB1KMLG  I126
  U9       1    IO1  TPD4E001DBVR  I94

PHY_TRD_2_P     @SCM_LIB.SCM(SCH_1):PHY_TRD_2_P
  J1      R7   TD3+  SCONN14_RS6QU0001  I95
  U7      20  TRD2+  BCM54612EB1KMLG  I126
  U9       6    IO4  TPD4E001DBVR  I94

PHY_TRD_3_N     @SCM_LIB.SCM(SCH_1):PHY_TRD_3_N
  J1     R10   TD4-  SCONN14_RS6QU0001  I95
  U7      23  TRD3-  BCM54612EB1KMLG  I126
  U9       3    IO2  TPD4E001DBVR  I94

PHY_TRD_3_P     @SCM_LIB.SCM(SCH_1):PHY_TRD_3_P
  J1      R9   TD4+  SCONN14_RS6QU0001  I95
  U7      24  TRD3+  BCM54612EB1KMLG  I126
  U9       4    IO3  TPD4E001DBVR  I94

PU39_ADJ        @SCM_LIB.SCM(SCH_1):PU39_ADJ
  PU39     4    ADJ  RT9059GQW   I60
  R829     2      B  Q_RES       I62
  R830     1      A  Q_RES       I61

PU40_ADJ        @SCM_LIB.SCM(SCH_1):PU40_ADJ
  PU40     4    ADJ  RT9059GQW   I96
  R831     2      B  Q_RES       I98
  R832     1      A  Q_RES       I97

PU_25M_BMC_CLK_EN   @SCM_LIB.SCM(SCH_1):PU_25M_BMC_CLK_EN
  OSC1     1     OE  OSC4_7X25000018  I39
  R212     2      B  Q_RES       I21

PU_25M_FPGA_CLK_EN   @SCM_LIB.SCM(SCH_1):PU_25M_FPGA_CLK_EN
  OSC2     1     OE  OSC4_7X25000018  I431
  R806     2      B  Q_RES       I436

PU_BMC_FWSPIABR_N   @SCM_LIB.SCM(SCH_1):PU_BMC_FWSPIABR_N
  R239     2      B  Q_RES       I185
  U5     AC12  GPIOY6||FWSPIABR  AST2600A1GP  I45

PU_FPGA_CONFIG_DONE   @SCM_LIB.SCM(SCH_1):PU_FPGA_CONFIG_DONE
  R808     1      A  Q_RES       I273
  U25     C5  IO_127_CONF_DONE_8  10M02SCU169C8G  I330

PU_FPGA_NCONFIG   @SCM_LIB.SCM(SCH_1):PU_FPGA_NCONFIG
  R809     1      A  Q_RES       I274
  U25     E7  IN_115_NCONFIG_8  10M02SCU169C8G  I330

PU_FPGA_NSTATUS   @SCM_LIB.SCM(SCH_1):PU_FPGA_NSTATUS
  R810     1      A  Q_RES       I275
  U25     C4  IO_125_NSTATUS_8  10M02SCU169C8G  I330

PU_FWSPIWP_N    @SCM_LIB.SCM(SCH_1):PU_FWSPIWP_N
  R240     2      B  Q_RES       I187
  U5     AB12  GPIOY7||FWSPIWP#  AST2600A1GP  I45

PU_JTAG_TCK_MUX   @SCM_LIB.SCM(SCH_1):PU_JTAG_TCK_MUX
  R615     2      B  Q_RES       I34
  SW1      2      2  SW4S_DHNF02FTVTR   I1

PU_LED_ACT      @SCM_LIB.SCM(SCH_1):PU_LED_ACT
  J1      L4     L4  SCONN14_RS6QU0001  I95
  R319     2      B  Q_RES       I118

PU_LED_POSTCODE_0_N   @SCM_LIB.SCM(SCH_1):PU_LED_POSTCODE_0_N
  D0       A      A  Q_LED        I7
  R604     2      B  Q_RES       I37

PU_LED_POSTCODE_1_N   @SCM_LIB.SCM(SCH_1):PU_LED_POSTCODE_1_N
  D1       A      A  Q_LED        I9
  R603     2      B  Q_RES       I35

PU_LED_POSTCODE_2_N   @SCM_LIB.SCM(SCH_1):PU_LED_POSTCODE_2_N
  D2       A      A  Q_LED       I11
  R602     2      B  Q_RES       I33

PU_LED_POSTCODE_3_N   @SCM_LIB.SCM(SCH_1):PU_LED_POSTCODE_3_N
  D3       A      A  Q_LED       I13
  R601     2      B  Q_RES       I31

PU_LED_POSTCODE_4_N   @SCM_LIB.SCM(SCH_1):PU_LED_POSTCODE_4_N
  D4       A      A  Q_LED       I10
  R600     2      B  Q_RES       I25

PU_LED_POSTCODE_5_N   @SCM_LIB.SCM(SCH_1):PU_LED_POSTCODE_5_N
  D5       A      A  Q_LED       I12
  R599     2      B  Q_RES       I23

PU_LED_POSTCODE_6_N   @SCM_LIB.SCM(SCH_1):PU_LED_POSTCODE_6_N
  D6       A      A  Q_LED       I14
  R598     2      B  Q_RES       I20

PU_LED_POSTCODE_7_N   @SCM_LIB.SCM(SCH_1):PU_LED_POSTCODE_7_N
  D7       A      A  Q_LED        I5
  R597     2      B  Q_RES       I18

PU_LOADSW_EN    @SCM_LIB.SCM(SCH_1):PU_LOADSW_EN
  R389     2      B  Q_RES       I16
  R390     1      A  Q_RES       I17
  U15      3     ON  TPS22965DSGR   I2

PU_RJ45_ESD     @SCM_LIB.SCM(SCH_1):PU_RJ45_ESD
  R301     2      B  Q_RES        I2
  U8       5    VCC  TPD4E001DBVR  I93
  U9       5    VCC  TPD4E001DBVR  I94

PU_SPI1ABR      @SCM_LIB.SCM(SCH_1):PU_SPI1ABR
  R241     2      B  Q_RES       I186
  U5     AD10  GPIOZ1||SPI1ABR  AST2600A1GP  I45

PU_SPI1WP_N     @SCM_LIB.SCM(SCH_1):PU_SPI1WP_N
  R683     2      B  Q_RES       I188
  U5     AE10  GPIOZ2||SPI1WP#  AST2600A1GP  I45

PU_SPI_BMC_BOOT_MISO   @SCM_LIB.SCM(SCH_1):PU_SPI_BMC_BOOT_MISO
  R70      2      B  Q_RES       I197
  SW2      2      2  SW4S_DHNF02FTVTR  I195

PVCC1_AUX       @SCM_LIB.SCM(SCH_1):PVCC1_AUX
  PR274    2      B  Q_RES       I45
  PR275    2      B  Q_RES       I48
  PR539    1      A  Q_RES        I8

PVCC2_AUX       @SCM_LIB.SCM(SCH_1):PVCC2_AUX
  PR193    2      B  Q_RES       I47
  PR205    2      B  Q_RES       I48
  PR541    1      A  Q_RES        I8

PVCCA_AUX_PLD   @SCM_LIB.SCM(SCH_1):PVCCA_AUX_PLD
  C193     1      A  Q_CAP       I17
  C194     1      A  Q_CAP       I13
  C195     1      A  Q_CAP       I11
  C339     1      A  Q_CAP       I31
  C340     1      A  Q_CAP       I20
  C341     1      A  Q_CAP       I41
  C342     1      A  Q_CAP       I39
  C343     1      A  Q_CAP       I37
  C344     1      A  Q_CAP       I36
  C345     1      A  Q_CAP       I32
  L27      2      2  Q_INDUCTOR  I16
  U25     F7  VCC_ONE_3  10M02SCU169C8G  I96
  U25     G6  VCC_ONE_2  10M02SCU169C8G  I96
  U25     G8  VCC_ONE_1  10M02SCU169C8G  I96
  U25     H7  VCC_ONE_0  10M02SCU169C8G  I96

PVCCD_PLL_AUX   @SCM_LIB.SCM(SCH_1):PVCCD_PLL_AUX
  C220     1      A  Q_CAP       I35
  C272     1      A  Q_CAP       I42
  C281     1      A  Q_CAP       I38
  C287     1      A  Q_CAP       I33
  L26      2      2  Q_INDUCTOR  I50
  U25     D4  VCCA3  10M02SCU169C8G  I96
  U25    D10  VCCA2  10M02SCU169C8G  I96
  U25     K4  VCCA1  10M02SCU169C8G  I96
  U25     K9  VCCA4  10M02SCU169C8G  I96

PVCCIO_PECI_BMC   @SCM_LIB.SCM(SCH_1):PVCCIO_PECI_BMC
  C42      1      A  Q_CAP       I117
  C43      1      A  Q_CAP       I119
  GF1    B28    B28  FCONN168_ME1016810106011  I171
  U5     AA18  PECIVDD  AST2600A1GP  I41

PWRGD_CPUPWRGD_LVC1   @SCM_LIB.SCM(SCH_1):PWRGD_CPUPWRGD_LVC1
  U5     W26  GPIOR6||TACH14  AST2600A1GP  I41
  U25     N6  IO_42_3  10M02SCU169C8G  I394

PWRGD_P1V0_AUX   @SCM_LIB.SCM(SCH_1):PWRGD_P1V0_AUX
  R49      1      A  Q_RES       I72
  R277     2      B  Q_RES       I54
  R379     2      B  Q_RES       I306

PWRGD_P1V0_AUX_DELAY   @SCM_LIB.SCM(SCH_1):PWRGD_P1V0_AUX_DELAY
  R451     1      A  Q_RES       I74
  R711     2      B  Q_RES       I49
  U6       1     1A  SN74LVC2G07DCKR  I64

PWRGD_P1V0_AUX_DELAY_BUF   @SCM_LIB.SCM(SCH_1):PWRGD_P1V0_AUX_DELAY_BUF
  R192     1      A  Q_RES       I41
  U6       6     1Y  SN74LVC2G07DCKR  I64

PWRGD_P1V0_AUX_DELAY_R1   @SCM_LIB.SCM(SCH_1):PWRGD_P1V0_AUX_DELAY_R1
  R451     2      B  Q_RES       I74
  U43      1  #RESET  TPS3808G33DBVR  I60

PWRGD_P1V0_AUX_R   @SCM_LIB.SCM(SCH_1):PWRGD_P1V0_AUX_R
  C156     1      A  Q_CAP       I51
  PR500    2      B  Q_RES       I18
  PU42    13     PG  NB695GDZ    I15
  R277     1      A  Q_RES       I54

PWRGD_P1V0_AUX_R1   @SCM_LIB.SCM(SCH_1):PWRGD_P1V0_AUX_R1
  R379     1      A  Q_RES       I306
  U25     B2  IO_129_8  10M02SCU169C8G  I330

PWRGD_P1V0_AUX_R2   @SCM_LIB.SCM(SCH_1):PWRGD_P1V0_AUX_R2
  R49      2      B  Q_RES       I72
  U43      3    #MR  TPS3808G33DBVR  I60

PWRGD_P1V2_AUX   @SCM_LIB.SCM(SCH_1):PWRGD_P1V2_AUX
  R276     2      B  Q_RES       I50
  R323     2      B  Q_RES       I305
  R399     1      A  Q_RES       I55

PWRGD_P1V2_AUX_R   @SCM_LIB.SCM(SCH_1):PWRGD_P1V2_AUX_R
  C155     1      A  Q_CAP       I52
  PR498    2      B  Q_RES       I18
  PU41    13     PG  NB695GDZ    I15
  R276     1      A  Q_RES       I50

PWRGD_P1V2_AUX_R1   @SCM_LIB.SCM(SCH_1):PWRGD_P1V2_AUX_R1
  R323     1      A  Q_RES       I305
  U25     A2  IO_128_8  10M02SCU169C8G  I330

PWRGD_P1V2_AUX_R2   @SCM_LIB.SCM(SCH_1):PWRGD_P1V2_AUX_R2
  PU42     5     EN  NB695GDZ    I15
  R399     2      B  Q_RES       I55

PWRGD_P1V8_AUX   @SCM_LIB.SCM(SCH_1):PWRGD_P1V8_AUX
  R275     1      A  Q_RES       I99
  R321     2      B  Q_RES       I303
  R380     1      A  Q_RES       I98
  R764     1      A  Q_RES       I41

PWRGD_P1V8_AUX_R   @SCM_LIB.SCM(SCH_1):PWRGD_P1V8_AUX_R
  C154     1      A  Q_CAP       I100
  PR255    2      B  Q_RES       I55
  PU40     5  PGOOD  RT9059GQW   I96
  R275     2      B  Q_RES       I99

PWRGD_P1V8_AUX_R1   @SCM_LIB.SCM(SCH_1):PWRGD_P1V8_AUX_R1
  R321     1      A  Q_RES       I303
  U25     B4  IO_124_8  10M02SCU169C8G  I330

PWRGD_P1V8_AUX_R2   @SCM_LIB.SCM(SCH_1):PWRGD_P1V8_AUX_R2
  R380     2      B  Q_RES       I98
  U14      4     EN  AP22811AW57  I79

PWRGD_P2V5_AUX   @SCM_LIB.SCM(SCH_1):PWRGD_P2V5_AUX
  R35      1      A  Q_RES       I58
  R320     2      B  Q_RES       I304
  R393     1      A  Q_RES       I102

PWRGD_P2V5_AUX_R   @SCM_LIB.SCM(SCH_1):PWRGD_P2V5_AUX_R
  C153     1      A  Q_CAP       I64
  PR244    2      B  Q_RES       I46
  PU39     5  PGOOD  RT9059GQW   I60
  R35      2      B  Q_RES       I58

PWRGD_P2V5_AUX_R1   @SCM_LIB.SCM(SCH_1):PWRGD_P2V5_AUX_R1
  R320     1      A  Q_RES       I304
  U25     B3  IO_122_8  10M02SCU169C8G  I330

PWRGD_P2V5_AUX_R2   @SCM_LIB.SCM(SCH_1):PWRGD_P2V5_AUX_R2
  PU40     6     EN  RT9059GQW   I96
  R393     2      B  Q_RES       I102

PWRGD_P3V3_AUX   @SCM_LIB.SCM(SCH_1):PWRGD_P3V3_AUX
  R293     2      B  Q_RES       I95
  R318     2      B  Q_RES       I301
  R382     1      A  Q_RES       I65

PWRGD_P3V3_AUX_R   @SCM_LIB.SCM(SCH_1):PWRGD_P3V3_AUX_R
  C151     1      A  Q_CAP       I93
  PR242    2      B  Q_RES       I13
  PU1      9  PGOOD  MPQ8626GDZ  I82
  R293     1      A  Q_RES       I95

PWRGD_P3V3_AUX_R1   @SCM_LIB.SCM(SCH_1):PWRGD_P3V3_AUX_R1
  R318     1      A  Q_RES       I301
  U25     E6  IO_121_8  10M02SCU169C8G  I330

PWRGD_P3V3_AUX_R2   @SCM_LIB.SCM(SCH_1):PWRGD_P3V3_AUX_R2
  PU39     6     EN  RT9059GQW   I60
  R382     2      B  Q_RES       I65

PWRGD_P3V3_RGM   @SCM_LIB.SCM(SCH_1):PWRGD_P3V3_RGM
  R99      2      B  Q_RES       I96
  R322     2      B  Q_RES       I307
  R708     1      A  Q_RES       I38

PWRGD_P3V3_RGM_R   @SCM_LIB.SCM(SCH_1):PWRGD_P3V3_RGM_R
  C252     1      A  Q_CAP       I73
  R99      1      A  Q_RES       I96
  R709     2      B  Q_RES       I72

PWRGD_P3V3_RGM_R1   @SCM_LIB.SCM(SCH_1):PWRGD_P3V3_RGM_R1
  R322     1      A  Q_RES       I307
  U25     A5  IO_126_8  10M02SCU169C8G  I330

PWRGD_P5V_AUX   @SCM_LIB.SCM(SCH_1):PWRGD_P5V_AUX
  R141     2      B  Q_RES       I302
  R292     2      B  Q_RES       I51
  R381     1      A  Q_RES       I97

PWRGD_P5V_AUX_R   @SCM_LIB.SCM(SCH_1):PWRGD_P5V_AUX_R
  C150     1      A  Q_CAP       I49
  PR241    2      B  Q_RES       I21
  PR245    1      A  Q_RES       I43
  PU38     9  PGOOD  MPQ8633AGLEC807Z  I42
  R292     1      A  Q_RES       I51

PWRGD_P5V_AUX_R1   @SCM_LIB.SCM(SCH_1):PWRGD_P5V_AUX_R1
  R141     1      A  Q_RES       I302
  U25     A3  IO_120_8  10M02SCU169C8G  I330

PWRGD_P5V_AUX_R2   @SCM_LIB.SCM(SCH_1):PWRGD_P5V_AUX_R2
  PU1      5     EN  MPQ8626GDZ  I82
  R381     2      B  Q_RES       I97

PWRGD_PCH_PWROK   @SCM_LIB.SCM(SCH_1):PWRGD_PCH_PWROK
  U5     T23  GPIOR5||TACH13  AST2600A1GP  I41
  U25     G4  IO_15_1B  10M02SCU169C8G  I394

PWRGD_PSU_AC_PWROK   @SCM_LIB.SCM(SCH_1):PWRGD_PSU_AC_PWROK
  R66      2      B  Q_RES       I181
  R243     1      A  Q_RES       I293
  R711     1      A  Q_RES       I49
  R836     1      A  Q_RES       I225
  R837     1      A  Q_RES       I406

PWRGD_PSU_AC_PWROK_BMC   @SCM_LIB.SCM(SCH_1):PWRGD_PSU_AC_PWROK_BMC
  R836     2      B  Q_RES       I225
  U5     A12  GPIOM2||NDSR1  AST2600A1GP  I45

PWRGD_PSU_AC_PWROK_PLD   @SCM_LIB.SCM(SCH_1):PWRGD_PSU_AC_PWROK_PLD
  R837     2      B  Q_RES       I406
  U25     E3  IO_4_1A  10M02SCU169C8G  I394

PWRGD_PSU_AC_PWROK_R   @SCM_LIB.SCM(SCH_1):PWRGD_PSU_AC_PWROK_R
  GF1    A44    A44  FCONN168_ME1016810106011  I171
  R243     2      B  Q_RES       I293

PWRGD_SYS_PWROK   @SCM_LIB.SCM(SCH_1):PWRGD_SYS_PWROK
  GF1    A48    A48  FCONN168_ME1016810106011  I171
  R40      2      B  Q_RES       I171
  R840     1      A  Q_RES       I295
  R841     2      B  Q_RES       I289

PWRGD_SYS_PWROK_BMC   @SCM_LIB.SCM(SCH_1):PWRGD_SYS_PWROK_BMC
  R840     2      B  Q_RES       I295
  U5     B12  GPIOM4||NDTR1  AST2600A1GP  I45

PWRGD_SYS_PWROK_PLD   @SCM_LIB.SCM(SCH_1):PWRGD_SYS_PWROK_PLD
  R841     1      A  Q_RES       I289
  U25    A11  IO_109_8  10M02SCU169C8G  I330

PWR_BTN_BMC_N   @SCM_LIB.SCM(SCH_1):PWR_BTN_BMC_N
  R80      2      B  Q_RES       I467
  R81      2      B  Q_RES       I245
  R225     2      B  Q_RES       I290
  U25     N4  IO_39_3  10M02SCU169C8G  I394
  U31      4      Y  74LVC1G07GW  I151

PWR_LED         @SCM_LIB.SCM(SCH_1):PWR_LED
  Q12      2     G1  MOSFET_DUAL_6P  I105
  R316     2      B  Q_RES       I318
  R317     2      B  Q_RES       I300
  R839     1      A  Q_RES       I140

PWR_LED_BUF     @SCM_LIB.SCM(SCH_1):PWR_LED_BUF
  Q12      6     D1  MOSFET_DUAL_6P  I105
  R812     1      A  Q_RES       I128

PWR_LED_BUF_R   @SCM_LIB.SCM(SCH_1):PWR_LED_BUF_R
  C326     1      A  Q_CAP       I133
  D14      C      C  Q_LED       I142
  R812     2      B  Q_RES       I128
  R814     2      B  Q_RES       I130

PWR_LED_CPLD    @SCM_LIB.SCM(SCH_1):PWR_LED_CPLD
  R317     1      A  Q_RES       I300
  U25     B5  IO_119_8  10M02SCU169C8G  I330

PWR_LED_P3V3_AUX   @SCM_LIB.SCM(SCH_1):PWR_LED_P3V3_AUX
  C321     1      A  Q_CAP       I95
  D14      A      A  Q_LED       I142
  R568     2      B  Q_RES       I93

Q7_D            @SCM_LIB.SCM(SCH_1):Q7_D
  Q7       3      D  MOSFET_N_123  I157
  R42      2      B  Q_RES       I159

QSPI_2_PLD_CLK   @SCM_LIB.SCM(SCH_1):QSPI_2_PLD_CLK
  GF1    B44    B44  FCONN168_ME1016810106011  I171
  R678     2      B  Q_RES       I239

QSPI_2_PLD_CS0_N   @SCM_LIB.SCM(SCH_1):QSPI_2_PLD_CS0_N
  GF1    B45    B45  FCONN168_ME1016810106011  I171
  R677     1      A  Q_RES       I250

QSPI_2_PLD_CS1_N   @SCM_LIB.SCM(SCH_1):QSPI_2_PLD_CS1_N
  GF1    B42    B42  FCONN168_ME1016810106011  I171
  R107     1      A  Q_RES       I251

QSPI_2_PLD_IO0   @SCM_LIB.SCM(SCH_1):QSPI_2_PLD_IO0
  GF1    B46    B46  FCONN168_ME1016810106011  I171
  R679     2      B  Q_RES       I247

QSPI_2_PLD_IO1   @SCM_LIB.SCM(SCH_1):QSPI_2_PLD_IO1
  GF1    B47    B47  FCONN168_ME1016810106011  I171
  R680     2      B  Q_RES       I248

QSPI_2_PLD_IO2   @SCM_LIB.SCM(SCH_1):QSPI_2_PLD_IO2
  GF1    B48    B48  FCONN168_ME1016810106011  I171
  R681     2      B  Q_RES       I245

QSPI_2_PLD_IO3   @SCM_LIB.SCM(SCH_1):QSPI_2_PLD_IO3
  GF1    B49    B49  FCONN168_ME1016810106011  I171
  R682     2      B  Q_RES       I246

REAR_ID_RST_BTN_N   @SCM_LIB.SCM(SCH_1):REAR_ID_RST_BTN_N
  C199     1      A  Q_CAP       I55
  R504     2      B  Q_RES       I82
  SW7      2      2  SW2S_TA31E2KQTR  I137
  U32      2      A  74LVC1G17GW  I49

REAR_PWR_BTN_N   @SCM_LIB.SCM(SCH_1):REAR_PWR_BTN_N
  C198     1      A  Q_CAP       I44
  R768     2      B  Q_RES       I89
  SW6      2      2  SW2S_TA31E2KQTR  I136
  U31      2      A  74LVC1G07GW  I151

RGMII_BMC_MDC   @SCM_LIB.SCM(SCH_1):RGMII_BMC_MDC
  R803     1      A  Q_RES       I308
  U5     M24  GPIOA0||MDC3||SCL11  AST2600A1GP  I45

RGMII_BMC_MDC_R   @SCM_LIB.SCM(SCH_1):RGMII_BMC_MDC_R
  R283     2      B  Q_RES       I31
  R803     2      B  Q_RES       I308
  U7      48    MDC  BCM54612EB1KMLG  I126

RGMII_BMC_MDIO   @SCM_LIB.SCM(SCH_1):RGMII_BMC_MDIO
  R804     1      A  Q_RES       I309
  U5     M25  GPIOA1||MDIO3||SDA11  AST2600A1GP  I45

RGMII_BMC_MDIO_R   @SCM_LIB.SCM(SCH_1):RGMII_BMC_MDIO_R
  R285     2      B  Q_RES       I29
  R804     2      B  Q_RES       I309
  U7      47   MDIO  BCM54612EB1KMLG  I126

RGMII_BMC_RXD_<0>   @SCM_LIB.SCM(SCH_1):RGMII_BMC_RXD_<0>
  R53      1      A  Q_RES       I138
  U5     F23  RGMII3RXD0||RMII3RXD0||GPIOD0  AST2600A1GP  I45

RGMII_BMC_RXD_<1>   @SCM_LIB.SCM(SCH_1):RGMII_BMC_RXD_<1>
  R54      1      A  Q_RES       I137
  U5     F26  RGMII3RXD1||RMII3RXD1||GPIOD1  AST2600A1GP  I45

RGMII_BMC_RXD_<2>   @SCM_LIB.SCM(SCH_1):RGMII_BMC_RXD_<2>
  R470     1      A  Q_RES       I136
  U5     F25  RGMII3RXD2||RMII3CRSDV||GPIOD2  AST2600A1GP  I45

RGMII_BMC_RXD_<3>   @SCM_LIB.SCM(SCH_1):RGMII_BMC_RXD_<3>
  R471     1      A  Q_RES       I135
  U5     E26  RGMII3RXD3||RMII3RXER||GPIOD3  AST2600A1GP  I45

RGMII_BMC_RX_CLK   @SCM_LIB.SCM(SCH_1):RGMII_BMC_RX_CLK
  C152     1      A  Q_CAP       I87
  R297     1      A  Q_RES       I90
  U7      33    RXC  BCM54612EB1KMLG  I126

RGMII_BMC_RX_CLK_R   @SCM_LIB.SCM(SCH_1):RGMII_BMC_RX_CLK_R
  R297     2      B  Q_RES       I90
  U5     G23  RGMII3RXCK||RMII3RCLKI||GPIOC6  AST2600A1GP  I45

RGMII_BMC_RX_CTRL   @SCM_LIB.SCM(SCH_1):RGMII_BMC_RX_CTRL
  R52      1      A  Q_RES       I139
  U5     G24  RGMII3RXCTL||GPIOC7  AST2600A1GP  I45

RGMII_BMC_RX_R_CTRL   @SCM_LIB.SCM(SCH_1):RGMII_BMC_RX_R_CTRL
  R52      2      B  Q_RES       I139
  U7      26  RX_DV  BCM54612EB1KMLG  I126

RGMII_BMC_R_RXD_<0>   @SCM_LIB.SCM(SCH_1):RGMII_BMC_R_RXD_<0>
  R53      2      B  Q_RES       I138
  U7      32   RXD0  BCM54612EB1KMLG  I126

RGMII_BMC_R_RXD_<1>   @SCM_LIB.SCM(SCH_1):RGMII_BMC_R_RXD_<1>
  R54      2      B  Q_RES       I137
  U7      31   RXD1  BCM54612EB1KMLG  I126

RGMII_BMC_R_RXD_<2>   @SCM_LIB.SCM(SCH_1):RGMII_BMC_R_RXD_<2>
  R470     2      B  Q_RES       I136
  U7      28   RXD2  BCM54612EB1KMLG  I126

RGMII_BMC_R_RXD_<3>   @SCM_LIB.SCM(SCH_1):RGMII_BMC_R_RXD_<3>
  R471     2      B  Q_RES       I135
  U7      27   RXD3  BCM54612EB1KMLG  I126

RGMII_BMC_TXD_<0>   @SCM_LIB.SCM(SCH_1):RGMII_BMC_TXD_<0>
  R628     2      B  Q_RES       I139
  U7      39   TXD0  BCM54612EB1KMLG  I126

RGMII_BMC_TXD_<1>   @SCM_LIB.SCM(SCH_1):RGMII_BMC_TXD_<1>
  R629     2      B  Q_RES       I140
  U7      38   TXD1  BCM54612EB1KMLG  I126

RGMII_BMC_TXD_<2>   @SCM_LIB.SCM(SCH_1):RGMII_BMC_TXD_<2>
  R630     2      B  Q_RES       I141
  U7      37   TXD2  BCM54612EB1KMLG  I126

RGMII_BMC_TXD_<3>   @SCM_LIB.SCM(SCH_1):RGMII_BMC_TXD_<3>
  R631     2      B  Q_RES       I142
  U7      36   TXD3  BCM54612EB1KMLG  I126

RGMII_BMC_TXD_R_<0>   @SCM_LIB.SCM(SCH_1):RGMII_BMC_TXD_R_<0>
  R628     1      A  Q_RES       I139
  U5     H22  RGMII3TXD0||RMII3TXD0||GPIOC2  AST2600A1GP  I45

RGMII_BMC_TXD_R_<1>   @SCM_LIB.SCM(SCH_1):RGMII_BMC_TXD_R_<1>
  R629     1      A  Q_RES       I140
  U5     H23  RGMII3TXD1||RMII3TXD1||GPIOC3  AST2600A1GP  I45

RGMII_BMC_TXD_R_<2>   @SCM_LIB.SCM(SCH_1):RGMII_BMC_TXD_R_<2>
  R630     1      A  Q_RES       I141
  U5     G22  RGMII3TXD2||GPIOC4  AST2600A1GP  I45

RGMII_BMC_TXD_R_<3>   @SCM_LIB.SCM(SCH_1):RGMII_BMC_TXD_R_<3>
  R631     1      A  Q_RES       I142
  U5     F22  RGMII3TXD3||GPIOC5  AST2600A1GP  I45

RGMII_BMC_TX_CLK   @SCM_LIB.SCM(SCH_1):RGMII_BMC_TX_CLK
  R538     2      B  Q_RES       I137
  U7      40  GTXCLK  BCM54612EB1KMLG  I126

RGMII_BMC_TX_CTRL   @SCM_LIB.SCM(SCH_1):RGMII_BMC_TX_CTRL
  R539     2      B  Q_RES       I138
  U7      35  TX_EN  BCM54612EB1KMLG  I126

RGMII_BMC_TX_R_CLK   @SCM_LIB.SCM(SCH_1):RGMII_BMC_TX_R_CLK
  R538     1      A  Q_RES       I137
  U5     H24  RGMII3TXCK||RMII3RCLKO||GPIOC0  AST2600A1GP  I45

RGMII_BMC_TX_R_CTRL   @SCM_LIB.SCM(SCH_1):RGMII_BMC_TX_R_CTRL
  R539     1      A  Q_RES       I138
  U5     J22  RGMII3TXCTL||RMII3TXEN||GPIOC1  AST2600A1GP  I45

RMII_CSRDV      @SCM_LIB.SCM(SCH_1):RMII_CSRDV
  GF1    B19    B19  FCONN168_ME1016810106011  I171
  R161     2      B  Q_RES       I218
  U5     B25  RGMII4RXD2||RMII4CRSDV||NDTR4||GPIOE6  AST2600A1GP  I45

RMII_OCP_RCLKI   @SCM_LIB.SCM(SCH_1):RMII_OCP_RCLKI
  GF1    B18    B18  FCONN168_ME1016810106011  I171
  U5     C25  RGMII4RXCK||RMII4RCLKI||NCTS4||GPIOE2  AST2600A1GP  I45

RMII_RXD0       @SCM_LIB.SCM(SCH_1):RMII_RXD0
  GF1    B24    B24  FCONN168_ME1016810106011  I171
  U5     C24  RGMII4RXD0||RMII4RXD0||NDSR4||GPIOE4  AST2600A1GP  I45

RMII_RXD1       @SCM_LIB.SCM(SCH_1):RMII_RXD1
  GF1    B25    B25  FCONN168_ME1016810106011  I171
  U5     B26  RGMII4RXD1||RMII4RXD1||NRI4||GPIOE5  AST2600A1GP  I45

RMII_RXER       @SCM_LIB.SCM(SCH_1):RMII_RXER
  GF1    B23    B23  FCONN168_ME1016810106011  I171
  R101     2      B  Q_RES       I214
  U5     B24  RGMII4RXD3||RMII4RXER||NRTS4||GPIOE7  AST2600A1GP  I45

RMII_TXD0       @SCM_LIB.SCM(SCH_1):RMII_TXD0
  GF1    B21    B21  FCONN168_ME1016810106011  I171
  R172     2      B  Q_RES       I66

RMII_TXD0_R     @SCM_LIB.SCM(SCH_1):RMII_TXD0_R
  R172     1      A  Q_RES       I66
  U5     E24  RGMII4TXD0||RMII4TXD0||NDSR3||GPIOD6  AST2600A1GP  I45

RMII_TXD1       @SCM_LIB.SCM(SCH_1):RMII_TXD1
  GF1    B22    B22  FCONN168_ME1016810106011  I171
  R173     2      B  Q_RES       I65

RMII_TXD1_R     @SCM_LIB.SCM(SCH_1):RMII_TXD1_R
  R173     1      A  Q_RES       I65
  U5     E25  RGMII4TXD1||RMII4TXD1||NRI3||GPIOD7  AST2600A1GP  I45

RMII_TXEN       @SCM_LIB.SCM(SCH_1):RMII_TXEN
  GF1    B20    B20  FCONN168_ME1016810106011  I171
  R103     2      B  Q_RES       I219
  R171     2      B  Q_RES       I68

RMII_TXEN_R     @SCM_LIB.SCM(SCH_1):RMII_TXEN_R
  R171     1      A  Q_RES       I68
  U5     E23  RGMII4TXCTL||RMII4TXEN||NDCD3||GPIOD5  AST2600A1GP  I45

RST_BMC_EXTRST_R1_N   @SCM_LIB.SCM(SCH_1):RST_BMC_EXTRST_R1_N
  R290     2      B  Q_RES        I8
  R291     2      B  Q_RES        I9
  U12      D  DRAIN  MOSFET_N    I14
  U13      4      Y  SN74LVC1G07DCKR  I15

RST_BMC_EXTRST_R2_N   @SCM_LIB.SCM(SCH_1):RST_BMC_EXTRST_R2_N
  Q1       C      3  MMBT39047F   I2
  R106     2      B  Q_RES       I12
  R110     2      B  Q_RES       I116
  R287     2      B  Q_RES        I5
  R636     2      B  Q_RES       I10

RST_BMC_EXTRST_R3_N   @SCM_LIB.SCM(SCH_1):RST_BMC_EXTRST_R3_N
  J10      2      2  SCONN11_9192031111LF  I113
  R110     1      A  Q_RES       I116

RST_BMC_HW      @SCM_LIB.SCM(SCH_1):RST_BMC_HW
  R282     1      A  Q_RES       I78
  R638     2      B  Q_RES       I359

RST_BMC_HW_R    @SCM_LIB.SCM(SCH_1):RST_BMC_HW_R
  R638     1      A  Q_RES       I359
  U25    D12  IO_100_6  10M02SCU169C8G  I330

RST_BMC_LPC_ESPI_N   @SCM_LIB.SCM(SCH_1):RST_BMC_LPC_ESPI_N
  GF1     B4     B4  FCONN168_ME1016810106011  I171
  R117     2      B  Q_RES        I2
  R120     1      A  Q_RES       I33

RST_BMC_RSTBTN_OUT_N   @SCM_LIB.SCM(SCH_1):RST_BMC_RSTBTN_OUT_N
  R566     2      B  Q_RES       I128
  R717     2      B  Q_RES       I174
  U25     H3  IO_17_1B  10M02SCU169C8G  I394

RST_BMC_RSTBTN_OUT_R_N   @SCM_LIB.SCM(SCH_1):RST_BMC_RSTBTN_OUT_R_N
  R566     1      A  Q_RES       I128
  U5     AA24  GPIOP3||PWM11||THRUOUT1  AST2600A1GP  I41

RST_BMC_SELF_HW   @SCM_LIB.SCM(SCH_1):RST_BMC_SELF_HW
  R271     1      A  Q_RES       I365
  R450     1      A  Q_RES       I77
  R494     2      B  Q_RES       I335

RST_BMC_SELF_HW_D   @SCM_LIB.SCM(SCH_1):RST_BMC_SELF_HW_D
  C161     1      A  Q_CAP       I23
  D17      2      2  Q_DIODE     I28
  R313     1      A  Q_RES       I30

RST_BMC_SELF_HW_D_C   @SCM_LIB.SCM(SCH_1):RST_BMC_SELF_HW_D_C
  C161     2      B  Q_CAP       I23
  C173     1      A  Q_CAP       I24
  R314     1      A  Q_RES       I26
  U12      G   GATE  MOSFET_N    I14

RST_BMC_SELF_HW_R1   @SCM_LIB.SCM(SCH_1):RST_BMC_SELF_HW_R1
  R494     1      A  Q_RES       I335
  U5     AF11  GPIOY0||SALT5||WDTRST1#  AST2600A1GP  I45

RST_BMC_SELF_HW_R2   @SCM_LIB.SCM(SCH_1):RST_BMC_SELF_HW_R2
  R271     2      B  Q_RES       I365
  R641     2      B  Q_RES       I53
  U25    L12  IO_67_5  10M02SCU169C8G  I330

RST_BMC_SELF_HW_R3   @SCM_LIB.SCM(SCH_1):RST_BMC_SELF_HW_R3
  D17      1      1  Q_DIODE     I28
  R282     2      B  Q_RES       I78
  R450     2      B  Q_RES       I77
  R633     2      B  Q_RES       I81

RST_BMC_SRST_BUF_R1_N   @SCM_LIB.SCM(SCH_1):RST_BMC_SRST_BUF_R1_N
  R315     2      B  Q_RES       I71
  U13      2      A  SN74LVC1G07DCKR  I15

RST_BMC_SRST_BUF_R_N   @SCM_LIB.SCM(SCH_1):RST_BMC_SRST_BUF_R_N
  C223     1      A  Q_CAP       I46
  R108     2      B  Q_RES       I65
  R124     2      B  Q_RES       I67
  R125     1      A  Q_RES       I69
  R134     1      A  Q_RES       I70
  R192     2      B  Q_RES       I41
  R315     1      A  Q_RES       I71

RST_BMC_SRST_N   @SCM_LIB.SCM(SCH_1):RST_BMC_SRST_N
  R106     1      A  Q_RES       I12
  R125     2      B  Q_RES       I69
  U5     E10  SRST#  AST2600A1GP  I41

RST_ESPI_LPC_BMC_N   @SCM_LIB.SCM(SCH_1):RST_ESPI_LPC_BMC_N
  R120     2      B  Q_RES       I33
  U5     AD8  GPIOW7||LPCRST#||ESPIRST#  AST2600A1GP  I45

RST_EXTRST_N    @SCM_LIB.SCM(SCH_1):RST_EXTRST_N
  R447     1      A  Q_RES       I386
  R623     2      B  Q_RES       I152
  R636     1      A  Q_RES       I10
  U5     B10  EXTRST#  AST2600A1GP  I41

RST_EXTRST_R_N   @SCM_LIB.SCM(SCH_1):RST_EXTRST_R_N
  R447     2      B  Q_RES       I386
  U25     N5  IO_41_3  10M02SCU169C8G  I394

RST_MB_STBY_N   @SCM_LIB.SCM(SCH_1):RST_MB_STBY_N
  GF1    A46    A46  FCONN168_ME1016810106011  I171
  R263     1      A  Q_RES       I316

RST_MB_STBY_R_N   @SCM_LIB.SCM(SCH_1):RST_MB_STBY_R_N
  R263     2      B  Q_RES       I316
  U25    H10  IO_74_5  10M02SCU169C8G  I330

RST_PCA9548_SENSOR_N   @SCM_LIB.SCM(SCH_1):RST_PCA9548_SENSOR_N
  R169     2      B  Q_RES       I253
  R704     1      A  Q_RES       I352
  U25     H1  IO_10_VREFB1N0_1B  10M02SCU169C8G  I394

RST_PCA9548_SENSOR_R_N   @SCM_LIB.SCM(SCH_1):RST_PCA9548_SENSOR_R_N
  R704     2      B  Q_RES       I352
  U5     A25  GPIOF5||SD1DAT3||PWM13  AST2600A1GP  I45

RST_PLTRST_N    @SCM_LIB.SCM(SCH_1):RST_PLTRST_N
  GF1    A51    A51  FCONN168_ME1016810106011  I171
  R34      2      B  Q_RES       I194
  R118     2      B  Q_RES       I53
  R168     1      A  Q_RES       I268
  R503     2      B  Q_RES       I60
  R718     1      A  Q_RES       I405
  U5      A7  PERST#  AST2600A1GP  I45

RST_PLTRST_R1_N   @SCM_LIB.SCM(SCH_1):RST_PLTRST_R1_N
  R718     2      B  Q_RES       I405
  U25     B1  IO_3_1A  10M02SCU169C8G  I394

RST_PLTRST_R_N   @SCM_LIB.SCM(SCH_1):RST_PLTRST_R_N
  R168     2      B  Q_RES       I268
  U5     D22  GPIOF0||SD1CLK||PWM8  AST2600A1GP  I45

RST_PLTRST_TPM_N   @SCM_LIB.SCM(SCH_1):RST_PLTRST_TPM_N
  J5       2      2  SCONN11_9192031111LF  I56
  R503     1      A  Q_RES       I60

RST_ROT_CPU_N   @SCM_LIB.SCM(SCH_1):RST_ROT_CPU_N
  GF1    A53    A53  FCONN168_ME1016810106011  I171
  R825     1      A  Q_RES       I313
  R828     2      B  Q_RES       I241

RST_ROT_CPU_R_N   @SCM_LIB.SCM(SCH_1):RST_ROT_CPU_R_N
  R825     2      B  Q_RES       I313
  U25    L13  IO_69_5  10M02SCU169C8G  I330

RST_RSMRST_N    @SCM_LIB.SCM(SCH_1):RST_RSMRST_N
  R160     1      A  Q_RES       I159
  R625     2      B  Q_RES       I401
  U25     F1  IO_5_1A  10M02SCU169C8G  I394

RST_RSMRST_R_N   @SCM_LIB.SCM(SCH_1):RST_RSMRST_R_N
  R160     2      B  Q_RES       I159
  U5     AF14  GPIOV1||SIOS5#  AST2600A1GP  I45

RST_RSTB_N      @SCM_LIB.SCM(SCH_1):RST_RSTB_N
  C142     2      B  Q_CAP       I28
  R134     2      B  Q_RES       I70
  R284     2      B  Q_RES       I27
  U7      46  RESET#  BCM54612EB1KMLG  I126

RST_SGPIO_RESET_BMC_N   @SCM_LIB.SCM(SCH_1):RST_SGPIO_RESET_BMC_N
  R688     2      B  Q_RES       I304
  U5     C23  GPIOF3||SD1DAT1||PWM11  AST2600A1GP  I45

RST_SGPIO_RESET_N   @SCM_LIB.SCM(SCH_1):RST_SGPIO_RESET_N
  GF1    B39    B39  FCONN168_ME1016810106011  I171
  R69      2      B  Q_RES       I227
  R688     1      A  Q_RES       I304
  R691     2      B  Q_RES       I393

RST_SGPIO_RESET_R_N   @SCM_LIB.SCM(SCH_1):RST_SGPIO_RESET_R_N
  R691     1      A  Q_RES       I393
  U25     N9  IO_57_3  10M02SCU169C8G  I394

RST_SPI_BMC_FLASH_R1_N   @SCM_LIB.SCM(SCH_1):RST_SPI_BMC_FLASH_R1_N
  J121     3    NC0  SCONN16_ACASPI006P06  I97
  R562     1      A  Q_RES       I46

RST_SPI_BMC_FLASH_R2_N   @SCM_LIB.SCM(SCH_1):RST_SPI_BMC_FLASH_R2_N
  R561     1      A  Q_RES       I44
  U28      3  RESET#  MX66L1G45GMI08G  I64

RST_SPI_FLASH_N   @SCM_LIB.SCM(SCH_1):RST_SPI_FLASH_N
  R561     2      B  Q_RES       I44
  R562     2      B  Q_RES       I46
  R563     2      B  Q_RES       I48
  U5      B7  RSTIND#  AST2600A1GP  I41

RST_SPI_PCH_FLASH_R1_N   @SCM_LIB.SCM(SCH_1):RST_SPI_PCH_FLASH_R1_N
  J40      3    NC0  SCONN16_ACASPI006P06  I53
  R496     2      B  Q_RES       I48

RST_SRST_PLD_BMC_BUF_N   @SCM_LIB.SCM(SCH_1):RST_SRST_PLD_BMC_BUF_N
  R108     1      A  Q_RES       I65
  U6       4     2Y  SN74LVC2G07DCKR  I64

RST_SRST_PLD_BMC_R_N   @SCM_LIB.SCM(SCH_1):RST_SRST_PLD_BMC_R_N
  R614     1      A  Q_RES       I35
  U6       3     2A  SN74LVC2G07DCKR  I64
  U25     K2  IO_33_2  10M02SCU169C8G  I394

RST_WDTRST_PLD_N   @SCM_LIB.SCM(SCH_1):RST_WDTRST_PLD_N
  R452     2      B  Q_RES       I339
  R635     1      A  Q_RES       I361
  R637     2      B  Q_RES       I337

RST_WDTRST_PLD_R1_N   @SCM_LIB.SCM(SCH_1):RST_WDTRST_PLD_R1_N
  R637     1      A  Q_RES       I337
  U5     AD12  GPIOY1||SALT6||WDTRST2#  AST2600A1GP  I45

RST_WDTRST_PLD_R2_N   @SCM_LIB.SCM(SCH_1):RST_WDTRST_PLD_R2_N
  R635     2      B  Q_RES       I361
  U25     F8  IO_90_6  10M02SCU169C8G  I330

SGPIO_BMC_M1_CLK   @SCM_LIB.SCM(SCH_1):SGPIO_BMC_M1_CLK
  R148     2      B  Q_RES       I379
  U5     A18  GPIOH0||SGPM1CK  AST2600A1GP  I45

SGPIO_BMC_M1_DI   @SCM_LIB.SCM(SCH_1):SGPIO_BMC_M1_DI
  R433     2      B  Q_RES       I382
  U5     A17  GPIOH3||SGPM1I  AST2600A1GP  I45

SGPIO_BMC_M1_DO   @SCM_LIB.SCM(SCH_1):SGPIO_BMC_M1_DO
  R151     2      B  Q_RES       I381
  U5     C18  GPIOH2||SGPM1O  AST2600A1GP  I45

SGPIO_BMC_M1_LD   @SCM_LIB.SCM(SCH_1):SGPIO_BMC_M1_LD
  R150     2      B  Q_RES       I380
  U5     B18  GPIOH1||SGPM1LD  AST2600A1GP  I45

SGPIO_CLK_0     @SCM_LIB.SCM(SCH_1):SGPIO_CLK_0
  GF1    B30    B30  FCONN168_ME1016810106011  I171
  R64      1      A  Q_RES       I233
  R82      2      B  Q_RES       I232
  R434     2      B  Q_RES       I389

SGPIO_CLK_1     @SCM_LIB.SCM(SCH_1):SGPIO_CLK_1
  GF1    B35    B35  FCONN168_ME1016810106011  I171
  R63      1      A  Q_RES       I231
  R76      2      B  Q_RES       I230
  R148     1      A  Q_RES       I379

SGPIO_CLK_PLD_0   @SCM_LIB.SCM(SCH_1):SGPIO_CLK_PLD_0
  R434     1      A  Q_RES       I389
  U25     K6  IO_48_3  10M02SCU169C8G  I394

SGPIO_DI_0      @SCM_LIB.SCM(SCH_1):SGPIO_DI_0
  GF1    B31    B31  FCONN168_ME1016810106011  I171
  R78      2      B  Q_RES       I129
  R437     2      B  Q_RES       I391

SGPIO_DI_1      @SCM_LIB.SCM(SCH_1):SGPIO_DI_1
  GF1    B36    B36  FCONN168_ME1016810106011  I171
  R74      2      B  Q_RES       I117
  R433     1      A  Q_RES       I382

SGPIO_DO_0      @SCM_LIB.SCM(SCH_1):SGPIO_DO_0
  GF1    B29    B29  FCONN168_ME1016810106011  I171
  R79      2      B  Q_RES       I130
  R435     2      B  Q_RES       I388

SGPIO_DO_1      @SCM_LIB.SCM(SCH_1):SGPIO_DO_1
  GF1    B34    B34  FCONN168_ME1016810106011  I171
  R75      2      B  Q_RES       I110
  R151     1      A  Q_RES       I381

SGPIO_LD_0      @SCM_LIB.SCM(SCH_1):SGPIO_LD_0
  GF1    B32    B32  FCONN168_ME1016810106011  I171
  R77      2      B  Q_RES       I128
  R436     2      B  Q_RES       I390

SGPIO_LD_1      @SCM_LIB.SCM(SCH_1):SGPIO_LD_1
  GF1    B37    B37  FCONN168_ME1016810106011  I171
  R73      2      B  Q_RES       I118
  R150     1      A  Q_RES       I380

SGPIO_PLD_DI_0   @SCM_LIB.SCM(SCH_1):SGPIO_PLD_DI_0
  R437     1      A  Q_RES       I391
  U25    N11  IO_51_VREFB3N0_3  10M02SCU169C8G  I394

SGPIO_PLD_DO_0   @SCM_LIB.SCM(SCH_1):SGPIO_PLD_DO_0
  R435     1      A  Q_RES       I388
  U25     M9  IO_49_3  10M02SCU169C8G  I394

SGPIO_PLD_LD_0   @SCM_LIB.SCM(SCH_1):SGPIO_PLD_LD_0
  R436     1      A  Q_RES       I390
  U25     J7  IO_50_3  10M02SCU169C8G  I394

SMB_BMC_ALERT10_N   @SCM_LIB.SCM(SCH_1):SMB_BMC_ALERT10_N
  R449     1      A  Q_RES       I321
  R457     1      A  Q_RES       I444
  R843     2      B  Q_RES       I177

SMB_BMC_ALERT10_R1_N   @SCM_LIB.SCM(SCH_1):SMB_BMC_ALERT10_R1_N
  R457     2      B  Q_RES       I444
  U25     K1  IO_31_2  10M02SCU169C8G  I394

SMB_BMC_ALERT10_R_N   @SCM_LIB.SCM(SCH_1):SMB_BMC_ALERT10_R_N
  R449     2      B  Q_RES       I321
  U5     AA17  ADC9||GPIU1||SALT10  AST2600A1GP  I41

SMB_BMC_ALERT12_N   @SCM_LIB.SCM(SCH_1):SMB_BMC_ALERT12_N
  R844     2      B  Q_RES       I179
  U5     AE16  ADC11||GPIU3||SALT12  AST2600A1GP  I41
  U25     B7  IO_112_VREFB8N0_8  10M02SCU169C8G  I330

SMB_BMC_ALERT15_N   @SCM_LIB.SCM(SCH_1):SMB_BMC_ALERT15_N
  R408     1      A  Q_RES       I19
  R851     2      B  Q_RES       I184
  U5     D21  GPIOG6||TXD9||SD2CD#||SALT15  AST2600A1GP  I45

SMB_BMC_ALERT15_R_N   @SCM_LIB.SCM(SCH_1):SMB_BMC_ALERT15_R_N
  R407     2      B  Q_RES       I42
  R408     2      B  Q_RES       I19
  U4       3  ALERT  TMP75AIDGKR  I23

SMB_BMC_ALERT16_N   @SCM_LIB.SCM(SCH_1):SMB_BMC_ALERT16_N
  R848     2      B  Q_RES       I182
  U5     AC17  ADC15||GPIU7||SALT16  AST2600A1GP  I41

SMB_BMC_ALERT3_N   @SCM_LIB.SCM(SCH_1):SMB_BMC_ALERT3_N
  R268     2      B  Q_RES       I86
  R442     1      A  Q_RES       I301
  R453     1      A  Q_RES       I438

SMB_BMC_ALERT3_R1_N   @SCM_LIB.SCM(SCH_1):SMB_BMC_ALERT3_R1_N
  R453     2      B  Q_RES       I438
  U25     N3  IO_28_DPCLK1_2  10M02SCU169C8G  I394

SMB_BMC_ALERT3_R_N   @SCM_LIB.SCM(SCH_1):SMB_BMC_ALERT3_R_N
  R442     2      B  Q_RES       I301
  U5     H26  GPIOB2||SALT3||LHAD2  AST2600A1GP  I45

SMB_BMC_ALERT4_N   @SCM_LIB.SCM(SCH_1):SMB_BMC_ALERT4_N
  R269     2      B  Q_RES       I84
  R443     1      A  Q_RES       I300
  R454     1      A  Q_RES       I440

SMB_BMC_ALERT4_R1_N   @SCM_LIB.SCM(SCH_1):SMB_BMC_ALERT4_R1_N
  R454     2      B  Q_RES       I440
  U25     L2  IO_29_2  10M02SCU169C8G  I394

SMB_BMC_ALERT4_R_N   @SCM_LIB.SCM(SCH_1):SMB_BMC_ALERT4_R_N
  R443     2      B  Q_RES       I300
  U5     J25  GPIOB3||SALT4||LHAD3  AST2600A1GP  I45

SMB_BMC_ALERT9_N   @SCM_LIB.SCM(SCH_1):SMB_BMC_ALERT9_N
  R448     1      A  Q_RES       I320
  R456     1      A  Q_RES       I442
  R842     2      B  Q_RES       I168

SMB_BMC_ALERT9_R1_N   @SCM_LIB.SCM(SCH_1):SMB_BMC_ALERT9_R1_N
  R456     2      B  Q_RES       I442
  U25     M3  IO_30_PLL_L_CLKOUTN_2  10M02SCU169C8G  I394

SMB_BMC_ALERT9_R_N   @SCM_LIB.SCM(SCH_1):SMB_BMC_ALERT9_R_N
  R448     2      B  Q_RES       I320
  U5     AB16  ADC8||GPIU0||SALT9  AST2600A1GP  I41

SMB_BMC_MM10_R_SCL   @SCM_LIB.SCM(SCH_1):SMB_BMC_MM10_R_SCL
  R583     1      A  Q_RES       I319
  U5     E15  GPIOL2||SCL10  AST2600A1GP  I45

SMB_BMC_MM10_R_SDA   @SCM_LIB.SCM(SCH_1):SMB_BMC_MM10_R_SDA
  R584     1      A  Q_RES       I320
  U5     A13  GPIOL3||SDA10  AST2600A1GP  I45

SMB_BMC_MM10_SCL   @SCM_LIB.SCM(SCH_1):SMB_BMC_MM10_SCL
  GF1    A31    A31  FCONN168_ME1016810106011  I171
  R262     2      B  Q_RES       I93
  R583     2      B  Q_RES       I319

SMB_BMC_MM10_SDA   @SCM_LIB.SCM(SCH_1):SMB_BMC_MM10_SDA
  GF1    A32    A32  FCONN168_ME1016810106011  I171
  R521     2      B  Q_RES       I91
  R584     2      B  Q_RES       I320

SMB_BMC_MM12_R_SCL   @SCM_LIB.SCM(SCH_1):SMB_BMC_MM12_R_SCL
  R137     1      A  Q_RES       I385
  U5     L26  GPIOA2||MDC4||SCL12  AST2600A1GP  I45

SMB_BMC_MM12_R_SDA   @SCM_LIB.SCM(SCH_1):SMB_BMC_MM12_R_SDA
  R144     1      A  Q_RES       I386
  U5     K24  GPIOA3||MDIO4||SDA12  AST2600A1GP  I45

SMB_BMC_MM12_SCL   @SCM_LIB.SCM(SCH_1):SMB_BMC_MM12_SCL
  GF1    A38    A38  FCONN168_ME1016810106011  I171
  R137     2      B  Q_RES       I385
  R145     2      B  Q_RES       I154

SMB_BMC_MM12_SDA   @SCM_LIB.SCM(SCH_1):SMB_BMC_MM12_SDA
  GF1    A39    A39  FCONN168_ME1016810106011  I171
  R144     2      B  Q_RES       I386
  R149     2      B  Q_RES       I153

SMB_BMC_MM13_R_SCL   @SCM_LIB.SCM(SCH_1):SMB_BMC_MM13_R_SCL
  R423     1      A  Q_RES       I252
  R817     1      A  Q_RES       I393
  U5     K26  GPIOA4||MAC1LINK||SCL13||SGPS2CK||SGPM2CK  AST2600A1GP  I45

SMB_BMC_MM13_R_SDA   @SCM_LIB.SCM(SCH_1):SMB_BMC_MM13_R_SDA
  R424     1      A  Q_RES       I253
  R818     1      A  Q_RES       I392
  U5     L24  GPIOA5||MAC2LINK||SDA13||SGPS2LD||SPGM2LD  AST2600A1GP  I45

SMB_BMC_MM13_SCL   @SCM_LIB.SCM(SCH_1):SMB_BMC_MM13_SCL
  GF1    A40    A40  FCONN168_ME1016810106011  I171
  R422     2      B  Q_RES       I203
  R423     2      B  Q_RES       I252

SMB_BMC_MM13_SDA   @SCM_LIB.SCM(SCH_1):SMB_BMC_MM13_SDA
  GF1    A41    A41  FCONN168_ME1016810106011  I171
  R424     2      B  Q_RES       I253
  R428     2      B  Q_RES       I210

SMB_BMC_MM14_R1_SCL   @SCM_LIB.SCM(SCH_1):SMB_BMC_MM14_R1_SCL
  GF1     A1     A1  FCONN168_ME1016810106011  I171
  R36      2      B  Q_RES       I458

SMB_BMC_MM14_R1_SDA   @SCM_LIB.SCM(SCH_1):SMB_BMC_MM14_R1_SDA
  GF1     A2     A2  FCONN168_ME1016810106011  I171
  R46      2      B  Q_RES       I459

SMB_BMC_MM14_R_SCL   @SCM_LIB.SCM(SCH_1):SMB_BMC_MM14_R_SCL
  R425     1      A  Q_RES       I254
  R819     1      A  Q_RES       I391
  U5     L23  GPIOA6||MAC3LINK||SCL14||SGPS2I0||SGPM2O  AST2600A1GP  I45

SMB_BMC_MM14_R_SDA   @SCM_LIB.SCM(SCH_1):SMB_BMC_MM14_R_SDA
  R426     1      A  Q_RES       I255
  R820     1      A  Q_RES       I390
  U5     K25  GPIOA7||MAC4LINK||SDA14||SGPS2I1||SGPM2I  AST2600A1GP  I45

SMB_BMC_MM14_SCL   @SCM_LIB.SCM(SCH_1):SMB_BMC_MM14_SCL
  R36      1      A  Q_RES       I458
  R425     2      B  Q_RES       I254
  R429     2      B  Q_RES       I209

SMB_BMC_MM14_SDA   @SCM_LIB.SCM(SCH_1):SMB_BMC_MM14_SDA
  R46      1      A  Q_RES       I459
  R426     2      B  Q_RES       I255
  R438     2      B  Q_RES       I208

SMB_BMC_MM15_R1_SCL   @SCM_LIB.SCM(SCH_1):SMB_BMC_MM15_R1_SCL
  R410     2      B  Q_RES       I21
  U4       2    SCL  TMP75AIDGKR  I23

SMB_BMC_MM15_R1_SDA   @SCM_LIB.SCM(SCH_1):SMB_BMC_MM15_R1_SDA
  R409     2      B  Q_RES       I20
  U4       1    SDA  TMP75AIDGKR  I23

SMB_BMC_MM15_R2_SCL   @SCM_LIB.SCM(SCH_1):SMB_BMC_MM15_R2_SCL
  R420     1      A  Q_RES       I34
  U19      6    SCL  M24128BWDW6TP  I15

SMB_BMC_MM15_R2_SDA   @SCM_LIB.SCM(SCH_1):SMB_BMC_MM15_R2_SDA
  R421     1      A  Q_RES       I33
  U19      5    SDA  M24128BWDW6TP  I15

SMB_BMC_MM15_R3_SCL   @SCM_LIB.SCM(SCH_1):SMB_BMC_MM15_R3_SCL
  R272     2      B  Q_RES       I331
  U25    E10  IO_98_6  10M02SCU169C8G  I330

SMB_BMC_MM15_R3_SDA   @SCM_LIB.SCM(SCH_1):SMB_BMC_MM15_R3_SDA
  R303     2      B  Q_RES       I335
  U25     D9  IO_99_6  10M02SCU169C8G  I330

SMB_BMC_MM15_R_SCL   @SCM_LIB.SCM(SCH_1):SMB_BMC_MM15_R_SCL
  R162     2      B  Q_RES       I245
  U5     D18  GPIOH4||SGPS1CK||SCL15  AST2600A1GP  I45

SMB_BMC_MM15_R_SDA   @SCM_LIB.SCM(SCH_1):SMB_BMC_MM15_R_SDA
  R236     2      B  Q_RES       I244
  U5     B17  GPIOH5||SGPS1LD||SDA15  AST2600A1GP  I45

SMB_BMC_MM15_SCL   @SCM_LIB.SCM(SCH_1):SMB_BMC_MM15_SCL
  R47      2      B  Q_RES       I106
  R136     2      B  Q_RES       I95
  R162     1      A  Q_RES       I245
  R272     1      A  Q_RES       I331
  R410     1      A  Q_RES       I21
  R420     2      B  Q_RES       I34
  R610     2      B  Q_RES       I92

SMB_BMC_MM15_SDA   @SCM_LIB.SCM(SCH_1):SMB_BMC_MM15_SDA
  R33      1      A  Q_RES       I117
  R126     1      A  Q_RES       I96
  R236     1      A  Q_RES       I244
  R303     1      A  Q_RES       I335
  R409     1      A  Q_RES       I20
  R421     2      B  Q_RES       I33
  R692     2      B  Q_RES       I90

SMB_BMC_MM16_R1_SCL   @SCM_LIB.SCM(SCH_1):SMB_BMC_MM16_R1_SCL
  D13      2   SCLA  PCA9517ADP   I1
  R135     2      B  Q_RES       I27

SMB_BMC_MM16_R1_SDA   @SCM_LIB.SCM(SCH_1):SMB_BMC_MM16_R1_SDA
  D13      3   SDAA  PCA9517ADP   I1
  R294     2      B  Q_RES       I28

SMB_BMC_MM16_R_SCL   @SCM_LIB.SCM(SCH_1):SMB_BMC_MM16_R_SCL
  R152     2      B  Q_RES       I249
  U5     C17  GPIOH6||SGPS1I0||SCL16  AST2600A1GP  I45

SMB_BMC_MM16_R_SDA   @SCM_LIB.SCM(SCH_1):SMB_BMC_MM16_R_SDA
  R153     2      B  Q_RES       I248
  U5     E18  GPIOH7||SGPS1I1||SDA16  AST2600A1GP  I45

SMB_BMC_MM16_SCL   @SCM_LIB.SCM(SCH_1):SMB_BMC_MM16_SCL
  R135     1      A  Q_RES       I27
  R152     1      A  Q_RES       I249
  R264     2      B  Q_RES       I89

SMB_BMC_MM16_SDA   @SCM_LIB.SCM(SCH_1):SMB_BMC_MM16_SDA
  R153     1      A  Q_RES       I248
  R265     2      B  Q_RES       I88
  R294     1      A  Q_RES       I28

SMB_BMC_MM1_R_SCL   @SCM_LIB.SCM(SCH_1):SMB_BMC_MM1_R_SCL
  R132     1      A  Q_RES       I98
  U5     B20  GPIOJ0||SCL1||HVI3C3SCL  AST2600A1GP  I45

SMB_BMC_MM1_R_SDA   @SCM_LIB.SCM(SCH_1):SMB_BMC_MM1_R_SDA
  R133     1      A  Q_RES       I97
  U5     A20  GPIOJ1||SDA1||HVI3C3SDA  AST2600A1GP  I45

SMB_BMC_MM1_SCL   @SCM_LIB.SCM(SCH_1):SMB_BMC_MM1_SCL
  GF1     A3     A3  FCONN168_ME1016810106011  I171
  R132     2      B  Q_RES       I98
  R244     2      B  Q_RES       I147

SMB_BMC_MM1_SDA   @SCM_LIB.SCM(SCH_1):SMB_BMC_MM1_SDA
  GF1     A4     A4  FCONN168_ME1016810106011  I171
  R133     2      B  Q_RES       I97
  R245     2      B  Q_RES       I146

SMB_BMC_MM2_R_SCL   @SCM_LIB.SCM(SCH_1):SMB_BMC_MM2_R_SCL
  R165     1      A  Q_RES       I315
  U5     E19  GPIOJ2||SCL2||HVI3C4SCL  AST2600A1GP  I45

SMB_BMC_MM2_R_SDA   @SCM_LIB.SCM(SCH_1):SMB_BMC_MM2_R_SDA
  R394     1      A  Q_RES       I314
  U5     D20  GPIOJ3||SDA2||HVI3C4SDA  AST2600A1GP  I45

SMB_BMC_MM2_SCL   @SCM_LIB.SCM(SCH_1):SMB_BMC_MM2_SCL
  GF1     A5     A5  FCONN168_ME1016810106011  I171
  R165     2      B  Q_RES       I315
  R246     2      B  Q_RES       I145

SMB_BMC_MM2_SDA   @SCM_LIB.SCM(SCH_1):SMB_BMC_MM2_SDA
  GF1     A6     A6  FCONN168_ME1016810106011  I171
  R247     2      B  Q_RES       I109
  R394     2      B  Q_RES       I314

SMB_BMC_MM3_R_SCL   @SCM_LIB.SCM(SCH_1):SMB_BMC_MM3_R_SCL
  R589     1      A  Q_RES       I316
  U5     C19  GPIOJ4||SCL3||HVI3C5SCL  AST2600A1GP  I45

SMB_BMC_MM3_R_SDA   @SCM_LIB.SCM(SCH_1):SMB_BMC_MM3_R_SDA
  R590     1      A  Q_RES       I317
  U5     A19  GPIOJ5||SDA3||HVI3C5SDA  AST2600A1GP  I45

SMB_BMC_MM3_SCL   @SCM_LIB.SCM(SCH_1):SMB_BMC_MM3_SCL
  GF1     A7     A7  FCONN168_ME1016810106011  I171
  R248     2      B  Q_RES       I107
  R589     2      B  Q_RES       I316

SMB_BMC_MM3_SDA   @SCM_LIB.SCM(SCH_1):SMB_BMC_MM3_SDA
  GF1     A8     A8  FCONN168_ME1016810106011  I171
  R249     2      B  Q_RES       I108
  R590     2      B  Q_RES       I317

SMB_BMC_MM4_R_SCL   @SCM_LIB.SCM(SCH_1):SMB_BMC_MM4_R_SCL
  R138     1      A  Q_RES       I92
  U5     C20  GPIOJ6||SCL4||HVI3C6SCL  AST2600A1GP  I45

SMB_BMC_MM4_R_SDA   @SCM_LIB.SCM(SCH_1):SMB_BMC_MM4_R_SDA
  R139     1      A  Q_RES       I91
  U5     D19  GPIOJ7||SDA4||HVI3C6SDA  AST2600A1GP  I45

SMB_BMC_MM4_SCL   @SCM_LIB.SCM(SCH_1):SMB_BMC_MM4_SCL
  GF1     A9     A9  FCONN168_ME1016810106011  I171
  R138     2      B  Q_RES       I92
  R250     2      B  Q_RES       I106

SMB_BMC_MM4_SDA   @SCM_LIB.SCM(SCH_1):SMB_BMC_MM4_SDA
  GF1    A10    A10  FCONN168_ME1016810106011  I171
  R139     2      B  Q_RES       I91
  R251     2      B  Q_RES       I104

SMB_BMC_MM5_R_SCL   @SCM_LIB.SCM(SCH_1):SMB_BMC_MM5_R_SCL
  R71      1      A  Q_RES       I277
  R252     2      B  Q_RES       I105
  U5     A11  GPIOK0||SCL5  AST2600A1GP  I45

SMB_BMC_MM5_R_SDA   @SCM_LIB.SCM(SCH_1):SMB_BMC_MM5_R_SDA
  R93      1      A  Q_RES       I276
  R253     2      B  Q_RES       I103
  U5     C11  GPIOK1||SDA5  AST2600A1GP  I45

SMB_BMC_MM5_SCL   @SCM_LIB.SCM(SCH_1):SMB_BMC_MM5_SCL
  GF1    A21    A21  FCONN168_ME1016810106011  I171
  R71      2      B  Q_RES       I277

SMB_BMC_MM5_SDA   @SCM_LIB.SCM(SCH_1):SMB_BMC_MM5_SDA
  GF1    A22    A22  FCONN168_ME1016810106011  I171
  R93      2      B  Q_RES       I276

SMB_BMC_MM6_R_SCL   @SCM_LIB.SCM(SCH_1):SMB_BMC_MM6_R_SCL
  R142     1      A  Q_RES       I88
  U5     D12  GPIOK2||SCL6  AST2600A1GP  I45

SMB_BMC_MM6_R_SDA   @SCM_LIB.SCM(SCH_1):SMB_BMC_MM6_R_SDA
  R143     1      A  Q_RES       I89
  U5     E13  GPIOK3||SDA6  AST2600A1GP  I45

SMB_BMC_MM6_SCL   @SCM_LIB.SCM(SCH_1):SMB_BMC_MM6_SCL
  GF1    A23    A23  FCONN168_ME1016810106011  I171
  R142     2      B  Q_RES       I88
  R254     2      B  Q_RES       I101

SMB_BMC_MM6_SDA   @SCM_LIB.SCM(SCH_1):SMB_BMC_MM6_SDA
  GF1    A24    A24  FCONN168_ME1016810106011  I171
  R143     2      B  Q_RES       I89
  R255     2      B  Q_RES       I102

SMB_BMC_MM7_R_SCL   @SCM_LIB.SCM(SCH_1):SMB_BMC_MM7_R_SCL
  R256     2      B  Q_RES       I100
  R567     1      A  Q_RES       I274
  U5     D11  GPIOK4||SCL7  AST2600A1GP  I45

SMB_BMC_MM7_R_SDA   @SCM_LIB.SCM(SCH_1):SMB_BMC_MM7_R_SDA
  R257     2      B  Q_RES       I99
  R570     1      A  Q_RES       I275
  U5     E11  GPIOK5||SDA7  AST2600A1GP  I45

SMB_BMC_MM7_SCL   @SCM_LIB.SCM(SCH_1):SMB_BMC_MM7_SCL
  GF1    A25    A25  FCONN168_ME1016810106011  I171
  R567     2      B  Q_RES       I274

SMB_BMC_MM7_SDA   @SCM_LIB.SCM(SCH_1):SMB_BMC_MM7_SDA
  GF1    A26    A26  FCONN168_ME1016810106011  I171
  R570     2      B  Q_RES       I275

SMB_BMC_MM8_R_SCL   @SCM_LIB.SCM(SCH_1):SMB_BMC_MM8_R_SCL
  R146     1      A  Q_RES       I235
  U5     F13  GPIOK6||SCL8  AST2600A1GP  I45

SMB_BMC_MM8_R_SDA   @SCM_LIB.SCM(SCH_1):SMB_BMC_MM8_R_SDA
  R147     1      A  Q_RES       I236
  U5     E12  GPIOK7||SDA8  AST2600A1GP  I45

SMB_BMC_MM8_SCL   @SCM_LIB.SCM(SCH_1):SMB_BMC_MM8_SCL
  GF1    A27    A27  FCONN168_ME1016810106011  I171
  R146     2      B  Q_RES       I235
  R258     2      B  Q_RES       I98

SMB_BMC_MM8_SDA   @SCM_LIB.SCM(SCH_1):SMB_BMC_MM8_SDA
  GF1    A28    A28  FCONN168_ME1016810106011  I171
  R147     2      B  Q_RES       I236
  R259     2      B  Q_RES       I96

SMB_BMC_MM9_R_SCL   @SCM_LIB.SCM(SCH_1):SMB_BMC_MM9_R_SCL
  R580     1      A  Q_RES       I321
  U5     D15  GPIOL0||SCL9  AST2600A1GP  I45

SMB_BMC_MM9_R_SDA   @SCM_LIB.SCM(SCH_1):SMB_BMC_MM9_R_SDA
  R582     1      A  Q_RES       I318
  U5     A14  GPIOL1||SDA9  AST2600A1GP  I45

SMB_BMC_MM9_SCL   @SCM_LIB.SCM(SCH_1):SMB_BMC_MM9_SCL
  GF1    A29    A29  FCONN168_ME1016810106011  I171
  R260     2      B  Q_RES       I97
  R580     2      B  Q_RES       I321

SMB_BMC_MM9_SDA   @SCM_LIB.SCM(SCH_1):SMB_BMC_MM9_SDA
  GF1    A30    A30  FCONN168_ME1016810106011  I171
  R261     2      B  Q_RES       I94
  R582     2      B  Q_RES       I318

SMB_BMC_TPM_MM15_SCL   @SCM_LIB.SCM(SCH_1):SMB_BMC_TPM_MM15_SCL
  J10     10     10  SCONN11_9192031111LF  I113
  R47      1      A  Q_RES       I106

SMB_BMC_TPM_MM15_SDA   @SCM_LIB.SCM(SCH_1):SMB_BMC_TPM_MM15_SDA
  J10      6      6  SCONN11_9192031111LF  I113
  R33      2      B  Q_RES       I117

SMB_DEBUG_AUX_LVC3_USB_R1_SCL   @SCM_LIB.SCM(SCH_1):SMB_DEBUG_AUX_LVC3_USB_R1_SCL
  D13      7   SCLB  PCA9517ADP   I1
  R298     2      B  Q_RES       I31
  R300     1      A  Q_RES       I23

SMB_DEBUG_AUX_LVC3_USB_R1_SDA   @SCM_LIB.SCM(SCH_1):SMB_DEBUG_AUX_LVC3_USB_R1_SDA
  D13      6   SDAB  PCA9517ADP   I1
  R299     2      B  Q_RES       I32
  R302     1      A  Q_RES       I24

SMB_DEBUG_AUX_LVC3_USB_SCL   @SCM_LIB.SCM(SCH_1):SMB_DEBUG_AUX_LVC3_USB_SCL
  J2       5  SSRX-  CONN9_GSB311131HR  I22
  R300     2      B  Q_RES       I23

SMB_DEBUG_AUX_LVC3_USB_SDA   @SCM_LIB.SCM(SCH_1):SMB_DEBUG_AUX_LVC3_USB_SDA
  J2       6  SSRX+  CONN9_GSB311131HR  I22
  R302     2      B  Q_RES       I24

SMB_TPM_MM15_SCL   @SCM_LIB.SCM(SCH_1):SMB_TPM_MM15_SCL
  J5      10     10  SCONN11_9192031111LF  I56
  R136     1      A  Q_RES       I95

SMB_TPM_MM15_SDA   @SCM_LIB.SCM(SCH_1):SMB_TPM_MM15_SDA
  J5       6      6  SCONN11_9192031111LF  I56
  R126     2      B  Q_RES       I96

SPA_SIN_SW_BUF   @SCM_LIB.SCM(SCH_1):SPA_SIN_SW_BUF
  R83      2      B  Q_RES       I105
  R95      2      B  Q_RES       I106
  U3       4      A  SN74LVC1G3157DCKR  I43

SPA_SIN_SW_DBG   @SCM_LIB.SCM(SCH_1):SPA_SIN_SW_DBG
  R83      1      A  Q_RES       I105
  R193     2      B  Q_RES       I46
  U36      4      4  74HC1G126GW  I43

SPA_SIN_SW_MNUSB   @SCM_LIB.SCM(SCH_1):SPA_SIN_SW_MNUSB
  R95      1      A  Q_RES       I106
  R397     1      A  Q_RES       I97

SPA_SIN_SW_MNUSB_R   @SCM_LIB.SCM(SCH_1):SPA_SIN_SW_MNUSB_R
  R397     2      B  Q_RES       I97
  R398     2      B  Q_RES       I96
  U17      7    TXD  FT234XDR    I98

SPA_SOUT_SW_BUF   @SCM_LIB.SCM(SCH_1):SPA_SOUT_SW_BUF
  R39      2      B  Q_RES       I102
  R43      2      B  Q_RES       I103
  U2       4      A  SN74LVC1G3157DCKR  I20

SPA_SOUT_SW_DBG   @SCM_LIB.SCM(SCH_1):SPA_SOUT_SW_DBG
  R39      1      A  Q_RES       I102
  U29      2      2  74HC1G126GW  I67

SPA_SOUT_SW_MNUSB   @SCM_LIB.SCM(SCH_1):SPA_SOUT_SW_MNUSB
  R43      1      A  Q_RES       I103
  U17     10    RXD  FT234XDR    I98

SPI_BMC_BIOS_CS0_N   @SCM_LIB.SCM(SCH_1):SPI_BMC_BIOS_CS0_N
  R728     1      A  Q_RES       I336
  R799     1      A  Q_RES       I215

SPI_BMC_BIOS_CS0_R1_N   @SCM_LIB.SCM(SCH_1):SPI_BMC_BIOS_CS0_R1_N
  R799     2      B  Q_RES       I215
  U5     AE8  GPIOX0||SPI2CS0#  AST2600A1GP  I45

SPI_BMC_BIOS_ROM_CLK   @SCM_LIB.SCM(SCH_1):SPI_BMC_BIOS_ROM_CLK
  R174     1      A  Q_RES       I331
  U5     AF8  GPIOX3||SPI2CK  AST2600A1GP  I45

SPI_BMC_BIOS_ROM_IO2   @SCM_LIB.SCM(SCH_1):SPI_BMC_BIOS_ROM_IO2
  R724     1      A  Q_RES       I333
  U5     AF9  GPIOX6||SPI2DQ2||TXD12  AST2600A1GP  I45

SPI_BMC_BIOS_ROM_IO3   @SCM_LIB.SCM(SCH_1):SPI_BMC_BIOS_ROM_IO3
  R725     1      A  Q_RES       I334
  U5     AB10  GPIOX7||SPI2DQ3||RXD12  AST2600A1GP  I45

SPI_BMC_BIOS_ROM_MISO   @SCM_LIB.SCM(SCH_1):SPI_BMC_BIOS_ROM_MISO
  R176     1      A  Q_RES       I332
  U5     AD9  GPIOX5||SPI2MISO  AST2600A1GP  I45

SPI_BMC_BIOS_ROM_MOSI   @SCM_LIB.SCM(SCH_1):SPI_BMC_BIOS_ROM_MOSI
  R175     1      A  Q_RES       I330
  U5     AB9  GPIOX4||SPI2MOSI  AST2600A1GP  I45

SPI_BMC_BIOS_ROM_R_CLK   @SCM_LIB.SCM(SCH_1):SPI_BMC_BIOS_ROM_R_CLK
  R174     2      B  Q_RES       I331
  U30     10   I_1C  IDTQS3VH257PAG  I271

SPI_BMC_BIOS_ROM_R_IO2   @SCM_LIB.SCM(SCH_1):SPI_BMC_BIOS_ROM_R_IO2
  R724     2      B  Q_RES       I333
  U21      3   I_1A  IDTQS3VH257PAG  I296

SPI_BMC_BIOS_ROM_R_IO3   @SCM_LIB.SCM(SCH_1):SPI_BMC_BIOS_ROM_R_IO3
  R725     2      B  Q_RES       I334
  U30      6   I_1B  IDTQS3VH257PAG  I271

SPI_BMC_BIOS_ROM_R_MISO   @SCM_LIB.SCM(SCH_1):SPI_BMC_BIOS_ROM_R_MISO
  R176     2      B  Q_RES       I332
  U21      6   I_1B  IDTQS3VH257PAG  I296

SPI_BMC_BIOS_ROM_R_MOSI   @SCM_LIB.SCM(SCH_1):SPI_BMC_BIOS_ROM_R_MOSI
  R175     2      B  Q_RES       I330
  U30      3   I_1A  IDTQS3VH257PAG  I271

SPI_BMC_BIOS_SOURCE_CS0_N   @SCM_LIB.SCM(SCH_1):SPI_BMC_BIOS_SOURCE_CS0_N
  R728     2      B  Q_RES       I336
  U21     10   I_1C  IDTQS3VH257PAG  I296

SPI_BMC_BOOT_CLK   @SCM_LIB.SCM(SCH_1):SPI_BMC_BOOT_CLK
  R178     2      B  Q_RES       I94
  R543     1      A  Q_RES       I18
  R549     1      A  Q_RES       I26
  R699     2      B  Q_RES       I163

SPI_BMC_BOOT_CS0_R1_N   @SCM_LIB.SCM(SCH_1):SPI_BMC_BOOT_CS0_R1_N
  R677     2      B  Q_RES       I250
  R801     2      B  Q_RES       I217
  U5     AB14  FWSPICS0#  AST2600A1GP  I45

SPI_BMC_BOOT_CS0_R_N   @SCM_LIB.SCM(SCH_1):SPI_BMC_BOOT_CS0_R_N
  R553     1      A  Q_RES       I23
  R801     1      A  Q_RES       I217

SPI_BMC_BOOT_CS1_R1_N   @SCM_LIB.SCM(SCH_1):SPI_BMC_BOOT_CS1_R1_N
  R107     2      B  Q_RES       I251
  R802     2      B  Q_RES       I218
  U5     AA13  FWSPICS1#  AST2600A1GP  I45

SPI_BMC_BOOT_CS1_R_N   @SCM_LIB.SCM(SCH_1):SPI_BMC_BOOT_CS1_R_N
  R547     1      A  Q_RES       I14
  R802     1      A  Q_RES       I218

SPI_BMC_BOOT_IO2   @SCM_LIB.SCM(SCH_1):SPI_BMC_BOOT_IO2
  R181     2      B  Q_RES       I93
  R545     1      A  Q_RES       I17
  R551     1      A  Q_RES       I24

SPI_BMC_BOOT_IO3   @SCM_LIB.SCM(SCH_1):SPI_BMC_BOOT_IO3
  R182     2      B  Q_RES       I92
  R548     1      A  Q_RES       I13
  R554     1      A  Q_RES       I22

SPI_BMC_BOOT_MISO   @SCM_LIB.SCM(SCH_1):SPI_BMC_BOOT_MISO
  R180     2      B  Q_RES       I96
  R546     1      A  Q_RES       I15
  R552     1      A  Q_RES       I25
  SW2      4      4  SW4S_DHNF02FTVTR  I195

SPI_BMC_BOOT_MOSI   @SCM_LIB.SCM(SCH_1):SPI_BMC_BOOT_MOSI
  R140     2      B  Q_RES       I200
  R179     2      B  Q_RES       I95
  R544     1      A  Q_RES       I16
  R550     1      A  Q_RES       I27
  SW2      3      3  SW4S_DHNF02FTVTR  I195

SPI_BMC_CLK_FLASH_R1   @SCM_LIB.SCM(SCH_1):SPI_BMC_CLK_FLASH_R1
  J121    16    CLK  SCONN16_ACASPI006P06  I97
  R549     2      B  Q_RES       I26

SPI_BMC_CLK_FLASH_R2   @SCM_LIB.SCM(SCH_1):SPI_BMC_CLK_FLASH_R2
  R543     2      B  Q_RES       I18
  U28     16   SCLK  MX66L1G45GMI08G  I64

SPI_BMC_CLK_R   @SCM_LIB.SCM(SCH_1):SPI_BMC_CLK_R
  R109     2      B  Q_RES       I114
  R178     1      A  Q_RES       I94
  R678     1      A  Q_RES       I239
  U5     AF13  FWSPICK  AST2600A1GP  I45

SPI_BMC_CPLD_R_MOSI   @SCM_LIB.SCM(SCH_1):SPI_BMC_CPLD_R_MOSI
  Q7       2      S  MOSFET_N_123  I157
  U5     AC11  GPIOZ4||SPI1MOSI  AST2600A1GP  I45

SPI_BMC_CS0_FLASH_R1_N   @SCM_LIB.SCM(SCH_1):SPI_BMC_CS0_FLASH_R1_N
  J121     7   CS_N  SCONN16_ACASPI006P06  I97
  R553     2      B  Q_RES       I23
  R557     2      B  Q_RES       I37

SPI_BMC_CS1_FLASH_R2_N   @SCM_LIB.SCM(SCH_1):SPI_BMC_CS1_FLASH_R2_N
  R547     2      B  Q_RES       I14
  R558     2      B  Q_RES       I32
  U28      7    CS#  MX66L1G45GMI08G  I64

SPI_BMC_IO0_FLASH_R1   @SCM_LIB.SCM(SCH_1):SPI_BMC_IO0_FLASH_R1
  J121    15     DI  SCONN16_ACASPI006P06  I97
  R550     2      B  Q_RES       I27

SPI_BMC_IO0_FLASH_R2   @SCM_LIB.SCM(SCH_1):SPI_BMC_IO0_FLASH_R2
  R544     2      B  Q_RES       I16
  U28     15  SI_SIO0  MX66L1G45GMI08G  I64

SPI_BMC_IO1_FLASH_R1   @SCM_LIB.SCM(SCH_1):SPI_BMC_IO1_FLASH_R1
  J121     8     DO  SCONN16_ACASPI006P06  I97
  R552     2      B  Q_RES       I25

SPI_BMC_IO1_FLASH_R2   @SCM_LIB.SCM(SCH_1):SPI_BMC_IO1_FLASH_R2
  R546     2      B  Q_RES       I15
  U28      8  SO||SIO1  MX66L1G45GMI08G  I64

SPI_BMC_IO2_FLASH_R1   @SCM_LIB.SCM(SCH_1):SPI_BMC_IO2_FLASH_R1
  J121     9   WP_N  SCONN16_ACASPI006P06  I97
  R551     2      B  Q_RES       I24
  R555     2      B  Q_RES       I28

SPI_BMC_IO2_FLASH_R2   @SCM_LIB.SCM(SCH_1):SPI_BMC_IO2_FLASH_R2
  R545     2      B  Q_RES       I17
  R556     2      B  Q_RES       I19
  U28      9  WP#||SIO2  MX66L1G45GMI08G  I64

SPI_BMC_IO2_R   @SCM_LIB.SCM(SCH_1):SPI_BMC_IO2_R
  R181     1      A  Q_RES       I93
  R681     1      A  Q_RES       I245
  U5     AE12  GPIOY4||FWSPIDQ2  AST2600A1GP  I45

SPI_BMC_IO3_FLASH_R1   @SCM_LIB.SCM(SCH_1):SPI_BMC_IO3_FLASH_R1
  J121     1  HOLD_N  SCONN16_ACASPI006P06  I97
  R554     2      B  Q_RES       I22
  R559     2      B  Q_RES       I58

SPI_BMC_IO3_FLASH_R2   @SCM_LIB.SCM(SCH_1):SPI_BMC_IO3_FLASH_R2
  R548     2      B  Q_RES       I13
  R560     2      B  Q_RES       I56
  U28      1  NC0||SIO3  MX66L1G45GMI08G  I64

SPI_BMC_IO3_R   @SCM_LIB.SCM(SCH_1):SPI_BMC_IO3_R
  R182     1      A  Q_RES       I92
  R682     1      A  Q_RES       I246
  U5     AF12  GPIOY5||FWSPIDQ3  AST2600A1GP  I45

SPI_BMC_MISO_IO1_R   @SCM_LIB.SCM(SCH_1):SPI_BMC_MISO_IO1_R
  R98      2      B  Q_RES       I119
  R180     1      A  Q_RES       I96
  R680     1      A  Q_RES       I248
  U5     AB13  FWSPIMISO  AST2600A1GP  I45

SPI_BMC_MOSI_IO0_R   @SCM_LIB.SCM(SCH_1):SPI_BMC_MOSI_IO0_R
  R97      2      B  Q_RES       I115
  R179     1      A  Q_RES       I95
  R679     1      A  Q_RES       I247
  U5     AC14  FWSPIMOSI  AST2600A1GP  I45

SPI_BMC_TPM_CLK_R   @SCM_LIB.SCM(SCH_1):SPI_BMC_TPM_CLK_R
  J10      1      1  SCONN11_9192031111LF  I113
  R109     1      A  Q_RES       I114

SPI_BMC_TPM_CS2_N_R   @SCM_LIB.SCM(SCH_1):SPI_BMC_TPM_CS2_N_R
  J10      5      5  SCONN11_9192031111LF  I113
  R100     1      A  Q_RES       I118

SPI_BMC_TPM_CS2_R1_N   @SCM_LIB.SCM(SCH_1):SPI_BMC_TPM_CS2_R1_N
  R183     2      B  Q_RES       I254
  U5     AC13  FWSPICS2#  AST2600A1GP  I45

SPI_BMC_TPM_CS2_R_N   @SCM_LIB.SCM(SCH_1):SPI_BMC_TPM_CS2_R_N
  R100     2      B  Q_RES       I118
  R183     1      A  Q_RES       I254
  R238     2      B  Q_RES       I184

SPI_BMC_TPM_MISO_R   @SCM_LIB.SCM(SCH_1):SPI_BMC_TPM_MISO_R
  J10      4      4  SCONN11_9192031111LF  I113
  R98      1      A  Q_RES       I119

SPI_BMC_TPM_MOSI_R   @SCM_LIB.SCM(SCH_1):SPI_BMC_TPM_MOSI_R
  J10      3      3  SCONN11_9192031111LF  I113
  R97      1      A  Q_RES       I115

SPI_PCH_CLK_FLASH_R1   @SCM_LIB.SCM(SCH_1):SPI_PCH_CLK_FLASH_R1
  J40     16    CLK  SCONN16_ACASPI006P06  I53
  R481     2      B  Q_RES       I24

SPI_PCH_CS0_FLASH_R1_N   @SCM_LIB.SCM(SCH_1):SPI_PCH_CS0_FLASH_R1_N
  J40      7   CS_N  SCONN16_ACASPI006P06  I53
  R485     2      B  Q_RES       I20
  R487     1      A  Q_RES       I51
  R490     2      B  Q_RES       I34

SPI_PCH_IO0_FLASH_R1   @SCM_LIB.SCM(SCH_1):SPI_PCH_IO0_FLASH_R1
  J40     15     DI  SCONN16_ACASPI006P06  I53
  R482     2      B  Q_RES       I22

SPI_PCH_IO1_FLASH_R1   @SCM_LIB.SCM(SCH_1):SPI_PCH_IO1_FLASH_R1
  J40      8     DO  SCONN16_ACASPI006P06  I53
  R484     2      B  Q_RES       I21

SPI_PCH_IO2_FLASH_R1   @SCM_LIB.SCM(SCH_1):SPI_PCH_IO2_FLASH_R1
  J40      9   WP_N  SCONN16_ACASPI006P06  I53
  R483     2      B  Q_RES       I23
  R488     2      B  Q_RES       I33

SPI_PCH_IO3_FLASH_R1   @SCM_LIB.SCM(SCH_1):SPI_PCH_IO3_FLASH_R1
  J40      1  HOLD_N  SCONN16_ACASPI006P06  I53
  R486     2      B  Q_RES       I19
  R492     2      B  Q_RES       I35

SPI_PCH_MUXED_CLK   @SCM_LIB.SCM(SCH_1):SPI_PCH_MUXED_CLK
  R481     1      A  Q_RES       I24
  U30      9     YC  IDTQS3VH257PAG  I271

SPI_PCH_MUXED_CS0_N   @SCM_LIB.SCM(SCH_1):SPI_PCH_MUXED_CS0_N
  R485     1      A  Q_RES       I20
  U21      9     YC  IDTQS3VH257PAG  I296

SPI_PCH_MUXED_IO0   @SCM_LIB.SCM(SCH_1):SPI_PCH_MUXED_IO0
  R482     1      A  Q_RES       I22
  U30      4     YA  IDTQS3VH257PAG  I271

SPI_PCH_MUXED_IO1   @SCM_LIB.SCM(SCH_1):SPI_PCH_MUXED_IO1
  R484     1      A  Q_RES       I21
  U21      7     YB  IDTQS3VH257PAG  I296

SPI_PCH_MUXED_IO2   @SCM_LIB.SCM(SCH_1):SPI_PCH_MUXED_IO2
  R483     1      A  Q_RES       I23
  U21      4     YA  IDTQS3VH257PAG  I296

SPI_PCH_MUXED_IO3   @SCM_LIB.SCM(SCH_1):SPI_PCH_MUXED_IO3
  R486     1      A  Q_RES       I19
  U30      7     YB  IDTQS3VH257PAG  I271

SPI_PCH_SECURE_CS0_N   @SCM_LIB.SCM(SCH_1):SPI_PCH_SECURE_CS0_N
  R864     2      B  Q_RES       I342
  U21     11   I_0C  IDTQS3VH257PAG  I296

SPI_SYS_CS0_N   @SCM_LIB.SCM(SCH_1):SPI_SYS_CS0_N
  GF1    B12    B12  FCONN168_ME1016810106011  I171
  R864     1      A  Q_RES       I342

SPI_SYS_HOLD_R_IO3   @SCM_LIB.SCM(SCH_1):SPI_SYS_HOLD_R_IO3
  GF1    B16    B16  FCONN168_ME1016810106011  I171
  R863     1      A  Q_RES       I341

SPI_SYS_MUX_CLK   @SCM_LIB.SCM(SCH_1):SPI_SYS_MUX_CLK
  R859     2      B  Q_RES       I339
  U30     11   I_0C  IDTQS3VH257PAG  I271

SPI_SYS_MUX_HOLD_IO3   @SCM_LIB.SCM(SCH_1):SPI_SYS_MUX_HOLD_IO3
  R863     2      B  Q_RES       I341
  U30      5   I_0B  IDTQS3VH257PAG  I271

SPI_SYS_MUX_MISO   @SCM_LIB.SCM(SCH_1):SPI_SYS_MUX_MISO
  R861     2      B  Q_RES       I338
  U21      5   I_0B  IDTQS3VH257PAG  I296

SPI_SYS_MUX_MOSI   @SCM_LIB.SCM(SCH_1):SPI_SYS_MUX_MOSI
  R860     2      B  Q_RES       I337
  U30      2   I_0A  IDTQS3VH257PAG  I271

SPI_SYS_MUX_WP_IO2   @SCM_LIB.SCM(SCH_1):SPI_SYS_MUX_WP_IO2
  R862     2      B  Q_RES       I340
  U21      2   I_0A  IDTQS3VH257PAG  I296

SPI_SYS_R1_CLK   @SCM_LIB.SCM(SCH_1):SPI_SYS_R1_CLK
  J5       1      1  SCONN11_9192031111LF  I56
  R501     1      A  Q_RES       I58
  R529     1      A  Q_RES       I84

SPI_SYS_R1_MISO   @SCM_LIB.SCM(SCH_1):SPI_SYS_R1_MISO
  J5       4      4  SCONN11_9192031111LF  I56
  R499     1      A  Q_RES       I62
  R585     1      A  Q_RES       I87

SPI_SYS_R1_MOSI   @SCM_LIB.SCM(SCH_1):SPI_SYS_R1_MOSI
  J5       3      3  SCONN11_9192031111LF  I56
  R498     1      A  Q_RES       I61
  R530     1      A  Q_RES       I85

SPI_SYS_R_CLK   @SCM_LIB.SCM(SCH_1):SPI_SYS_R_CLK
  GF1    B11    B11  FCONN168_ME1016810106011  I171
  R501     2      B  Q_RES       I58
  R859     1      A  Q_RES       I339

SPI_SYS_R_MISO   @SCM_LIB.SCM(SCH_1):SPI_SYS_R_MISO
  GF1    B14    B14  FCONN168_ME1016810106011  I171
  R499     2      B  Q_RES       I62
  R861     1      A  Q_RES       I338

SPI_SYS_R_MOSI   @SCM_LIB.SCM(SCH_1):SPI_SYS_R_MOSI
  GF1    B13    B13  FCONN168_ME1016810106011  I171
  R498     2      B  Q_RES       I61
  R860     1      A  Q_RES       I337

SPI_SYS_WP_R_IO2   @SCM_LIB.SCM(SCH_1):SPI_SYS_WP_R_IO2
  GF1    B15    B15  FCONN168_ME1016810106011  I171
  R862     1      A  Q_RES       I340

SPI_TPM_CS_N    @SCM_LIB.SCM(SCH_1):SPI_TPM_CS_N
  GF1    OB12   OB12  FCONN168_ME1016810106011  I171
  R594     1      A  Q_RES       I360

SPI_TPM_CS_N_R   @SCM_LIB.SCM(SCH_1):SPI_TPM_CS_N_R
  J5       5      5  SCONN11_9192031111LF  I56
  R500     1      A  Q_RES       I65

SPI_TPM_CS_R_N   @SCM_LIB.SCM(SCH_1):SPI_TPM_CS_R_N
  R500     2      B  Q_RES       I65
  R594     2      B  Q_RES       I360

SW_P1V0_AUX_BST   @SCM_LIB.SCM(SCH_1):SW_P1V0_AUX_BST
  PC264    1      A  Q_CAP       I19
  PU42     9    BST  NB695GDZ    I15

SW_P1V0_AUX_FLT   @SCM_LIB.SCM(SCH_1):SW_P1V0_AUX_FLT
  PC261    1      A  Q_CAP       I44
  PC262    1      A  Q_CAP       I43
  PC263    1      A  Q_CAP       I16
  PL32     2      2  Q_INDUCTOR  I34
  PU42     1    VIN  NB695GDZ    I15

SW_P1V0_AUX_SW   @SCM_LIB.SCM(SCH_1):SW_P1V0_AUX_SW
  PC264    2      B  Q_CAP       I19
  PL33     1      1  Q_INDUCTOR  I37
  PU42     8     SW  NB695GDZ    I15

SW_P1V2_AUX_BST   @SCM_LIB.SCM(SCH_1):SW_P1V2_AUX_BST
  PC254    1      A  Q_CAP       I19
  PU41     9    BST  NB695GDZ    I15

SW_P1V2_AUX_FLT   @SCM_LIB.SCM(SCH_1):SW_P1V2_AUX_FLT
  PC251    1      A  Q_CAP       I43
  PC252    1      A  Q_CAP       I42
  PC253    1      A  Q_CAP       I16
  PL29     2      2  Q_INDUCTOR  I31
  PU41     1    VIN  NB695GDZ    I15

SW_P1V2_AUX_SW   @SCM_LIB.SCM(SCH_1):SW_P1V2_AUX_SW
  PC254    2      B  Q_CAP       I19
  PL31     1      1  Q_INDUCTOR  I21
  PU41     8     SW  NB695GDZ    I15

SW_P3V3_AUX_BST   @SCM_LIB.SCM(SCH_1):SW_P3V3_AUX_BST
  PC224    1      A  Q_CAP       I15
  PU1     10    BST  MPQ8626GDZ  I82

SW_P3V3_AUX_FLT   @SCM_LIB.SCM(SCH_1):SW_P3V3_AUX_FLT
  PC218    1      A  Q_CAP       I81
  PC219    1      A  Q_CAP       I80
  PC223    1      A  Q_CAP       I11
  PL19     2      2  Q_INDUCTOR  I32
  PU1      3    VIN  MPQ8626GDZ  I82

SW_P3V3_AUX_SW   @SCM_LIB.SCM(SCH_1):SW_P3V3_AUX_SW
  PC224    2      B  Q_CAP       I15
  PL35     1      1  Q_INDUCTOR  I92
  PU1      2    SW1  MPQ8626GDZ  I82
  PU1     11    SW2  MPQ8626GDZ  I82

SW_P5V_AUX_BST   @SCM_LIB.SCM(SCH_1):SW_P5V_AUX_BST
  PC216    1      A  Q_CAP       I23
  PU38     1    BST  MPQ8633AGLEC807Z  I42

SW_P5V_AUX_FLT   @SCM_LIB.SCM(SCH_1):SW_P5V_AUX_FLT
  PC206    1      A  Q_CAP       I47
  PC207    1      A  Q_CAP       I48
  PC210    1      A  Q_CAP       I45
  PL4      2      2  Q_INDUCTOR  I39
  PU38    10   VIN1  MPQ8633AGLEC807Z  I42
  PU38    21   VIN2  MPQ8633AGLEC807Z  I42

SW_P5V_AUX_SW   @SCM_LIB.SCM(SCH_1):SW_P5V_AUX_SW
  PC216    2      B  Q_CAP       I23
  PL34     1      1  Q_INDUCTOR  I28
  PU38    20     SW  MPQ8633AGLEC807Z  I42

SYS_BMC_PWRBTN_R_N   @SCM_LIB.SCM(SCH_1):SYS_BMC_PWRBTN_R_N
  R564     1      A  Q_RES       I160
  U5     W24  GPIOP1||PWM9||THRUOUT0  AST2600A1GP  I41

SYS_PWRBTN_N    @SCM_LIB.SCM(SCH_1):SYS_PWRBTN_N
  GF1    A47    A47  FCONN168_ME1016810106011  I171
  R44      2      B  Q_RES       I175
  R80      1      A  Q_RES       I467
  R564     2      B  Q_RES       I160

TEMP_A0         @SCM_LIB.SCM(SCH_1):TEMP_A0
  R418     2      B  Q_RES       I39
  R419     1      A  Q_RES       I38
  U4       7     A0  TMP75AIDGKR  I23

TEMP_A1         @SCM_LIB.SCM(SCH_1):TEMP_A1
  R416     2      B  Q_RES       I30
  R417     1      A  Q_RES       I28
  U4       6     A1  TMP75AIDGKR  I23

TEMP_A2         @SCM_LIB.SCM(SCH_1):TEMP_A2
  R414     2      B  Q_RES       I29
  R415     1      A  Q_RES       I27
  U4       5     A2  TMP75AIDGKR  I23

U43_CT          @SCM_LIB.SCM(SCH_1):U43_CT
  C264     1      A  Q_CAP       I59
  R710     2      B  Q_RES       I55
  U43      4     CT  TPS3808G33DBVR  I60

UART_1_SCM_RXD   @SCM_LIB.SCM(SCH_1):UART_1_SCM_RXD
  R760     1      A  Q_RES       I366
  R766     2      B  Q_RES       I72

UART_1_SCM_R_RXD   @SCM_LIB.SCM(SCH_1):UART_1_SCM_R_RXD
  R760     2      B  Q_RES       I366
  U5     B22  GPIOG1||RXD6||SD2CMD||SALT10  AST2600A1GP  I45

UART_1_SCM_R_TXD   @SCM_LIB.SCM(SCH_1):UART_1_SCM_R_TXD
  R122     2      B  Q_RES       I367
  U5     E21  GPIOG0||TXD6||SD2CLK||SALT9  AST2600A1GP  I45

UART_1_SCM_TXD   @SCM_LIB.SCM(SCH_1):UART_1_SCM_TXD
  R122     1      A  Q_RES       I367
  R765     2      B  Q_RES       I66

UART_2_BMC_RXD   @SCM_LIB.SCM(SCH_1):UART_2_BMC_RXD
  GF1    OB6    OB6  FCONN168_ME1016810106011  I171
  R762     1      A  Q_RES       I364

UART_2_BMC_R_RXD   @SCM_LIB.SCM(SCH_1):UART_2_BMC_R_RXD
  R762     2      B  Q_RES       I364
  U5     A22  GPIOG3||RXD7||SD2DAT1||SALT12  AST2600A1GP  I45

UART_2_BMC_R_TXD   @SCM_LIB.SCM(SCH_1):UART_2_BMC_R_TXD
  R761     2      B  Q_RES       I365
  U5     C21  GPIOG2||TXD7||SD2DAT0||SALT11  AST2600A1GP  I45

UART_2_BMC_TXD   @SCM_LIB.SCM(SCH_1):UART_2_BMC_TXD
  GF1    OB5    OB5  FCONN168_ME1016810106011  I171
  R761     1      A  Q_RES       I365

UART_BMC_1_RXD   @SCM_LIB.SCM(SCH_1):UART_BMC_1_RXD
  R427     2      B  Q_RES       I198
  U5     D13  GPIOM7||RXD1  AST2600A1GP  I45

UART_BMC_1_RXD_R   @SCM_LIB.SCM(SCH_1):UART_BMC_1_RXD_R
  R427     1      A  Q_RES       I198
  U3       1     B1  SN74LVC1G3157DCKR  I43

UART_BMC_1_TXD   @SCM_LIB.SCM(SCH_1):UART_BMC_1_TXD
  R157     2      B  Q_RES       I18
  U5     C13  GPIOM6||TXD1  AST2600A1GP  I45

UART_BMC_1_TXD_R   @SCM_LIB.SCM(SCH_1):UART_BMC_1_TXD_R
  R157     1      A  Q_RES       I18
  U2       1     B1  SN74LVC1G3157DCKR  I20

UART_BMC_5_RXD   @SCM_LIB.SCM(SCH_1):UART_BMC_5_RXD
  R759     1      A  Q_RES       I208
  U5      D8   RXD5  AST2600A1GP  I45

UART_BMC_5_RXD_BUF   @SCM_LIB.SCM(SCH_1):UART_BMC_5_RXD_BUF
  J6       3      3  CONN3_210P9103GBR1  I109
  U24      3     2A  SN74LVC2G07DCKR  I115

UART_BMC_5_RXD_BUF_R   @SCM_LIB.SCM(SCH_1):UART_BMC_5_RXD_BUF_R
  R72      2      B  Q_RES       I123
  R104     1      A  Q_RES       I117
  U24      4     2Y  SN74LVC2G07DCKR  I115

UART_BMC_5_RXD_R   @SCM_LIB.SCM(SCH_1):UART_BMC_5_RXD_R
  R104     2      B  Q_RES       I117
  R759     2      B  Q_RES       I208
  R766     1      A  Q_RES       I72
  U3       3     B0  SN74LVC1G3157DCKR  I43

UART_BMC_5_TXD   @SCM_LIB.SCM(SCH_1):UART_BMC_5_TXD
  R170     1      A  Q_RES       I67
  U5      C8   TXD5  AST2600A1GP  I45

UART_BMC_5_TXD_BUF   @SCM_LIB.SCM(SCH_1):UART_BMC_5_TXD_BUF
  R67      2      B  Q_RES       I121
  R102     1      A  Q_RES       I118
  U24      6     1Y  SN74LVC2G07DCKR  I115

UART_BMC_5_TXD_BUF_R   @SCM_LIB.SCM(SCH_1):UART_BMC_5_TXD_BUF_R
  J6       1      1  CONN3_210P9103GBR1  I109
  R102     2      B  Q_RES       I118

UART_BMC_5_TXD_R   @SCM_LIB.SCM(SCH_1):UART_BMC_5_TXD_R
  R170     2      B  Q_RES       I67
  R765     1      A  Q_RES       I66
  U2       3     B0  SN74LVC1G3157DCKR  I20
  U11      2      A  BAT54C      I185
  U24      1     1A  SN74LVC2G07DCKR  I115

UNNAMED_231_QFUSE_I153_1   @SCM_LIB.SCM(SCH_1):UNNAMED_231_QFUSE_I153_1
  D16      C      C  SCHOTTKY_AC  I152
  FS1      1      1  Q_FUSE      I153

UNNAMED_231_QFUSE_I153_2   @SCM_LIB.SCM(SCH_1):UNNAMED_231_QFUSE_I153_2
  FS1      2      2  Q_FUSE      I153
  J8      13     13  SCONN13_502240130C001  I151

USB2_01_F_DN    @SCM_LIB.SCM(SCH_1):USB2_01_F_DN
  J2       2     D-  CONN9_GSB311131HR  I22
  L23      3      3  Q_INDUCTOR4P_12   I9
  R385     2      B  Q_RES        I2
  U38      3    IO2  PRTR5V0U2X   I6

USB2_01_F_DP    @SCM_LIB.SCM(SCH_1):USB2_01_F_DP
  J2       3     D+  CONN9_GSB311131HR  I22
  L23      2      2  Q_INDUCTOR4P_12   I9
  R386     2      B  Q_RES       I10
  U38      2    IO1  PRTR5V0U2X   I6

USB2_EXT_DN     @SCM_LIB.SCM(SCH_1):USB2_EXT_DN
  L24      4      4  Q_INDUCTOR4P_12  I86
  R402     2      B  Q_RES       I88

USB2_EXT_DP     @SCM_LIB.SCM(SCH_1):USB2_EXT_DP
  L24      1      1  Q_INDUCTOR4P_12  I86
  R403     2      B  Q_RES       I87

USB2_EXT_R_DN   @SCM_LIB.SCM(SCH_1):USB2_EXT_R_DN
  J4       2     D-  SCONN5_2UB2141000111F  I83
  L24      3      3  Q_INDUCTOR4P_12  I86
  U18      2    D_N  TPD2EUSB30DRTR  I84

USB2_EXT_R_DP   @SCM_LIB.SCM(SCH_1):USB2_EXT_R_DP
  J4       3     D+  SCONN5_2UB2141000111F  I83
  L24      2      2  Q_INDUCTOR4P_12  I86
  U18      1    D_P  TPD2EUSB30DRTR  I84

USB2_PL2303_EXT_DN   @SCM_LIB.SCM(SCH_1):USB2_PL2303_EXT_DN
  R402     1      A  Q_RES       I88
  U17      1  USBDM  FT234XDR    I98

USB2_PL2303_EXT_DP   @SCM_LIB.SCM(SCH_1):USB2_PL2303_EXT_DP
  R401     2      B  Q_RES       I90
  R403     1      A  Q_RES       I87
  U17     12  USBDP  FT234XDR    I98

USB_FPNL_DN     @SCM_LIB.SCM(SCH_1):USB_FPNL_DN
  GF1    B57    B57  FCONN168_ME1016810106011  I171
  L23      4      4  Q_INDUCTOR4P_12   I9
  R385     1      A  Q_RES        I2

USB_FPNL_DP     @SCM_LIB.SCM(SCH_1):USB_FPNL_DP
  GF1    B56    B56  FCONN168_ME1016810106011  I171
  L23      1      1  Q_INDUCTOR4P_12   I9
  R386     1      A  Q_RES       I10

USB_HOST_BMC_A_DN   @SCM_LIB.SCM(SCH_1):USB_HOST_BMC_A_DN
  GF1    B54    B54  FCONN168_ME1016810106011  I171
  R218     2      B  Q_RES       I93

USB_HOST_BMC_A_DP   @SCM_LIB.SCM(SCH_1):USB_HOST_BMC_A_DP
  GF1    B53    B53  FCONN168_ME1016810106011  I171
  R217     2      B  Q_RES       I92

USB_HOST_BMC_A_R_DN   @SCM_LIB.SCM(SCH_1):USB_HOST_BMC_A_R_DN
  R218     1      A  Q_RES       I93
  U5      B4  USB2A_DN  AST2600A1GP  I41

USB_HOST_BMC_A_R_DP   @SCM_LIB.SCM(SCH_1):USB_HOST_BMC_A_R_DP
  R217     1      A  Q_RES       I92
  U5      A4  USB2A_DP  AST2600A1GP  I41

USB_HOST_BMC_B_DN   @SCM_LIB.SCM(SCH_1):USB_HOST_BMC_B_DN
  GF1    B51    B51  FCONN168_ME1016810106011  I171
  R528     2      B  Q_RES       I168

USB_HOST_BMC_B_DP   @SCM_LIB.SCM(SCH_1):USB_HOST_BMC_B_DP
  GF1    B50    B50  FCONN168_ME1016810106011  I171
  R527     2      B  Q_RES       I169

USB_HOST_BMC_B_R_DN   @SCM_LIB.SCM(SCH_1):USB_HOST_BMC_B_R_DN
  R528     1      A  Q_RES       I168
  U5      B6  USB2B_DN  AST2600A1GP  I41

USB_HOST_BMC_B_R_DP   @SCM_LIB.SCM(SCH_1):USB_HOST_BMC_B_R_DP
  R527     1      A  Q_RES       I169
  U5      A6  USB2B_DP  AST2600A1GP  I41

USB_OC0_EN      @SCM_LIB.SCM(SCH_1):USB_OC0_EN
  R376     2      B  Q_RES       I62
  R377     1      A  Q_RES       I63
  U10      3     EN  TPS2553DBVR1  I51

USB_OC0_ILIM    @SCM_LIB.SCM(SCH_1):USB_OC0_ILIM
  R378     1      A  Q_RES       I54
  U10      5   ILIM  TPS2553DBVR1  I51

USB_OC0_REAR_N   @SCM_LIB.SCM(SCH_1):USB_OC0_REAR_N
  R383     2      B  Q_RES       I42
  R384     1      A  Q_RES       I41
  U10      4  FAULT_N  TPS2553DBVR1  I51

USB_OC0_REAR_R_N   @SCM_LIB.SCM(SCH_1):USB_OC0_REAR_R_N
  R384     2      B  Q_RES       I41
  U25     E8  IO_111_8  10M02SCU169C8G  I330

VDDI_U2_EMMC    @SCM_LIB.SCM(SCH_1):VDDI_U2_EMMC
  C11      1      A  Q_CAP       I26
  C231     1      A  Q_CAP        I2
  U20     C2  VDDIM  MTFC8GAKAJCN1MWT  I38

VOL_SEN_ALERT_R   @SCM_LIB.SCM(SCH_1):VOL_SEN_ALERT_R
  R267     2      B  Q_RES       I85
  U5     K23  GPIOB1||SALT2||LHAD1  AST2600A1GP  I45
  U25     N2  IO_26_DPCLK0_2  10M02SCU169C8G  I394

V_BMC_DDC_LS_GATE   @SCM_LIB.SCM(SCH_1):V_BMC_DDC_LS_GATE
  Q2       2     G1  MOSFET_NCH_DUAL  I56
  Q2       5     G2  MOSFET_NCH_DUAL   I2
  R86      2      B  Q_RES       I51

V_BMC_DDC_SCL   @SCM_LIB.SCM(SCH_1):V_BMC_DDC_SCL
  Q2       4     S2  MOSFET_NCH_DUAL   I2
  R32      2      B  Q_RES       I50
  U5      B8  DDCCLK  AST2600A1GP  I41

V_BMC_DDC_SDA   @SCM_LIB.SCM(SCH_1):V_BMC_DDC_SDA
  Q2       1     S1  MOSFET_NCH_DUAL  I56
  R31      2      B  Q_RES       I27
  U5      A8  DDCDAT  AST2600A1GP  I41

V_BMC_LS_DDC_SCL   @SCM_LIB.SCM(SCH_1):V_BMC_LS_DDC_SCL
  Q2       3     D2  MOSFET_NCH_DUAL   I2
  R28      1      A  Q_RES       I99
  R92      2      B  Q_RES       I64

V_BMC_LS_DDC_SCL_R   @SCM_LIB.SCM(SCH_1):V_BMC_LS_DDC_SCL_R
  C214     1      A  Q_CAP       I84
  J8      12     12  SCONN13_502240130C001  I151
  R16      1      A  Q_RES       I75
  R28      2      B  Q_RES       I99
  U34      3    IO2  TPD4E001DBVR  I48

V_BMC_LS_DDC_SDA   @SCM_LIB.SCM(SCH_1):V_BMC_LS_DDC_SDA
  Q2       6     D1  MOSFET_NCH_DUAL  I56
  R29      1      A  Q_RES       I34
  R91      2      B  Q_RES       I62

V_BMC_LS_DDC_SDA_R   @SCM_LIB.SCM(SCH_1):V_BMC_LS_DDC_SDA_R
  C213     1      A  Q_CAP       I83
  J8      11     11  SCONN13_502240130C001  I151
  R17      1      A  Q_RES       I68
  R29      2      B  Q_RES       I34
  U34      1    IO1  TPD4E001DBVR  I48

V_DACB          @SCM_LIB.SCM(SCH_1):V_DACB
  C207     1      A  Q_CAP       I29
  L28      1      1  Q_INDUCTOR  I38
  R24      2      B  Q_RES       I134

V_DACB_IO       @SCM_LIB.SCM(SCH_1):V_DACB_IO
  C210     1      A  Q_CAP       I55
  J8       5      5  SCONN13_502240130C001  I151
  L28      2      2  Q_INDUCTOR  I38
  R87      1      A  Q_RES       I57
  U35      1    IO1  TPD4E001DBVR  I70

V_DACB_R        @SCM_LIB.SCM(SCH_1):V_DACB_R
  R22      1      A  Q_RES       I151
  R24      1      A  Q_RES       I134
  U5     AD21   DACB  AST2600A1GP  I41

V_DACG          @SCM_LIB.SCM(SCH_1):V_DACG
  C206     1      A  Q_CAP       I26
  L29      1      1  Q_INDUCTOR  I37
  R21      2      B  Q_RES       I133

V_DACG_IO       @SCM_LIB.SCM(SCH_1):V_DACG_IO
  C209     1      A  Q_CAP       I54
  J8       3      3  SCONN13_502240130C001  I151
  L29      2      2  Q_INDUCTOR  I37
  R88      1      A  Q_RES       I59
  U35      3    IO2  TPD4E001DBVR  I70

V_DACG_R        @SCM_LIB.SCM(SCH_1):V_DACG_R
  R21      1      A  Q_RES       I133
  R23      1      A  Q_RES       I150
  U5     AE21   DACG  AST2600A1GP  I41

V_DACR          @SCM_LIB.SCM(SCH_1):V_DACR
  C205     1      A  Q_CAP       I25
  L30      1      1  Q_INDUCTOR  I36
  R26      2      B  Q_RES       I142

V_DACR_IO       @SCM_LIB.SCM(SCH_1):V_DACR_IO
  C208     1      A  Q_CAP       I30
  J8       1      1  SCONN13_502240130C001  I151
  L30      2      2  Q_INDUCTOR  I36
  R89      1      A  Q_RES       I65
  U35      4    IO3  TPD4E001DBVR  I70

V_DACR_R        @SCM_LIB.SCM(SCH_1):V_DACR_R
  R25      1      A  Q_RES       I149
  R26      1      A  Q_RES       I142
  U5     AF21   DACR  AST2600A1GP  I41

V_VGAHS         @SCM_LIB.SCM(SCH_1):V_VGAHS
  R19      2      B  Q_RES       I141
  U33      2      2  74HC1G126GW  I32

V_VGAHS_BUF     @SCM_LIB.SCM(SCH_1):V_VGAHS_BUF
  C211     1      A  Q_CAP       I67
  J8       9      9  SCONN13_502240130C001  I151
  R85      2      B  Q_RES       I60
  U34      6    IO4  TPD4E001DBVR  I48

V_VGAHS_BUF_R   @SCM_LIB.SCM(SCH_1):V_VGAHS_BUF_R
  R85      1      A  Q_RES       I60
  U33      4      4  74HC1G126GW  I32

V_VGAHS_R       @SCM_LIB.SCM(SCH_1):V_VGAHS_R
  R19      1      A  Q_RES       I141
  U5     B14  GPIOL6||VGAHS  AST2600A1GP  I41

V_VGAVS         @SCM_LIB.SCM(SCH_1):V_VGAVS
  R20      2      B  Q_RES       I140
  U26      2      2  74HC1G126GW  I33

V_VGAVS_BUF     @SCM_LIB.SCM(SCH_1):V_VGAVS_BUF
  C212     1      A  Q_CAP       I77
  J8       7      7  SCONN13_502240130C001  I151
  R84      2      B  Q_RES       I61
  U34      4    IO3  TPD4E001DBVR  I48

V_VGAVS_BUF_R   @SCM_LIB.SCM(SCH_1):V_VGAVS_BUF_R
  R84      1      A  Q_RES       I61
  U26      4      4  74HC1G126GW  I33

V_VGAVS_R       @SCM_LIB.SCM(SCH_1):V_VGAVS_R
  R20      1      A  Q_RES       I140
  U5     C14  GPIOL7||VGAVS  AST2600A1GP  I41

XTAL_PHY_XI     @SCM_LIB.SCM(SCH_1):XTAL_PHY_XI
  R286     2      B  Q_RES       I203
  U7       8  XTALI  BCM54612EB1KMLG  I126

XTAL_PHY_XI_R   @SCM_LIB.SCM(SCH_1):XTAL_PHY_XI_R
  C141     1      A  Q_CAP       I206
  R286     1      A  Q_RES       I203
  Y1       1     X1  Q_XTAL_4P_13BI_24GND  I204

XTAL_PHY_XO     @SCM_LIB.SCM(SCH_1):XTAL_PHY_XO
  R288     2      B  Q_RES       I200
  U7       7  XTALO  BCM54612EB1KMLG  I126

XTAL_PHY_XO_R   @SCM_LIB.SCM(SCH_1):XTAL_PHY_XO_R
  C145     1      A  Q_CAP       I201
  R288     1      A  Q_RES       I200
  Y1       3     X2  Q_XTAL_4P_13BI_24GND  I204
END OF SIGNAL CROSS REFERENCE
**** Part Type 'SCONN11_9192031111LF' ('SCONN11_9192031111LF-SCONN11_9A') ****
**** Part Type 'SCONN13_502240130C001' ('SCONN13_502240130C001-SCONN13_A') ****
**** Part Type 'SCONN14_RS6QU0001' ('SCONN14_RS6QU0001-SCONN14_RS6-A') ****
**** Part Type 'SCONN16_ACASPI006P06' ('SCONN16_ACASPI006P06-SCONN16_AA') ****
**** Part Type 'SCONN20_3VM11207D7307H' ('SCONN20_3VM11207D7307H-SCONN20A') ****
**** Part Type 'SCONN5_2UB2141000111F' ('SCONN5_2UB2141000111F-SCONN5_2A') ****
**** Part Type 'SN74LVC1G07DBVR' ('SN74LVC1G07DBVR_SMLF-SN74LVC1GA') ****
**** Part Type 'SN74LVC1G07DCKR' ('SN74LVC1G07DCKR-SN74LVC1G07DCKA') ****
**** Part Type 'SN74LVC1G3157DCKR' ('SN74LVC1G3157DCKR-SN74LVC1G315A') ****
**** Part Type 'SN74LVC2G07DCKR' ('SN74LVC2G07DCKR_SMLF-SN74LVC2GA') ****
**** Part Type 'SW2S_TA31E2KQTR' ('SW2S_TA31E2KQTR-SW2S_TA3-1E2K-A') ****
**** Part Type 'SW4S_DHNF02FTVTR' ('SW4S_DHNF02FTVTR-SW4S_DHNF-02FA') ****
**** Part Type 'TMP75AIDGKR' ('TMP75AIDGKR-TMP75AIDGKR,SMLF,IA') ****
**** Part Type 'TPD2EUSB30DRTR' ('TPD2EUSB30DRTR_SMLF-TPD2EUSB30A') ****
**** Part Type 'TPD4E001DBVR' ('TPD4E001DBVR-TPD4E001DBVR,SMLFA') ****
**** Part Type 'TPD4E001DBVR' ('TPD4E001DBVR-TPD4E001DBVR,SMLFB') ****
**** Part Type 'TPS22965DSGR' ('TPS22965DSGR-TPS22965DSGR,SMLFA') ****
**** Part Type 'TPS2553DBVR1' ('TPS2553DBVR1-TPS2553DBVR-1,SMLA') ****
**** Part Type 'TPS3808G33DBVR' ('TPS3808G33DBVR-TPS3808G33DBVR,A') ****

END.
